G04 ================== begin FILE IDENTIFICATION RECORD ==================*
G04 Layout Name:  DAT6MTH3AD0_t6m_cm_d_brd_103112_274.brd*
G04 Film Name:    sst.art*
G04 File Format:  Gerber RS274X*
G04 File Origin:  Cadence Allegro 16.3-S048*
G04 Origin Date:  Tue Nov 26 10:18:27 2013*
G04 *
G04 Layer:  REF DES/SILKSCREEN_TOP*
G04 Layer:  PACKAGE GEOMETRY/SILKSCREEN_TOP*
G04 Layer:  MANUFACTURING/PHOTOPLOT_OUTLINE*
G04 Layer:  MANUFACTURING/TP_TEXT_TOP*
G04 Layer:  DRAWING FORMAT/TITLE_BLOCK*
G04 Layer:  DRAWING FORMAT/TITLE_DATA_SST*
G04 Layer:  BOARD GEOMETRY/OUTLINE*
G04 Layer:  BOARD GEOMETRY/SILKSCREEN_TOP*
G04 *
G04 Offset:    (0.00 0.00)*
G04 Mirror:    No*
G04 Mode:      Positive*
G04 Rotation:  0*
G04 FullContactRelief:  No*
G04 UndefLineWidth:     6.00*
G04 ================== end FILE IDENTIFICATION RECORD ====================*
%FSLAX25Y25*MOIN*%
%IR0*IPPOS*OFA0.00000B0.00000*MIA0B0*SFA1.00000B1.00000*%
%ADD10C,.025*%
%ADD11C,.005*%
%ADD12C,.006*%
%ADD13C,.008*%
%ADD14C,.00492*%
%ADD15C,.00197*%
%ADD16C,.01844*%
G75*
%LPD*%
G75*
G36*
G01X10259Y114404D02*
X12396Y120005D01*
X8416D01*
X10259Y114404D01*
G37*
G36*
G01X54119Y187238D02*
Y181238D01*
X48119Y184238D01*
X54119Y187238D01*
G37*
G36*
G01X56580Y290514D02*
X54005D01*
Y295828D01*
X56580D01*
Y290514D01*
G37*
G36*
G01X55055Y336832D02*
X58055Y337732D01*
Y335732D01*
X55055Y336832D01*
G37*
G36*
G01X61667Y497579D02*
X57424Y496165D01*
X60253Y493336D01*
X61667Y497579D01*
G37*
G36*
G01X66190Y521151D02*
X67686Y525639D01*
X64694D01*
X66190Y521151D01*
G37*
G36*
G01X73740Y36808D02*
X71740Y40808D01*
X75740D01*
X73740Y36808D01*
G37*
G36*
G01X77080Y136319D02*
X74180Y129219D01*
X79580D01*
X77080Y136319D01*
G37*
G36*
G01X77738Y413472D02*
X81120D01*
Y431788D01*
X77738D01*
Y413472D01*
G37*
G36*
G01Y432288D02*
X81120D01*
Y450604D01*
X77738D01*
Y432288D01*
G37*
G36*
G01X93194Y200108D02*
X95186Y198115D01*
X97108Y202133D01*
X93194Y200108D01*
G37*
G36*
G01X111607Y601914D02*
Y605914D01*
X107607Y603914D01*
X111607Y601914D01*
G37*
G36*
G01X133040Y400246D02*
X131859Y396702D01*
X134221D01*
X133040Y400246D01*
G37*
G36*
G01X124572Y507380D02*
X125753Y510924D01*
X123391D01*
X124572Y507380D01*
G37*
G36*
G01X138344Y714023D02*
Y710423D01*
X136375Y708623D01*
X138344Y706823D01*
Y703223D01*
X126532D01*
Y714023D01*
X138344D01*
G37*
G36*
G01X139152Y42965D02*
Y45425D01*
X141332Y44133D01*
X139152Y42965D01*
G37*
G36*
G01X144995Y440518D02*
X142952D01*
X143990Y442791D01*
X144995Y440518D01*
G37*
G36*
G01X142724Y569753D02*
X157634D01*
Y569563D01*
X152724Y564653D01*
X159329Y558048D01*
X159234Y557953D01*
X154424D01*
Y553253D01*
X154274Y553103D01*
X147724Y559653D01*
X142824Y554753D01*
X142724Y554853D01*
Y569753D01*
G37*
G36*
G01X156755Y74312D02*
X154755Y70312D01*
X158755D01*
X156755Y74312D01*
G37*
G36*
G01X149488Y351936D02*
X154288Y356834D01*
X160288Y350434D01*
X164588Y354734D01*
X158988Y360934D01*
X163888Y365434D01*
X149488D01*
Y351936D01*
G37*
G36*
G01X160654Y589633D02*
X158449Y583633D01*
X162949D01*
X160654Y589633D01*
G37*
G36*
G01X169261Y28483D02*
X167261Y24483D01*
X171261D01*
X169261Y28483D01*
G37*
G36*
G01X173881Y437357D02*
X171765Y441589D01*
X169650Y439473D01*
X173881Y437357D01*
G37*
G36*
G01X168118Y695539D02*
X172218Y693889D01*
Y697039D01*
X168118Y695539D01*
G37*
G36*
G01X184831Y482446D02*
X187131Y483346D01*
Y481646D01*
X184831Y482446D01*
G37*
G36*
G01X209231Y387987D02*
Y390987D01*
X206231Y389487D01*
X209231Y387987D01*
G37*
G36*
G01X209509Y459303D02*
X207209Y455003D01*
X211409D01*
X209509Y459303D01*
G37*
G36*
G01X201333Y687179D02*
Y689179D01*
X198333Y688179D01*
X201333Y687179D01*
G37*
G36*
G01X235489Y44331D02*
Y47713D01*
X217173D01*
Y44331D01*
X235489D01*
G37*
G36*
G01X215333Y687179D02*
Y689179D01*
X212333Y688179D01*
X215333Y687179D01*
G37*
G36*
G01X228705D02*
Y689179D01*
X225705Y688179D01*
X228705Y687179D01*
G37*
G36*
G01X254305Y44331D02*
Y47713D01*
X235989D01*
Y44331D01*
X254305D01*
G37*
G36*
G01X242333Y687179D02*
Y689179D01*
X239333Y688179D01*
X242333Y687179D01*
G37*
G36*
G01X247766Y388539D02*
X245723D01*
X246761Y390812D01*
X247766Y388539D01*
G37*
G36*
G01X255833Y687179D02*
Y689179D01*
X252833Y688179D01*
X255833Y687179D01*
G37*
G36*
G01X269330Y29608D02*
X267214Y33839D01*
X265099Y31723D01*
X269330Y29608D01*
G37*
G36*
G01X258438Y645975D02*
X260481D01*
X259443Y643702D01*
X258438Y645975D01*
G37*
G36*
G01X269333Y687179D02*
Y689179D01*
X266333Y688179D01*
X269333Y687179D01*
G37*
G36*
G01X282244Y441167D02*
Y439124D01*
X279971Y440162D01*
X282244Y441167D01*
G37*
G36*
G01X292662Y388104D02*
Y392104D01*
X296662Y390104D01*
X292662Y388104D01*
G37*
G36*
G01X308343Y580210D02*
Y565485D01*
X307968D01*
X303243Y570210D01*
X296701Y563668D01*
X296543Y563826D01*
Y568510D01*
X291959D01*
X291926Y568543D01*
X291751Y568718D01*
X298243Y575210D01*
X293418Y580035D01*
Y580210D01*
X308343D01*
G37*
G36*
G01X319905Y382204D02*
X317862D01*
X318900Y384477D01*
X319905Y382204D01*
G37*
G36*
G01X317135Y603826D02*
X319250Y599595D01*
X321366Y601711D01*
X317135Y603826D01*
G37*
G36*
G01X335255Y386762D02*
X331255Y384762D01*
Y388762D01*
X335255Y386762D01*
G37*
G36*
G01X329120Y488263D02*
X330820Y493463D01*
X327520D01*
X329120Y488263D01*
G37*
G36*
G01X326488Y548156D02*
X325307Y544612D01*
X327669D01*
X326488Y548156D01*
G37*
G36*
G01X338860Y712112D02*
X339460Y715112D01*
X338360D01*
X338860Y712112D01*
G37*
G36*
G01X376233Y47412D02*
X378757D01*
Y51054D01*
X376233D01*
Y47412D01*
G37*
G36*
G01X371833D02*
X369309D01*
Y51054D01*
X371833D01*
Y47412D01*
G37*
G36*
G01X379286Y538419D02*
X380467Y541963D01*
X378105D01*
X379286Y538419D01*
G37*
G36*
G01X391697Y718786D02*
X393197Y721786D01*
X390197D01*
X391697Y718786D01*
G37*
G36*
G01X413783Y44920D02*
Y48920D01*
X409283Y46920D01*
X413783Y44920D01*
G37*
G36*
G01X407080Y300812D02*
X402580Y302312D01*
Y299312D01*
X407080Y300812D01*
G37*
G36*
G01X409564Y605419D02*
X411680Y601188D01*
X413795Y603303D01*
X409564Y605419D01*
G37*
G36*
G01X434316Y427863D02*
X430934D01*
Y409547D01*
X434316D01*
Y427863D01*
G37*
G36*
G01Y447863D02*
X430934D01*
Y429547D01*
X434316D01*
Y447863D01*
G37*
G36*
G01X444138Y177140D02*
X438138Y180140D01*
Y174140D01*
X444138Y177140D01*
G37*
G36*
G01X443369Y482269D02*
X447369Y480269D01*
Y484269D01*
X443369Y482269D01*
G37*
G36*
G01X435264Y524007D02*
X437964Y522807D01*
Y525207D01*
X435264Y524007D01*
G37*
G36*
G01X458200Y95966D02*
X459381Y99510D01*
X457019D01*
X458200Y95966D01*
G37*
G36*
G01X496324Y216371D02*
X494062Y217361D01*
X495264Y218563D01*
X496324Y216371D01*
G37*
G36*
G01X495417Y224781D02*
X493117Y223881D01*
Y225581D01*
X495417Y224781D01*
G37*
G36*
G01X510582Y448565D02*
X504780Y445881D01*
X507962Y442699D01*
X510582Y448565D01*
G37*
G36*
G01X519161Y427684D02*
X523461Y425384D01*
Y429584D01*
X519161Y427684D01*
G37*
G36*
G01X554093Y46321D02*
X557093Y53821D01*
X551093D01*
X554093Y46321D01*
G37*
G36*
G01X546231Y71689D02*
X547931Y65489D01*
X544431D01*
X546231Y71689D01*
G37*
G36*
G01X550400Y232768D02*
X553228Y229940D01*
X554642Y234182D01*
X550400Y232768D01*
G37*
G36*
G01X558434Y288129D02*
X556938Y283641D01*
X559930D01*
X558434Y288129D01*
G37*
G36*
G01X554237Y538563D02*
X552172Y532783D01*
X556772D01*
X554237Y538563D01*
G37*
G36*
G01X563954Y190257D02*
X561954Y194257D01*
X565954D01*
X563954Y190257D01*
G37*
G36*
G01X559034Y638589D02*
X563034D01*
X561034Y634589D01*
X559034Y638589D01*
G37*
G36*
G01X567179Y707992D02*
X569725Y709689D01*
X568947Y710467D01*
X567179Y707992D01*
G37*
G36*
G01X585179Y101117D02*
X582179Y107117D01*
X588179D01*
X585179Y101117D01*
G37*
G36*
G01X589926Y519730D02*
X581926Y517430D01*
Y522530D01*
X589926Y519730D01*
G37*
G36*
G01X617830Y47364D02*
X620830Y54864D01*
X614830D01*
X617830Y47364D01*
G37*
G36*
G01X608929Y547993D02*
X606929D01*
X607929Y544993D01*
X608929Y547993D01*
G37*
G36*
G01X628574Y92629D02*
X634574Y95629D01*
Y89629D01*
X628574Y92629D01*
G37*
G36*
G01X631363Y308935D02*
X627819Y310116D01*
Y307754D01*
X631363Y308935D01*
G37*
G36*
G01X651744Y360470D02*
Y357834D01*
X654928Y359101D01*
X651744Y360470D01*
G37*
G36*
G01X637238Y411483D02*
Y408483D01*
X640238Y409983D01*
X637238Y411483D01*
G37*
G36*
G01X650042Y621511D02*
X655844Y624194D01*
X652662Y627376D01*
X650042Y621511D01*
G37*
G36*
G01X661852Y524801D02*
X669852Y527101D01*
Y522001D01*
X661852Y524801D01*
G37*
G36*
G01X664927Y629183D02*
Y625183D01*
X668927Y627183D01*
X664927Y629183D01*
G37*
G36*
G01X677633Y52359D02*
X680633Y59859D01*
X674633D01*
X677633Y52359D01*
G37*
G36*
G01X691286Y173109D02*
X692786Y177609D01*
X689786D01*
X691286Y173109D01*
G37*
G36*
G01X691324Y251915D02*
X692824Y256415D01*
X689824D01*
X691324Y251915D01*
G37*
G36*
G01X691703Y531725D02*
X693703D01*
X692703Y534725D01*
X691703Y531725D01*
G37*
G36*
G01X703661Y36808D02*
X701661Y40808D01*
X705661D01*
X703661Y36808D01*
G37*
G36*
G01X728823Y441949D02*
X709923D01*
X715723Y447749D01*
X709623Y453849D01*
X716923D01*
Y461149D01*
X723023Y455049D01*
X728823Y460849D01*
Y441949D01*
G37*
G36*
G01X723275Y135705D02*
X720275Y128205D01*
X726275D01*
X723275Y135705D01*
G37*
G36*
G01X723398Y218123D02*
X720398Y210623D01*
X726398D01*
X723398Y218123D01*
G37*
G36*
G01X740168Y22411D02*
X737268Y15311D01*
X742668D01*
X740168Y22411D01*
G37*
%LPC*%
G75*
G54D16*
X136438Y712023D03*
%LPD*%
G75*
G54D10*
G01X20859Y81018D02*
Y104640D01*
G01X10859D02*
Y81018D01*
G54D11*
G01X488640Y542458D02*
X491640D01*
G01X485640Y550358D02*
X491640D01*
G01X488640Y558158D02*
X491640D01*
G01X488640Y573958D02*
X491640D01*
G01X489538Y566058D02*
X491640D01*
G01X485640Y581758D02*
X491640D01*
G01X488640Y589658D02*
X491640D01*
G01X506140Y525158D02*
Y531158D01*
G01X507640Y599358D02*
Y605358D01*
G01X521840Y525158D02*
Y531158D01*
G01X513940Y528158D02*
Y531158D01*
G01X523440Y599358D02*
Y605358D01*
G01X515540Y599358D02*
Y602358D01*
G01X537540Y525158D02*
Y531158D01*
G01X529740Y528158D02*
Y531158D01*
G01X539140Y599358D02*
Y605358D01*
G01X531240Y599358D02*
Y602358D01*
G01X545440Y528158D02*
Y531158D01*
G01X547040Y599358D02*
Y602358D01*
G01X559840Y547158D02*
X562840D01*
G01X559840Y555058D02*
X565840D01*
G01X559840Y562858D02*
X562840D01*
G01X559840Y570758D02*
X565840D01*
G01X559840Y578658D02*
X562840D01*
G01X559840Y586558D02*
X565840D01*
G54D12*
G01X-42372Y125213D02*
G02I-2500J0D01*
G01X-44872Y127713D02*
G03Y122713I0J-2500D01*
G03Y127713I0J2500D01*
G01X-42372Y125213D02*
G03X-47372I-2500J0D01*
G03X-42372I2500J0D01*
G01X-44872Y127713D02*
G03I0J-2500D01*
G01X-42372Y141213D02*
G02I-2500J0D01*
G01X-44872Y143713D02*
G03Y138713I0J-2500D01*
G03Y143713I0J2500D01*
G01X-42372Y141213D02*
G03X-47372I-2500J0D01*
G03X-42372I2500J0D01*
G01X-44872Y143713D02*
G03I0J-2500D01*
G01X-42372Y232533D02*
G02I-2500J0D01*
G01X-44872Y235033D02*
G03Y230033I0J-2500D01*
G03Y235033I0J2500D01*
G01D02*
G03Y230033I0J-2500D01*
G03Y235033I0J2500D01*
G01X-42372Y232533D02*
G03X-47372I-2500J0D01*
G03X-42372I2500J0D01*
G01X-44872Y235033D02*
G03I0J-2500D01*
G01D02*
G02I0J-2500D01*
G01X-42372Y248533D02*
G02I-2500J0D01*
G01X-44872Y251033D02*
G03Y246033I0J-2500D01*
G03Y251033I0J2500D01*
G01D02*
G03Y246033I0J-2500D01*
G03Y251033I0J2500D01*
G01X-42372Y248533D02*
G03X-47372I-2500J0D01*
G03X-42372I2500J0D01*
G01X-44872Y251033D02*
G03I0J-2500D01*
G01D02*
G02I0J-2500D01*
G01X-42372Y738493D02*
G02I-2500J0D01*
G01X-44872Y735993D02*
G03Y740993I0J2500D01*
G03Y735993I0J-2500D01*
G01X-42372Y738493D02*
G03X-47372I-2500J0D01*
G03X-42372I2500J0D01*
G01X-44872Y735993D02*
G03I0J2500D01*
G01X-42372Y754493D02*
G02I-2500J0D01*
G01X-44872Y751993D02*
G03Y756993I0J2500D01*
G03Y751993I0J-2500D01*
G01X-42372Y754493D02*
G03X-47372I-2500J0D01*
G03X-42372I2500J0D01*
G01X-44872Y751993D02*
G03I0J2500D01*
G01X-24372Y125213D02*
G02I-2500J0D01*
G01X-26872Y127713D02*
G03Y122713I0J-2500D01*
G03Y127713I0J2500D01*
G01X-24372Y125213D02*
G03X-29372I-2500J0D01*
G03X-24372I2500J0D01*
G01X-26872Y127713D02*
G03I0J-2500D01*
G01X-24372Y141213D02*
G02I-2500J0D01*
G01X-26872Y143713D02*
G03Y138713I0J-2500D01*
G03Y143713I0J2500D01*
G01X-24372Y141213D02*
G03X-29372I-2500J0D01*
G03X-24372I2500J0D01*
G01X-26872Y143713D02*
G03I0J-2500D01*
G01X-24372Y232533D02*
G02I-2500J0D01*
G01X-26872Y235033D02*
G03Y230033I0J-2500D01*
G03Y235033I0J2500D01*
G01D02*
G03Y230033I0J-2500D01*
G03Y235033I0J2500D01*
G01X-24372Y232533D02*
G03X-29372I-2500J0D01*
G03X-24372I2500J0D01*
G01X-26872Y235033D02*
G03I0J-2500D01*
G01D02*
G02I0J-2500D01*
G01X-24372Y248533D02*
G02I-2500J0D01*
G01X-26872Y251033D02*
G03Y246033I0J-2500D01*
G03Y251033I0J2500D01*
G01D02*
G03Y246033I0J-2500D01*
G03Y251033I0J2500D01*
G01X-24372Y248533D02*
G03X-29372I-2500J0D01*
G03X-24372I2500J0D01*
G01X-26872Y251033D02*
G03I0J-2500D01*
G01D02*
G02I0J-2500D01*
G01X-24372Y738493D02*
G02I-2500J0D01*
G01X-26872Y735993D02*
G03Y740993I0J2500D01*
G03Y735993I0J-2500D01*
G01X-24372Y738493D02*
G03X-29372I-2500J0D01*
G03X-24372I2500J0D01*
G01X-26872Y735993D02*
G03I0J2500D01*
G01X-24372Y754493D02*
G02I-2500J0D01*
G01X-26872Y751993D02*
G03Y756993I0J2500D01*
G03Y751993I0J-2500D01*
G01X-24372Y754493D02*
G03X-29372I-2500J0D01*
G03X-24372I2500J0D01*
G01X-26872Y751993D02*
G03I0J2500D01*
G01X736866Y821652D02*
X738695Y819832D01*
X738819Y819708D01*
Y679921D01*
G03X746693Y672047I7874J0D01*
G01X779528D01*
G02X787402Y664173I0J-7874D01*
G01Y297835D01*
G02X781496Y291929I-5906J0D01*
G01X780315D01*
G03X774409Y286024I0J-5906D01*
G01Y132480D01*
G03X780315Y126575I5906J1D01*
G01X781496D01*
G02X787402Y120669I0J-5906D01*
G01Y7874D01*
G02X779528Y0I-7874J0D01*
G01X7874D01*
G02X0Y7874I0J7874D01*
G01Y115354D01*
G02X5906Y121260I5906J0D01*
G01X25591D01*
G03X31496Y127165I0J5905D01*
G01Y272835D01*
G03X25591Y278740I-5905J0D01*
G01X5906D01*
G02X0Y284646I0J5906D01*
G01Y664173D01*
G02X7874Y672047I7874J0D01*
G01X40787D01*
G03X48661Y679921I0J7874D01*
G01Y819674D01*
X49201Y820214D01*
X50646Y821652D01*
X327026D01*
X328915Y819773D01*
X328976Y819712D01*
Y792323D01*
G03X336457I3740J0D01*
G01Y819673D01*
X336476Y819692D01*
X338446Y821652D01*
X378606D01*
X380551Y819707D01*
Y741142D01*
G03X406929I13189J0D01*
G01Y819675D01*
X406946Y819692D01*
X408916Y821652D01*
X685296D01*
X686388Y820566D01*
X687244Y819710D01*
Y792323D01*
G03X694724I3740J0D01*
G01Y819670D01*
X694746Y819692D01*
X696716Y821652D01*
X736866D01*
G01X5906Y278740D02*
X25591D01*
G02X31496Y272835I0J-5905D01*
G01Y127165D01*
G02X25591Y121260I-5905J0D01*
G01X5906D01*
G03X0Y115354I0J-5906D01*
G01Y7874D01*
G03X7874Y0I7874J0D01*
G01X779528D01*
G03X787402Y7874I0J7874D01*
G01Y120669D01*
G03X781496Y126575I-5906J0D01*
G01X780315D01*
G02X774409Y132480I0J5906D01*
G01Y286024D01*
G02X780315Y291929I5906J-1D01*
G01X781496D01*
G03X787402Y297835I0J5906D01*
G01Y664173D01*
G03X779528Y672047I-7874J0D01*
G01X746693D01*
G02X738819Y679921I0J7874D01*
G01Y819708D01*
X738695Y819832D01*
X736866Y821652D01*
G01X5906Y278740D02*
G02X0Y284646I0J5906D01*
G01Y664173D01*
G02X7874Y672047I7874J0D01*
G01X40787D01*
G03X48661Y679921I0J7874D01*
G01Y819674D01*
X49201Y820214D01*
X50646Y821652D01*
G01X38493Y-241864D02*
Y-246864D01*
G01X37036Y-241864D02*
X39950D01*
G01X44860Y-246864D02*
X42326D01*
Y-241864D01*
X44860D01*
G01X43846Y-244281D02*
X42326D01*
G01X47426Y-241864D02*
Y-246864D01*
X49960D01*
G01X53793Y-247031D02*
X53666Y-246947D01*
Y-246781D01*
X53793Y-246697D01*
X53920Y-246781D01*
Y-246947D01*
X53793Y-247031D01*
G01Y-244781D02*
X53666Y-244697D01*
Y-244531D01*
X53793Y-244447D01*
X53920Y-244531D01*
Y-244697D01*
X53793Y-244781D01*
G01X58576Y-248531D02*
X57943Y-247697D01*
X57626Y-246864D01*
Y-243531D01*
X57943Y-242697D01*
X58576Y-241864D01*
G01X63993D02*
X63486Y-242031D01*
X63106Y-242447D01*
X62853Y-242947D01*
X62663Y-243614D01*
X62600Y-244364D01*
X62663Y-245114D01*
X62853Y-245781D01*
X63106Y-246281D01*
X63486Y-246697D01*
X63993Y-246864D01*
X64500Y-246697D01*
X64880Y-246281D01*
X65133Y-245781D01*
X65323Y-245114D01*
X65386Y-244364D01*
X65323Y-243614D01*
X65133Y-242947D01*
X64880Y-242447D01*
X64500Y-242031D01*
X63993Y-241864D01*
G01X67700Y-245864D02*
X68080Y-246447D01*
X68586Y-246781D01*
X69156Y-246864D01*
X69663Y-246781D01*
X70170Y-246364D01*
X70486Y-245864D01*
X70550Y-245364D01*
X70423Y-244781D01*
X69980Y-244364D01*
X69536Y-244197D01*
X68966D01*
G01X69536D02*
X69916Y-243947D01*
X70233Y-243531D01*
X70360Y-243031D01*
X70233Y-242531D01*
X69916Y-242114D01*
X69346Y-241864D01*
X68776Y-241947D01*
X68206Y-242281D01*
G01X74510Y-248531D02*
X75143Y-247697D01*
X75460Y-246864D01*
Y-243531D01*
X75143Y-242697D01*
X74510Y-241864D01*
G01X77900Y-245864D02*
X78280Y-246447D01*
X78786Y-246781D01*
X79356Y-246864D01*
X79863Y-246781D01*
X80370Y-246364D01*
X80686Y-245864D01*
X80750Y-245364D01*
X80623Y-244781D01*
X80180Y-244364D01*
X79736Y-244197D01*
X79166D01*
G01X79736D02*
X80116Y-243947D01*
X80433Y-243531D01*
X80560Y-243031D01*
X80433Y-242531D01*
X80116Y-242114D01*
X79546Y-241864D01*
X78976Y-241947D01*
X78406Y-242281D01*
G01X83190Y-242697D02*
X83570Y-242197D01*
X84013Y-241947D01*
X84520Y-241864D01*
X85153Y-242031D01*
X85596Y-242447D01*
X85723Y-242947D01*
X85660Y-243447D01*
X85406Y-243864D01*
X84140Y-244697D01*
X83570Y-245281D01*
X83190Y-246114D01*
X83063Y-246864D01*
X85723D01*
G01X89366D02*
X89493Y-245781D01*
X89683Y-244864D01*
X89936Y-244031D01*
X90253Y-243114D01*
X90760Y-241864D01*
X88226D01*
G01X93770Y-245197D02*
X95416D01*
G01X98490Y-242697D02*
X98870Y-242197D01*
X99313Y-241947D01*
X99820Y-241864D01*
X100453Y-242031D01*
X100896Y-242447D01*
X101023Y-242947D01*
X100960Y-243447D01*
X100706Y-243864D01*
X99440Y-244697D01*
X98870Y-245281D01*
X98490Y-246114D01*
X98363Y-246864D01*
X101023D01*
G01X103400Y-245864D02*
X103780Y-246447D01*
X104286Y-246781D01*
X104856Y-246864D01*
X105363Y-246781D01*
X105870Y-246364D01*
X106186Y-245864D01*
X106250Y-245364D01*
X106123Y-244781D01*
X105680Y-244364D01*
X105236Y-244197D01*
X104666D01*
G01X105236D02*
X105616Y-243947D01*
X105933Y-243531D01*
X106060Y-243031D01*
X105933Y-242531D01*
X105616Y-242114D01*
X105046Y-241864D01*
X104476Y-241947D01*
X103906Y-242281D01*
G01X110653Y-246864D02*
Y-241864D01*
X108310Y-245447D01*
X111476D01*
G01X113600Y-246114D02*
X113980Y-246531D01*
X114423Y-246781D01*
X114993Y-246864D01*
X115563Y-246697D01*
X116006Y-246364D01*
X116323Y-245781D01*
X116386Y-245114D01*
X116260Y-244447D01*
X115943Y-244031D01*
X115500Y-243697D01*
X115056Y-243614D01*
X114613Y-243697D01*
X114043Y-244031D01*
X114233Y-241864D01*
X115943D01*
G01X123990Y-246864D02*
Y-241864D01*
X126396D01*
G01X125510Y-244281D02*
X123990D01*
G01X128710Y-246864D02*
X130293Y-241864D01*
X131876Y-246864D01*
G01X131306Y-245114D02*
X129280D01*
G01X134063Y-246864D02*
X136723Y-241864D01*
G01X134063D02*
X136723Y-246864D01*
G01X140493Y-247031D02*
X140366Y-246947D01*
Y-246781D01*
X140493Y-246697D01*
X140620Y-246781D01*
Y-246947D01*
X140493Y-247031D01*
G01Y-244781D02*
X140366Y-244697D01*
Y-244531D01*
X140493Y-244447D01*
X140620Y-244531D01*
Y-244697D01*
X140493Y-244781D01*
G01X145276Y-248531D02*
X144643Y-247697D01*
X144326Y-246864D01*
Y-243531D01*
X144643Y-242697D01*
X145276Y-241864D01*
G01X150693D02*
X150186Y-242031D01*
X149806Y-242447D01*
X149553Y-242947D01*
X149363Y-243614D01*
X149300Y-244364D01*
X149363Y-245114D01*
X149553Y-245781D01*
X149806Y-246281D01*
X150186Y-246697D01*
X150693Y-246864D01*
X151200Y-246697D01*
X151580Y-246281D01*
X151833Y-245781D01*
X152023Y-245114D01*
X152086Y-244364D01*
X152023Y-243614D01*
X151833Y-242947D01*
X151580Y-242447D01*
X151200Y-242031D01*
X150693Y-241864D01*
G01X154400Y-245864D02*
X154780Y-246447D01*
X155286Y-246781D01*
X155856Y-246864D01*
X156363Y-246781D01*
X156870Y-246364D01*
X157186Y-245864D01*
X157250Y-245364D01*
X157123Y-244781D01*
X156680Y-244364D01*
X156236Y-244197D01*
X155666D01*
G01X156236D02*
X156616Y-243947D01*
X156933Y-243531D01*
X157060Y-243031D01*
X156933Y-242531D01*
X156616Y-242114D01*
X156046Y-241864D01*
X155476Y-241947D01*
X154906Y-242281D01*
G01X161210Y-248531D02*
X161843Y-247697D01*
X162160Y-246864D01*
Y-243531D01*
X161843Y-242697D01*
X161210Y-241864D01*
G01X164600Y-245864D02*
X164980Y-246447D01*
X165486Y-246781D01*
X166056Y-246864D01*
X166563Y-246781D01*
X167070Y-246364D01*
X167386Y-245864D01*
X167450Y-245364D01*
X167323Y-244781D01*
X166880Y-244364D01*
X166436Y-244197D01*
X165866D01*
G01X166436D02*
X166816Y-243947D01*
X167133Y-243531D01*
X167260Y-243031D01*
X167133Y-242531D01*
X166816Y-242114D01*
X166246Y-241864D01*
X165676Y-241947D01*
X165106Y-242281D01*
G01X170016Y-246281D02*
X170460Y-246697D01*
X170966Y-246864D01*
X171473Y-246697D01*
X171916Y-246197D01*
X172233Y-245447D01*
X172360Y-244697D01*
Y-243781D01*
X172233Y-243031D01*
X171916Y-242364D01*
X171536Y-242031D01*
X171093Y-241864D01*
X170586Y-242031D01*
X170206Y-242364D01*
X169953Y-242864D01*
X169826Y-243531D01*
X169953Y-244114D01*
X170270Y-244697D01*
X170650Y-245031D01*
X171093Y-245114D01*
X171600Y-244947D01*
X171980Y-244531D01*
X172360Y-243781D01*
G01X176066Y-246864D02*
X176193Y-245781D01*
X176383Y-244864D01*
X176636Y-244031D01*
X176953Y-243114D01*
X177460Y-241864D01*
X174926D01*
G01X180470Y-245197D02*
X182116D01*
G01X185000Y-245864D02*
X185380Y-246447D01*
X185886Y-246781D01*
X186456Y-246864D01*
X186963Y-246781D01*
X187470Y-246364D01*
X187786Y-245864D01*
X187850Y-245364D01*
X187723Y-244781D01*
X187280Y-244364D01*
X186836Y-244197D01*
X186266D01*
G01X186836D02*
X187216Y-243947D01*
X187533Y-243531D01*
X187660Y-243031D01*
X187533Y-242531D01*
X187216Y-242114D01*
X186646Y-241864D01*
X186076Y-241947D01*
X185506Y-242281D01*
G01X190290Y-244781D02*
X190733Y-244197D01*
X191113Y-243864D01*
X191620Y-243697D01*
X192063Y-243864D01*
X192380Y-244197D01*
X192633Y-244697D01*
X192696Y-245281D01*
X192633Y-245781D01*
X192380Y-246281D01*
X192000Y-246697D01*
X191556Y-246864D01*
X191050Y-246697D01*
X190606Y-246197D01*
X190353Y-245447D01*
X190290Y-244614D01*
X190416Y-243531D01*
X190606Y-242947D01*
X190923Y-242364D01*
X191366Y-241947D01*
X191810Y-241864D01*
X192253Y-242031D01*
X192570Y-242447D01*
G01X196593Y-246864D02*
Y-241864D01*
X195833Y-242864D01*
G01Y-246864D02*
X197353D01*
G01X202453D02*
Y-241864D01*
X200110Y-245447D01*
X203276D01*
G01X26493Y-176864D02*
Y-251864D01*
X526493D01*
Y-176864D01*
X26493D01*
G01X327026Y821652D02*
X50646D01*
G01X106999Y96614D02*
G02X89851I-8574J-10787D01*
G03X91339Y99696I-2449J3083D01*
G01Y105512D01*
G02X105512I7086J0D01*
G01Y99696D01*
G03X106999Y96614I3937J0D01*
G01D02*
G02X89851I-8574J-10787D01*
G03X91339Y99696I-2449J3083D01*
G01Y105512D01*
G02X105512I7086J0D01*
G01Y99696D01*
G03X106999Y96614I3937J0D01*
G01D02*
G02X89851I-8574J-10787D01*
G03X91339Y99696I-2449J3083D01*
G01Y105512D01*
G02X105512I7086J0D01*
G01Y99696D01*
G03X106999Y96614I3937J0D01*
G01D02*
G02X89851I-8574J-10787D01*
G03X91339Y99696I-2449J3083D01*
G01Y105512D01*
G02X105512I7086J0D01*
G01Y99696D01*
G03X106999Y96614I3937J0D01*
G01Y710787D02*
G02X89851I-8574J-10787D01*
G03X91339Y713869I-2449J3083D01*
G01Y719685D01*
G02X105512I7086J0D01*
G01Y713869D01*
G03X106999Y710787I3937J0D01*
G01D02*
G02X89851I-8574J-10787D01*
G03X91339Y713869I-2449J3083D01*
G01Y719685D01*
G02X105512I7086J0D01*
G01Y713869D01*
G03X106999Y710787I3937J0D01*
G01D02*
G02X89851I-8574J-10787D01*
G03X91339Y713869I-2449J3083D01*
G01Y719685D01*
G02X105512I7086J0D01*
G01Y713869D01*
G03X106999Y710787I3937J0D01*
G01D02*
G02X89851I-8574J-10787D01*
G03X91339Y713869I-2449J3083D01*
G01Y719685D01*
G02X105512I7086J0D01*
G01Y713869D01*
G03X106999Y710787I3937J0D01*
G01X155874Y350256D02*
X156499Y352256D01*
X157124Y350256D01*
G01X156899Y350956D02*
X156099D01*
G01X221493Y-176864D02*
Y-251864D01*
G01Y-226864D02*
X324493D01*
Y-201864D01*
G01X221493D02*
X324493D01*
G01X332000Y-236864D02*
Y-231864D01*
X333266D01*
X333773Y-232114D01*
X334153Y-232447D01*
X334470Y-232947D01*
X334723Y-233531D01*
X334786Y-234364D01*
X334723Y-235197D01*
X334470Y-235781D01*
X334153Y-236281D01*
X333773Y-236614D01*
X333266Y-236864D01*
X332000D01*
G01X336910D02*
X338493Y-231864D01*
X340076Y-236864D01*
G01X339506Y-235114D02*
X337480D01*
G01X343593Y-231864D02*
Y-236864D01*
G01X342136Y-231864D02*
X345050D01*
G01X349960Y-236864D02*
X347426D01*
Y-231864D01*
X349960D01*
G01X348946Y-234281D02*
X347426D01*
G01X353793Y-237031D02*
X353666Y-236947D01*
Y-236781D01*
X353793Y-236697D01*
X353920Y-236781D01*
Y-236947D01*
X353793Y-237031D01*
G01Y-234781D02*
X353666Y-234697D01*
Y-234531D01*
X353793Y-234447D01*
X353920Y-234531D01*
Y-234697D01*
X353793Y-234781D01*
G01X326493Y-176864D02*
Y-251864D01*
G01X324493Y-176864D02*
Y-251864D01*
G01X326493Y-226864D02*
X526493D01*
G01X332126Y-211864D02*
Y-206864D01*
X333646D01*
X334153Y-207114D01*
X334533Y-207697D01*
X334660Y-208364D01*
X334533Y-209031D01*
X334216Y-209531D01*
X333646Y-209781D01*
X332126D01*
G01X337353Y-212031D02*
X339633Y-206864D01*
G01X342136Y-211864D02*
Y-206864D01*
X345050Y-211864D01*
Y-206864D01*
G01X348693Y-212031D02*
X348566Y-211947D01*
Y-211781D01*
X348693Y-211697D01*
X348820Y-211781D01*
Y-211947D01*
X348693Y-212031D01*
G01Y-209781D02*
X348566Y-209697D01*
Y-209531D01*
X348693Y-209447D01*
X348820Y-209531D01*
Y-209697D01*
X348693Y-209781D01*
G01X326493Y-201864D02*
X526493D01*
G01X332126Y-186864D02*
Y-181864D01*
X333646D01*
X334153Y-182114D01*
X334533Y-182697D01*
X334660Y-183364D01*
X334533Y-184031D01*
X334216Y-184531D01*
X333646Y-184781D01*
X332126D01*
G01X337226Y-186864D02*
Y-181864D01*
X338810D01*
X339316Y-182114D01*
X339633Y-182447D01*
X339760Y-183114D01*
X339633Y-183781D01*
X339253Y-184197D01*
X338810Y-184447D01*
X337226D01*
G01X338810D02*
X339760Y-186864D01*
G01X343593D02*
X343086Y-186781D01*
X342643Y-186447D01*
X342263Y-185947D01*
X342010Y-185364D01*
X341883Y-184697D01*
Y-184031D01*
X342010Y-183364D01*
X342263Y-182781D01*
X342643Y-182281D01*
X343086Y-181947D01*
X343593Y-181864D01*
X344100Y-181947D01*
X344543Y-182281D01*
X344923Y-182781D01*
X345176Y-183364D01*
X345303Y-184031D01*
Y-184697D01*
X345176Y-185364D01*
X344923Y-185947D01*
X344543Y-186447D01*
X344100Y-186781D01*
X343593Y-186864D01*
G01X347426Y-185864D02*
X347743Y-186364D01*
X348123Y-186697D01*
X348566Y-186864D01*
X349073Y-186697D01*
X349453Y-186364D01*
X349833Y-185864D01*
X349960Y-185197D01*
Y-181864D01*
G01X355060Y-186864D02*
X352526D01*
Y-181864D01*
X355060D01*
G01X354046Y-184281D02*
X352526D01*
G01X360286Y-182281D02*
X359906Y-182031D01*
X359463Y-181864D01*
X358956D01*
X358386Y-182114D01*
X357943Y-182531D01*
X357626Y-183031D01*
X357373Y-183864D01*
X357310Y-184614D01*
X357436Y-185364D01*
X357626Y-185864D01*
X358006Y-186364D01*
X358450Y-186697D01*
X358893Y-186864D01*
X359336D01*
X359780Y-186697D01*
X360160Y-186447D01*
X360476Y-186114D01*
G01X363993Y-181864D02*
Y-186864D01*
G01X362536Y-181864D02*
X365450D01*
G01X369093Y-187031D02*
X368966Y-186947D01*
Y-186781D01*
X369093Y-186697D01*
X369220Y-186781D01*
Y-186947D01*
X369093Y-187031D01*
G01Y-184781D02*
X368966Y-184697D01*
Y-184531D01*
X369093Y-184447D01*
X369220Y-184531D01*
Y-184697D01*
X369093Y-184781D01*
G01X327026Y821652D02*
X328915Y819773D01*
X328976Y819712D01*
Y792323D01*
G03X336457I3740J0D01*
G01Y819673D01*
X336476Y819692D01*
X338446Y821652D01*
G01X378606D02*
X338446D01*
G01X378606D02*
X380551Y819707D01*
Y741142D01*
G01X406929D02*
Y819675D01*
X406946Y819692D01*
X408916Y821652D01*
G01X685296D02*
X408916D01*
G01X447126Y-236864D02*
Y-231864D01*
X448710D01*
X449216Y-232114D01*
X449533Y-232447D01*
X449660Y-233114D01*
X449533Y-233781D01*
X449153Y-234197D01*
X448710Y-234447D01*
X447126D01*
G01X448710D02*
X449660Y-236864D01*
G01X454760D02*
X452226D01*
Y-231864D01*
X454760D01*
G01X453746Y-234281D02*
X452226D01*
G01X457010Y-231864D02*
X458593Y-236864D01*
X460176Y-231864D01*
G01X463693Y-237031D02*
X463566Y-236947D01*
Y-236781D01*
X463693Y-236697D01*
X463820Y-236781D01*
Y-236947D01*
X463693Y-237031D01*
G01Y-234781D02*
X463566Y-234697D01*
Y-234531D01*
X463693Y-234447D01*
X463820Y-234531D01*
Y-234697D01*
X463693Y-234781D01*
G01X441493Y-226864D02*
Y-251864D01*
G01X490493Y-226864D02*
Y-251864D01*
G01X697857Y96166D02*
G02X680096I-8880J-10536D01*
G03X681496Y99177I-2537J3011D01*
G01Y105315D01*
G02X696457I7481J0D01*
G01Y99177D01*
G03X697857Y96166I3937J0D01*
G01D02*
G02X680096I-8880J-10536D01*
G03X681496Y99177I-2537J3011D01*
G01Y105315D01*
G02X696457I7481J0D01*
G01Y99177D01*
G03X697857Y96166I3937J0D01*
G01D02*
G02X680096I-8880J-10536D01*
G03X681496Y99177I-2537J3011D01*
G01Y105315D01*
G02X696457I7481J0D01*
G01Y99177D01*
G03X697857Y96166I3937J0D01*
G01D02*
G02X680096I-8880J-10536D01*
G03X681496Y99177I-2537J3011D01*
G01Y105315D01*
G02X696457I7481J0D01*
G01Y99177D01*
G03X697857Y96166I3937J0D01*
G01X681496Y713350D02*
Y719488D01*
G02X696457I7481J0D01*
G01Y713350D01*
G03X697857Y710340I3937J0D01*
G02X680096I-8880J-10537D01*
G03X681496Y713350I-2537J3011D01*
G01D02*
Y719488D01*
G02X696457I7481J0D01*
G01Y713350D01*
G03X697857Y710340I3937J0D01*
G02X680096I-8880J-10537D01*
G03X681496Y713350I-2537J3011D01*
G01D02*
Y719488D01*
G02X696457I7481J0D01*
G01Y713350D01*
G03X697857Y710340I3937J0D01*
G02X680096I-8880J-10537D01*
G03X681496Y713350I-2537J3011D01*
G01D02*
Y719488D01*
G02X696457I7481J0D01*
G01Y713350D01*
G03X697857Y710340I3937J0D01*
G02X680096I-8880J-10537D01*
G03X681496Y713350I-2537J3011D01*
G01X696716Y821652D02*
X694746Y819692D01*
X694724Y819670D01*
Y792323D01*
G02X687244I-3740J0D01*
G01Y819710D01*
X686388Y820566D01*
X685296Y821652D01*
G01X736866D02*
X696716D01*
G01X-1043962Y-705877D02*
Y2342823D01*
X2300638D01*
Y-705877D01*
X-1043962D01*
G01X-52542Y130276D02*
X-52232Y130468D01*
X-52025Y130698D01*
X-51922Y130966D01*
X-52025Y131273D01*
X-52232Y131503D01*
X-52542Y131733D01*
X-52955Y131810D01*
X-55022D01*
G01X-52542Y133300D02*
X-52180Y133530D01*
X-51974Y133836D01*
X-51922Y134181D01*
X-51974Y134488D01*
X-52232Y134795D01*
X-52542Y134986D01*
X-52852Y135025D01*
X-53214Y134948D01*
X-53472Y134680D01*
X-53575Y134411D01*
Y134066D01*
G01Y134411D02*
X-53730Y134641D01*
X-53989Y134833D01*
X-54299Y134910D01*
X-54609Y134833D01*
X-54867Y134641D01*
X-55022Y134296D01*
X-54970Y133951D01*
X-54764Y133606D01*
G01X-55022Y137243D02*
X-54919Y136936D01*
X-54660Y136706D01*
X-54350Y136553D01*
X-53937Y136438D01*
X-53472Y136400D01*
X-53007Y136438D01*
X-52594Y136553D01*
X-52284Y136706D01*
X-52025Y136936D01*
X-51922Y137243D01*
X-52025Y137550D01*
X-52284Y137780D01*
X-52594Y137933D01*
X-53007Y138048D01*
X-53472Y138086D01*
X-53937Y138048D01*
X-54350Y137933D01*
X-54660Y137780D01*
X-54919Y137550D01*
X-55022Y137243D01*
G01X-52242Y238596D02*
X-51932Y238788D01*
X-51725Y239018D01*
X-51622Y239286D01*
X-51725Y239593D01*
X-51932Y239823D01*
X-52242Y240053D01*
X-52655Y240130D01*
X-54722D01*
G01X-51622Y242923D02*
X-54722D01*
X-52500Y241505D01*
Y243421D01*
G01X-51352Y743196D02*
X-51042Y743388D01*
X-50835Y743618D01*
X-50732Y743886D01*
X-50835Y744193D01*
X-51042Y744423D01*
X-51352Y744653D01*
X-51765Y744730D01*
X-53832D01*
G01X-53315Y746335D02*
X-53625Y746565D01*
X-53780Y746833D01*
X-53832Y747140D01*
X-53729Y747523D01*
X-53470Y747791D01*
X-53160Y747868D01*
X-52850Y747830D01*
X-52592Y747676D01*
X-52075Y746910D01*
X-51714Y746565D01*
X-51197Y746335D01*
X-50732Y746258D01*
Y747868D01*
G01X-51197Y749320D02*
X-50939Y749550D01*
X-50784Y749818D01*
X-50732Y750163D01*
X-50835Y750508D01*
X-51042Y750776D01*
X-51404Y750968D01*
X-51817Y751006D01*
X-52230Y750930D01*
X-52489Y750738D01*
X-52695Y750470D01*
X-52747Y750201D01*
X-52695Y749933D01*
X-52489Y749588D01*
X-53832Y749703D01*
Y750738D01*
G01X3350Y107800D02*
Y110900D01*
X2890Y110280D01*
G01Y107800D02*
X3810D01*
G01X26548Y104640D02*
X5170D01*
Y114482D01*
X26548D01*
Y104640D01*
G01X5316Y138977D02*
X47048D01*
G01X5316Y261024D02*
Y138977D01*
G01X47048Y261024D02*
X5316D01*
G01X5863Y568051D02*
X8085D01*
X8550Y568204D01*
X8860Y568511D01*
X8963Y568894D01*
X8860Y569277D01*
X8550Y569584D01*
X8085Y569737D01*
X5863D01*
G01X8498Y571151D02*
X8756Y571381D01*
X8911Y571649D01*
X8963Y571994D01*
X8860Y572339D01*
X8653Y572607D01*
X8291Y572799D01*
X7878Y572837D01*
X7465Y572761D01*
X7206Y572569D01*
X7000Y572301D01*
X6948Y572032D01*
X7000Y571764D01*
X7206Y571419D01*
X5863Y571534D01*
Y572569D01*
G01X7671Y574366D02*
X7310Y574634D01*
X7103Y574864D01*
X7000Y575171D01*
X7103Y575439D01*
X7310Y575631D01*
X7620Y575784D01*
X7981Y575822D01*
X8291Y575784D01*
X8601Y575631D01*
X8860Y575401D01*
X8963Y575132D01*
X8860Y574826D01*
X8550Y574557D01*
X8085Y574404D01*
X7568Y574366D01*
X6896Y574442D01*
X6535Y574557D01*
X6173Y574749D01*
X5915Y575017D01*
X5863Y575286D01*
X5966Y575554D01*
X6225Y575746D01*
G01X2753Y592207D02*
X4975D01*
X5440Y592360D01*
X5750Y592667D01*
X5853Y593050D01*
X5750Y593433D01*
X5440Y593740D01*
X4975Y593893D01*
X2753D01*
G01X5853Y596150D02*
X2753D01*
X3373Y595690D01*
G01X5853D02*
Y596610D01*
G01Y599710D02*
X2753D01*
X4975Y598292D01*
Y600208D01*
G01X5853Y602810D02*
X2753D01*
X4975Y601392D01*
Y603308D01*
G01X6710Y612569D02*
X3610D01*
Y613528D01*
X3765Y613834D01*
X3972Y614026D01*
X4385Y614103D01*
X4798Y614026D01*
X5057Y613796D01*
X5212Y613528D01*
Y612569D01*
G01Y613528D02*
X6710Y614103D01*
G01Y616436D02*
X3610D01*
X4230Y615976D01*
G01X6710D02*
Y616896D01*
G01X3610Y619536D02*
X3713Y619229D01*
X3972Y618999D01*
X4282Y618846D01*
X4695Y618731D01*
X5160Y618693D01*
X5625Y618731D01*
X6038Y618846D01*
X6348Y618999D01*
X6607Y619229D01*
X6710Y619536D01*
X6607Y619843D01*
X6348Y620073D01*
X6038Y620226D01*
X5625Y620341D01*
X5160Y620379D01*
X4695Y620341D01*
X4282Y620226D01*
X3972Y620073D01*
X3713Y619843D01*
X3610Y619536D01*
G01X5418Y621908D02*
X5057Y622176D01*
X4850Y622406D01*
X4747Y622713D01*
X4850Y622981D01*
X5057Y623173D01*
X5367Y623326D01*
X5728Y623364D01*
X6038Y623326D01*
X6348Y623173D01*
X6607Y622943D01*
X6710Y622674D01*
X6607Y622368D01*
X6297Y622099D01*
X5832Y621946D01*
X5315Y621908D01*
X4643Y621984D01*
X4282Y622099D01*
X3920Y622291D01*
X3662Y622559D01*
X3610Y622828D01*
X3713Y623096D01*
X3972Y623288D01*
G01X6710Y625736D02*
X6658Y626004D01*
X6503Y626311D01*
X6245Y626503D01*
X5883Y626579D01*
X5522Y626503D01*
X5212Y626273D01*
X5057Y625928D01*
Y625544D01*
X4953Y625314D01*
X4695Y625123D01*
X4333Y625046D01*
X3972Y625161D01*
X3713Y625429D01*
X3610Y625736D01*
X3713Y626043D01*
X3972Y626311D01*
X4333Y626426D01*
X4695Y626349D01*
X4953Y626158D01*
X5057Y625928D01*
Y625544D01*
X5212Y625199D01*
X5522Y624969D01*
X5883Y624893D01*
X6245Y624969D01*
X6503Y625161D01*
X6658Y625468D01*
X6710Y625736D01*
G01X5280Y606938D02*
X5493Y606730D01*
X5733Y606605D01*
X5947D01*
X6160Y606730D01*
X6320Y606938D01*
X6400Y607230D01*
X6347Y607522D01*
X6213Y607772D01*
X5973Y607938D01*
X5653Y608022D01*
X5467Y608188D01*
X5387Y608480D01*
X5440Y608772D01*
X5573Y608980D01*
X5760Y609105D01*
X5947D01*
X6133Y609022D01*
X6293Y608813D01*
G01X15155Y10518D02*
X15000Y10288D01*
X14897Y10020D01*
Y9713D01*
X15052Y9368D01*
X15310Y9100D01*
X15620Y8908D01*
X16137Y8755D01*
X16602Y8717D01*
X17067Y8793D01*
X17377Y8908D01*
X17687Y9138D01*
X17894Y9407D01*
X17997Y9675D01*
Y9943D01*
X17894Y10212D01*
X17739Y10442D01*
X17532Y10633D01*
G01X17997Y12775D02*
X14897D01*
X15517Y12315D01*
G01X17997D02*
Y13235D01*
G01Y15798D02*
X17325Y15875D01*
X16757Y15990D01*
X16240Y16143D01*
X15672Y16335D01*
X14897Y16642D01*
Y15108D01*
G01X17635Y18323D02*
X17894Y18592D01*
X17997Y18898D01*
X17894Y19205D01*
X17584Y19473D01*
X17119Y19665D01*
X16654Y19742D01*
X16085D01*
X15620Y19665D01*
X15207Y19473D01*
X15000Y19243D01*
X14897Y18975D01*
X15000Y18668D01*
X15207Y18438D01*
X15517Y18285D01*
X15930Y18208D01*
X16292Y18285D01*
X16654Y18477D01*
X16860Y18707D01*
X16912Y18975D01*
X16809Y19282D01*
X16550Y19512D01*
X16085Y19742D01*
G01X19402Y8832D02*
X21624D01*
X22089Y8985D01*
X22399Y9292D01*
X22502Y9675D01*
X22399Y10058D01*
X22089Y10365D01*
X21624Y10518D01*
X19402D01*
G01X22502Y12775D02*
X19402D01*
X20022Y12315D01*
G01X22502D02*
Y13235D01*
G01X19402Y15875D02*
X19505Y15568D01*
X19764Y15338D01*
X20074Y15185D01*
X20487Y15070D01*
X20952Y15032D01*
X21417Y15070D01*
X21830Y15185D01*
X22140Y15338D01*
X22399Y15568D01*
X22502Y15875D01*
X22399Y16182D01*
X22140Y16412D01*
X21830Y16565D01*
X21417Y16680D01*
X20952Y16718D01*
X20487Y16680D01*
X20074Y16565D01*
X19764Y16412D01*
X19505Y16182D01*
X19402Y15875D01*
G01X20459Y29883D02*
X20304Y29653D01*
X20201Y29385D01*
Y29078D01*
X20356Y28733D01*
X20614Y28465D01*
X20924Y28273D01*
X21441Y28120D01*
X21906Y28082D01*
X22371Y28158D01*
X22681Y28273D01*
X22991Y28503D01*
X23198Y28772D01*
X23301Y29040D01*
Y29308D01*
X23198Y29577D01*
X23043Y29807D01*
X22836Y29998D01*
G01X23301Y32140D02*
X20201D01*
X20821Y31680D01*
G01X23301D02*
Y32600D01*
G01Y35240D02*
X23249Y35508D01*
X23094Y35815D01*
X22836Y36007D01*
X22474Y36083D01*
X22113Y36007D01*
X21803Y35777D01*
X21648Y35432D01*
Y35048D01*
X21544Y34818D01*
X21286Y34627D01*
X20924Y34550D01*
X20563Y34665D01*
X20304Y34933D01*
X20201Y35240D01*
X20304Y35547D01*
X20563Y35815D01*
X20924Y35930D01*
X21286Y35853D01*
X21544Y35662D01*
X21648Y35432D01*
Y35048D01*
X21803Y34703D01*
X22113Y34473D01*
X22474Y34397D01*
X22836Y34473D01*
X23094Y34665D01*
X23249Y34972D01*
X23301Y35240D01*
G01X20201Y38340D02*
X20304Y38033D01*
X20563Y37803D01*
X20873Y37650D01*
X21286Y37535D01*
X21751Y37497D01*
X22216Y37535D01*
X22629Y37650D01*
X22939Y37803D01*
X23198Y38033D01*
X23301Y38340D01*
X23198Y38647D01*
X22939Y38877D01*
X22629Y39030D01*
X22216Y39145D01*
X21751Y39183D01*
X21286Y39145D01*
X20873Y39030D01*
X20563Y38877D01*
X20304Y38647D01*
X20201Y38340D01*
G01X7848Y27728D02*
Y30828D01*
X8807D01*
X9113Y30673D01*
X9305Y30466D01*
X9382Y30053D01*
X9305Y29640D01*
X9075Y29381D01*
X8807Y29226D01*
X7848D01*
G01X8807D02*
X9382Y27728D01*
G01X10987Y30311D02*
X11217Y30621D01*
X11485Y30776D01*
X11792Y30828D01*
X12175Y30725D01*
X12443Y30466D01*
X12520Y30156D01*
X12482Y29846D01*
X12328Y29588D01*
X11562Y29071D01*
X11217Y28710D01*
X10987Y28193D01*
X10910Y27728D01*
X12520D01*
G01X14815D02*
Y30828D01*
X14355Y30208D01*
G01Y27728D02*
X15275D01*
G01X18375D02*
Y30828D01*
X16957Y28606D01*
X18873D01*
G01X17602Y43840D02*
X17447Y43610D01*
X17344Y43342D01*
Y43035D01*
X17499Y42690D01*
X17757Y42422D01*
X18067Y42230D01*
X18584Y42077D01*
X19049Y42039D01*
X19514Y42115D01*
X19824Y42230D01*
X20134Y42460D01*
X20341Y42729D01*
X20444Y42997D01*
Y43265D01*
X20341Y43534D01*
X20186Y43764D01*
X19979Y43955D01*
G01X20444Y46097D02*
X17344D01*
X17964Y45637D01*
G01X20444D02*
Y46557D01*
G01Y49197D02*
X20392Y49465D01*
X20237Y49772D01*
X19979Y49964D01*
X19617Y50040D01*
X19256Y49964D01*
X18946Y49734D01*
X18791Y49389D01*
Y49005D01*
X18687Y48775D01*
X18429Y48584D01*
X18067Y48507D01*
X17706Y48622D01*
X17447Y48890D01*
X17344Y49197D01*
X17447Y49504D01*
X17706Y49772D01*
X18067Y49887D01*
X18429Y49810D01*
X18687Y49619D01*
X18791Y49389D01*
Y49005D01*
X18946Y48660D01*
X19256Y48430D01*
X19617Y48354D01*
X19979Y48430D01*
X20237Y48622D01*
X20392Y48929D01*
X20444Y49197D01*
G01Y52297D02*
X17344D01*
X17964Y51837D01*
G01X20444D02*
Y52757D01*
G01X24561Y42230D02*
X21461D01*
Y43189D01*
X21616Y43495D01*
X21823Y43687D01*
X22236Y43764D01*
X22649Y43687D01*
X22908Y43457D01*
X23063Y43189D01*
Y42230D01*
G01Y43189D02*
X24561Y43764D01*
G01X21978Y45369D02*
X21668Y45599D01*
X21513Y45867D01*
X21461Y46174D01*
X21564Y46557D01*
X21823Y46825D01*
X22133Y46902D01*
X22443Y46864D01*
X22701Y46710D01*
X23218Y45944D01*
X23579Y45599D01*
X24096Y45369D01*
X24561Y45292D01*
Y46902D01*
G01Y49197D02*
X21461D01*
X22081Y48737D01*
G01X24561D02*
Y49657D01*
G01X23269Y51569D02*
X22908Y51837D01*
X22701Y52067D01*
X22598Y52374D01*
X22701Y52642D01*
X22908Y52834D01*
X23218Y52987D01*
X23579Y53025D01*
X23889Y52987D01*
X24199Y52834D01*
X24458Y52604D01*
X24561Y52335D01*
X24458Y52029D01*
X24148Y51760D01*
X23683Y51607D01*
X23166Y51569D01*
X22494Y51645D01*
X22133Y51760D01*
X21771Y51952D01*
X21513Y52220D01*
X21461Y52489D01*
X21564Y52757D01*
X21823Y52949D01*
G01X7848Y31728D02*
Y34828D01*
X8807D01*
X9113Y34673D01*
X9305Y34466D01*
X9382Y34053D01*
X9305Y33640D01*
X9075Y33381D01*
X8807Y33226D01*
X7848D01*
G01X8807D02*
X9382Y31728D01*
G01X10987Y34311D02*
X11217Y34621D01*
X11485Y34776D01*
X11792Y34828D01*
X12175Y34725D01*
X12443Y34466D01*
X12520Y34156D01*
X12482Y33846D01*
X12328Y33588D01*
X11562Y33071D01*
X11217Y32710D01*
X10987Y32193D01*
X10910Y31728D01*
X12520D01*
G01X14815D02*
Y34828D01*
X14355Y34208D01*
G01Y31728D02*
X15275D01*
G01X17072Y32348D02*
X17302Y31986D01*
X17608Y31780D01*
X17953Y31728D01*
X18260Y31780D01*
X18567Y32038D01*
X18758Y32348D01*
X18797Y32658D01*
X18720Y33020D01*
X18452Y33278D01*
X18183Y33381D01*
X17838D01*
G01X18183D02*
X18413Y33536D01*
X18605Y33795D01*
X18682Y34105D01*
X18605Y34415D01*
X18413Y34673D01*
X18068Y34828D01*
X17723Y34776D01*
X17378Y34570D01*
G01X23495Y58495D02*
X20395D01*
Y59454D01*
X20550Y59760D01*
X20757Y59952D01*
X21170Y60029D01*
X21583Y59952D01*
X21842Y59722D01*
X21997Y59454D01*
Y58495D01*
G01Y59454D02*
X23495Y60029D01*
G01X22203Y61634D02*
X21842Y61902D01*
X21635Y62132D01*
X21532Y62439D01*
X21635Y62707D01*
X21842Y62899D01*
X22152Y63052D01*
X22513Y63090D01*
X22823Y63052D01*
X23133Y62899D01*
X23392Y62669D01*
X23495Y62400D01*
X23392Y62094D01*
X23082Y61825D01*
X22617Y61672D01*
X22100Y61634D01*
X21428Y61710D01*
X21067Y61825D01*
X20705Y62017D01*
X20447Y62285D01*
X20395Y62554D01*
X20498Y62822D01*
X20757Y63014D01*
G01X23030Y64619D02*
X23288Y64849D01*
X23443Y65117D01*
X23495Y65462D01*
X23392Y65807D01*
X23185Y66075D01*
X22823Y66267D01*
X22410Y66305D01*
X21997Y66229D01*
X21738Y66037D01*
X21532Y65769D01*
X21480Y65500D01*
X21532Y65232D01*
X21738Y64887D01*
X20395Y65002D01*
Y66037D01*
G01X20912Y67834D02*
X20602Y68064D01*
X20447Y68332D01*
X20395Y68639D01*
X20498Y69022D01*
X20757Y69290D01*
X21067Y69367D01*
X21377Y69329D01*
X21635Y69175D01*
X22152Y68409D01*
X22513Y68064D01*
X23030Y67834D01*
X23495Y67757D01*
Y69367D01*
G01X19783Y116720D02*
X19975Y116410D01*
X20205Y116203D01*
X20473Y116100D01*
X20780Y116203D01*
X21010Y116410D01*
X21240Y116720D01*
X21317Y117133D01*
Y119200D01*
G01X22807Y116720D02*
X23037Y116358D01*
X23343Y116152D01*
X23688Y116100D01*
X23995Y116152D01*
X24302Y116410D01*
X24493Y116720D01*
X24532Y117030D01*
X24455Y117392D01*
X24187Y117650D01*
X23918Y117753D01*
X23573D01*
G01X23918D02*
X24148Y117908D01*
X24340Y118167D01*
X24417Y118477D01*
X24340Y118787D01*
X24148Y119045D01*
X23803Y119200D01*
X23458Y119148D01*
X23113Y118942D01*
G01X26022Y117392D02*
X26290Y117753D01*
X26520Y117960D01*
X26827Y118063D01*
X27095Y117960D01*
X27287Y117753D01*
X27440Y117443D01*
X27478Y117082D01*
X27440Y116772D01*
X27287Y116462D01*
X27057Y116203D01*
X26788Y116100D01*
X26482Y116203D01*
X26213Y116513D01*
X26060Y116978D01*
X26022Y117495D01*
X26098Y118167D01*
X26213Y118528D01*
X26405Y118890D01*
X26673Y119148D01*
X26942Y119200D01*
X27210Y119097D01*
X27402Y118838D01*
G01X9280Y288412D02*
X10863Y283412D01*
X12446Y288412D01*
G01X16343Y285912D02*
X17610D01*
Y284412D01*
X17230Y283912D01*
X16786Y283579D01*
X16153Y283412D01*
X15520Y283579D01*
X15076Y283912D01*
X14696Y284412D01*
X14443Y284995D01*
X14316Y285662D01*
Y286245D01*
X14443Y286745D01*
X14696Y287329D01*
X15076Y287829D01*
X15456Y288162D01*
X15963Y288412D01*
X16406D01*
X16913Y288245D01*
X17293Y287912D01*
G01X19480Y283412D02*
X21063Y288412D01*
X22646Y283412D01*
G01X22076Y285162D02*
X20050D01*
G01X32656Y287995D02*
X32276Y288245D01*
X31833Y288412D01*
X31326D01*
X30756Y288162D01*
X30313Y287745D01*
X29996Y287245D01*
X29743Y286412D01*
X29680Y285662D01*
X29806Y284912D01*
X29996Y284412D01*
X30376Y283912D01*
X30820Y283579D01*
X31263Y283412D01*
X31706D01*
X32150Y283579D01*
X32530Y283829D01*
X32846Y284162D01*
G01X36363Y283412D02*
X35856Y283495D01*
X35413Y283829D01*
X35033Y284329D01*
X34780Y284912D01*
X34653Y285579D01*
Y286245D01*
X34780Y286912D01*
X35033Y287495D01*
X35413Y287995D01*
X35856Y288329D01*
X36363Y288412D01*
X36870Y288329D01*
X37313Y287995D01*
X37693Y287495D01*
X37946Y286912D01*
X38073Y286245D01*
Y285579D01*
X37946Y284912D01*
X37693Y284329D01*
X37313Y283829D01*
X36870Y283495D01*
X36363Y283412D01*
G01X40006D02*
Y288412D01*
X42920Y283412D01*
Y288412D01*
G01X45106Y283412D02*
Y288412D01*
X48020Y283412D01*
Y288412D01*
G01X9020Y290655D02*
X49535D01*
Y281409D01*
X8455D01*
Y290655D01*
X9020D01*
G01X18155Y295932D02*
Y311132D01*
G01X32755Y295832D02*
X18155Y295932D01*
G01Y311132D02*
X18255D01*
G01X16345Y311134D02*
Y348930D01*
G01X54140Y311134D02*
X16345D01*
G01X14178Y318343D02*
Y321443D01*
X12760Y319221D01*
X14676D01*
G01X10833Y323339D02*
X16345D01*
G01X10833Y336725D02*
Y323339D01*
G01X12729Y338202D02*
X12959Y337840D01*
X13265Y337634D01*
X13610Y337582D01*
X13917Y337634D01*
X14224Y337892D01*
X14415Y338202D01*
X14454Y338512D01*
X14377Y338874D01*
X14109Y339132D01*
X13840Y339235D01*
X13495D01*
G01X13840D02*
X14070Y339390D01*
X14262Y339649D01*
X14339Y339959D01*
X14262Y340269D01*
X14070Y340527D01*
X13725Y340682D01*
X13380Y340630D01*
X13035Y340424D01*
G01X10833Y336725D02*
X16345D01*
G01X18155Y348932D02*
X18955D01*
G01X18155Y364132D02*
Y348932D01*
G01X16345Y348930D02*
X54140D01*
G01X14487Y370584D02*
X25487D01*
G01X14487Y396584D02*
Y370584D01*
G01X32755Y364132D02*
X18155D01*
G01X18018Y384265D02*
X21956D01*
G01X19987Y383871D02*
X18018Y381903D01*
G01X21956D02*
X19987Y383871D01*
G01X18018Y381903D02*
X21956D01*
G01X22544Y397677D02*
X19444D01*
Y398443D01*
X19599Y398750D01*
X19806Y398980D01*
X20116Y399172D01*
X20477Y399325D01*
X20994Y399363D01*
X21511Y399325D01*
X21872Y399172D01*
X22182Y398980D01*
X22389Y398750D01*
X22544Y398443D01*
Y397677D01*
G01X19961Y400892D02*
X19651Y401122D01*
X19496Y401390D01*
X19444Y401697D01*
X19547Y402080D01*
X19806Y402348D01*
X20116Y402425D01*
X20426Y402387D01*
X20684Y402233D01*
X21201Y401467D01*
X21562Y401122D01*
X22079Y400892D01*
X22544Y400815D01*
Y402425D01*
G01Y404720D02*
X22492Y404988D01*
X22337Y405295D01*
X22079Y405487D01*
X21717Y405563D01*
X21356Y405487D01*
X21046Y405257D01*
X20891Y404912D01*
Y404528D01*
X20787Y404298D01*
X20529Y404107D01*
X20167Y404030D01*
X19806Y404145D01*
X19547Y404413D01*
X19444Y404720D01*
X19547Y405027D01*
X19806Y405295D01*
X20167Y405410D01*
X20529Y405333D01*
X20787Y405142D01*
X20891Y404912D01*
Y404528D01*
X21046Y404183D01*
X21356Y403953D01*
X21717Y403877D01*
X22079Y403953D01*
X22337Y404145D01*
X22492Y404452D01*
X22544Y404720D01*
G01X25487Y396584D02*
X14487D01*
G01Y396084D02*
X25487D01*
G01Y395584D02*
X14487D01*
G01X20732Y531000D02*
X20577Y530770D01*
X20474Y530502D01*
Y530195D01*
X20629Y529850D01*
X20887Y529582D01*
X21197Y529390D01*
X21714Y529237D01*
X22179Y529199D01*
X22644Y529275D01*
X22954Y529390D01*
X23264Y529620D01*
X23471Y529889D01*
X23574Y530157D01*
Y530425D01*
X23471Y530694D01*
X23316Y530924D01*
X23109Y531115D01*
G01Y532414D02*
X23367Y532644D01*
X23522Y532912D01*
X23574Y533257D01*
X23471Y533602D01*
X23264Y533870D01*
X22902Y534062D01*
X22489Y534100D01*
X22076Y534024D01*
X21817Y533832D01*
X21611Y533564D01*
X21559Y533295D01*
X21611Y533027D01*
X21817Y532682D01*
X20474Y532797D01*
Y533832D01*
G01X23109Y535514D02*
X23367Y535744D01*
X23522Y536012D01*
X23574Y536357D01*
X23471Y536702D01*
X23264Y536970D01*
X22902Y537162D01*
X22489Y537200D01*
X22076Y537124D01*
X21817Y536932D01*
X21611Y536664D01*
X21559Y536395D01*
X21611Y536127D01*
X21817Y535782D01*
X20474Y535897D01*
Y536932D01*
G01X23109Y538614D02*
X23367Y538844D01*
X23522Y539112D01*
X23574Y539457D01*
X23471Y539802D01*
X23264Y540070D01*
X22902Y540262D01*
X22489Y540300D01*
X22076Y540224D01*
X21817Y540032D01*
X21611Y539764D01*
X21559Y539495D01*
X21611Y539227D01*
X21817Y538882D01*
X20474Y538997D01*
Y540032D01*
G01X19372Y529431D02*
X16272D01*
Y530390D01*
X16427Y530696D01*
X16634Y530888D01*
X17047Y530965D01*
X17460Y530888D01*
X17719Y530658D01*
X17874Y530390D01*
Y529431D01*
G01Y530390D02*
X19372Y530965D01*
G01Y533298D02*
X16272D01*
X16892Y532838D01*
G01X19372D02*
Y533758D01*
G01X18752Y535555D02*
X19114Y535785D01*
X19320Y536091D01*
X19372Y536436D01*
X19320Y536743D01*
X19062Y537050D01*
X18752Y537241D01*
X18442Y537280D01*
X18080Y537203D01*
X17822Y536935D01*
X17719Y536666D01*
Y536321D01*
G01Y536666D02*
X17564Y536896D01*
X17305Y537088D01*
X16995Y537165D01*
X16685Y537088D01*
X16427Y536896D01*
X16272Y536551D01*
X16324Y536206D01*
X16530Y535861D01*
G01X16272Y539498D02*
X16375Y539191D01*
X16634Y538961D01*
X16944Y538808D01*
X17357Y538693D01*
X17822Y538655D01*
X18287Y538693D01*
X18700Y538808D01*
X19010Y538961D01*
X19269Y539191D01*
X19372Y539498D01*
X19269Y539805D01*
X19010Y540035D01*
X18700Y540188D01*
X18287Y540303D01*
X17822Y540341D01*
X17357Y540303D01*
X16944Y540188D01*
X16634Y540035D01*
X16375Y539805D01*
X16272Y539498D01*
G01X16789Y541870D02*
X16479Y542100D01*
X16324Y542368D01*
X16272Y542675D01*
X16375Y543058D01*
X16634Y543326D01*
X16944Y543403D01*
X17254Y543365D01*
X17512Y543211D01*
X18029Y542445D01*
X18390Y542100D01*
X18907Y541870D01*
X19372Y541793D01*
Y543403D01*
G01X14852Y529431D02*
X11752D01*
Y530390D01*
X11907Y530696D01*
X12114Y530888D01*
X12527Y530965D01*
X12940Y530888D01*
X13199Y530658D01*
X13354Y530390D01*
Y529431D01*
G01Y530390D02*
X14852Y530965D01*
G01Y533298D02*
X11752D01*
X12372Y532838D01*
G01X14852D02*
Y533758D01*
G01X14232Y535555D02*
X14594Y535785D01*
X14800Y536091D01*
X14852Y536436D01*
X14800Y536743D01*
X14542Y537050D01*
X14232Y537241D01*
X13922Y537280D01*
X13560Y537203D01*
X13302Y536935D01*
X13199Y536666D01*
Y536321D01*
G01Y536666D02*
X13044Y536896D01*
X12785Y537088D01*
X12475Y537165D01*
X12165Y537088D01*
X11907Y536896D01*
X11752Y536551D01*
X11804Y536206D01*
X12010Y535861D01*
G01X11752Y539498D02*
X11855Y539191D01*
X12114Y538961D01*
X12424Y538808D01*
X12837Y538693D01*
X13302Y538655D01*
X13767Y538693D01*
X14180Y538808D01*
X14490Y538961D01*
X14749Y539191D01*
X14852Y539498D01*
X14749Y539805D01*
X14490Y540035D01*
X14180Y540188D01*
X13767Y540303D01*
X13302Y540341D01*
X12837Y540303D01*
X12424Y540188D01*
X12114Y540035D01*
X11855Y539805D01*
X11752Y539498D01*
G01X14852Y542598D02*
X11752D01*
X12372Y542138D01*
G01X14852D02*
Y543058D01*
G01X10791Y529271D02*
X7691D01*
Y530230D01*
X7846Y530536D01*
X8053Y530728D01*
X8466Y530805D01*
X8879Y530728D01*
X9138Y530498D01*
X9293Y530230D01*
Y529271D01*
G01Y530230D02*
X10791Y530805D01*
G01Y533138D02*
X7691D01*
X8311Y532678D01*
G01X10791D02*
Y533598D01*
G01X10171Y535395D02*
X10533Y535625D01*
X10739Y535931D01*
X10791Y536276D01*
X10739Y536583D01*
X10481Y536890D01*
X10171Y537081D01*
X9861Y537120D01*
X9499Y537043D01*
X9241Y536775D01*
X9138Y536506D01*
Y536161D01*
G01Y536506D02*
X8983Y536736D01*
X8724Y536928D01*
X8414Y537005D01*
X8104Y536928D01*
X7846Y536736D01*
X7691Y536391D01*
X7743Y536046D01*
X7949Y535701D01*
G01X10791Y539338D02*
X7691D01*
X8311Y538878D01*
G01X10791D02*
Y539798D01*
G01Y542438D02*
X7691D01*
X8311Y541978D01*
G01X10791D02*
Y542898D01*
G01X10092Y564823D02*
Y580623D01*
G01X48692Y564823D02*
X10092D01*
G01Y580623D02*
X48692D01*
G01X22672Y597459D02*
X22798D01*
Y589532D01*
X21787D01*
G01X7476Y588503D02*
Y591603D01*
X8435D01*
X8741Y591448D01*
X8933Y591241D01*
X9010Y590828D01*
X8933Y590415D01*
X8703Y590156D01*
X8435Y590001D01*
X7476D01*
G01X8435D02*
X9010Y588503D01*
G01X11343D02*
Y591603D01*
X10883Y590983D01*
G01Y588503D02*
X11803D01*
G01X13715Y591086D02*
X13945Y591396D01*
X14213Y591551D01*
X14520Y591603D01*
X14903Y591500D01*
X15171Y591241D01*
X15248Y590931D01*
X15210Y590621D01*
X15056Y590363D01*
X14290Y589846D01*
X13945Y589485D01*
X13715Y588968D01*
X13638Y588503D01*
X15248D01*
G01X16815Y589795D02*
X17083Y590156D01*
X17313Y590363D01*
X17620Y590466D01*
X17888Y590363D01*
X18080Y590156D01*
X18233Y589846D01*
X18271Y589485D01*
X18233Y589175D01*
X18080Y588865D01*
X17850Y588606D01*
X17581Y588503D01*
X17275Y588606D01*
X17006Y588916D01*
X16853Y589381D01*
X16815Y589898D01*
X16891Y590570D01*
X17006Y590931D01*
X17198Y591293D01*
X17466Y591551D01*
X17735Y591603D01*
X18003Y591500D01*
X18195Y591241D01*
G01X19915Y591086D02*
X20145Y591396D01*
X20413Y591551D01*
X20720Y591603D01*
X21103Y591500D01*
X21371Y591241D01*
X21448Y590931D01*
X21410Y590621D01*
X21256Y590363D01*
X20490Y589846D01*
X20145Y589485D01*
X19915Y588968D01*
X19838Y588503D01*
X21448D01*
G01X18833Y590917D02*
Y593417D01*
X19367D01*
X19580Y593292D01*
X19740Y593125D01*
X19873Y592875D01*
X19980Y592584D01*
X20007Y592167D01*
X19980Y591750D01*
X19873Y591459D01*
X19740Y591209D01*
X19580Y591042D01*
X19367Y590917D01*
X18833D01*
G01X20320Y609079D02*
Y594079D01*
G01X7320D02*
Y609079D01*
G01X20320Y594079D02*
X7320D01*
G01X7503Y610529D02*
Y613729D01*
G01X13703Y610529D02*
X7503D01*
G01X13703Y613729D02*
Y610529D01*
G01X24535Y604470D02*
Y598270D01*
X21335D01*
Y604470D01*
X24535D01*
G01X21818Y613178D02*
Y616278D01*
X22777D01*
X23083Y616123D01*
X23275Y615916D01*
X23352Y615503D01*
X23275Y615090D01*
X23045Y614831D01*
X22777Y614676D01*
X21818D01*
G01X22777D02*
X23352Y613178D01*
G01X25685D02*
Y616278D01*
X25225Y615658D01*
G01Y613178D02*
X26145D01*
G01X27942Y613798D02*
X28172Y613436D01*
X28478Y613230D01*
X28823Y613178D01*
X29130Y613230D01*
X29437Y613488D01*
X29628Y613798D01*
X29667Y614108D01*
X29590Y614470D01*
X29322Y614728D01*
X29053Y614831D01*
X28708D01*
G01X29053D02*
X29283Y614986D01*
X29475Y615245D01*
X29552Y615555D01*
X29475Y615865D01*
X29283Y616123D01*
X28938Y616278D01*
X28593Y616226D01*
X28248Y616020D01*
G01X31885Y613178D02*
Y616278D01*
X31425Y615658D01*
G01Y613178D02*
X32345D01*
G01X34985Y616278D02*
X34678Y616175D01*
X34448Y615916D01*
X34295Y615606D01*
X34180Y615193D01*
X34142Y614728D01*
X34180Y614263D01*
X34295Y613850D01*
X34448Y613540D01*
X34678Y613281D01*
X34985Y613178D01*
X35292Y613281D01*
X35522Y613540D01*
X35675Y613850D01*
X35790Y614263D01*
X35828Y614728D01*
X35790Y615193D01*
X35675Y615606D01*
X35522Y615916D01*
X35292Y616175D01*
X34985Y616278D01*
G01X20203Y616439D02*
Y610239D01*
X17003D01*
Y616439D01*
X20203D01*
G01X22760Y608608D02*
X23293D01*
Y607858D01*
X23133Y607608D01*
X22947Y607441D01*
X22680Y607358D01*
X22413Y607441D01*
X22227Y607608D01*
X22067Y607858D01*
X21960Y608150D01*
X21907Y608483D01*
Y608775D01*
X21960Y609025D01*
X22067Y609316D01*
X22227Y609566D01*
X22387Y609733D01*
X22600Y609858D01*
X22787D01*
X23000Y609775D01*
X23160Y609608D01*
G01X7320Y609079D02*
X20320D01*
G01X7605Y626514D02*
Y642314D01*
G01X46205Y626514D02*
X7605D01*
G01X7503Y613729D02*
X13703D01*
G01X7605Y642314D02*
X46205D01*
G01X17767Y654276D02*
Y652054D01*
X17920Y651589D01*
X18227Y651279D01*
X18610Y651176D01*
X18993Y651279D01*
X19300Y651589D01*
X19453Y652054D01*
Y654276D01*
G01X20867Y651641D02*
X21097Y651383D01*
X21365Y651228D01*
X21710Y651176D01*
X22055Y651279D01*
X22323Y651486D01*
X22515Y651848D01*
X22553Y652261D01*
X22477Y652674D01*
X22285Y652933D01*
X22017Y653139D01*
X21748Y653191D01*
X21480Y653139D01*
X21135Y652933D01*
X21250Y654276D01*
X22285D01*
G01X23967Y651641D02*
X24197Y651383D01*
X24465Y651228D01*
X24810Y651176D01*
X25155Y651279D01*
X25423Y651486D01*
X25615Y651848D01*
X25653Y652261D01*
X25577Y652674D01*
X25385Y652933D01*
X25117Y653139D01*
X24848Y653191D01*
X24580Y653139D01*
X24235Y652933D01*
X24350Y654276D01*
X25385D01*
G01X18495Y657351D02*
Y660551D01*
G01X24695Y657351D02*
X18495D01*
G01X15448Y661667D02*
Y664767D01*
X16407D01*
X16713Y664612D01*
X16905Y664405D01*
X16982Y663992D01*
X16905Y663579D01*
X16675Y663320D01*
X16407Y663165D01*
X15448D01*
G01X16407D02*
X16982Y661667D01*
G01X19315D02*
Y664767D01*
X18855Y664147D01*
G01Y661667D02*
X19775D01*
G01X21687Y664250D02*
X21917Y664560D01*
X22185Y664715D01*
X22492Y664767D01*
X22875Y664664D01*
X23143Y664405D01*
X23220Y664095D01*
X23182Y663785D01*
X23028Y663527D01*
X22262Y663010D01*
X21917Y662649D01*
X21687Y662132D01*
X21610Y661667D01*
X23220D01*
G01X24863Y662029D02*
X25132Y661770D01*
X25438Y661667D01*
X25745Y661770D01*
X26013Y662080D01*
X26205Y662545D01*
X26282Y663010D01*
Y663579D01*
X26205Y664044D01*
X26013Y664457D01*
X25783Y664664D01*
X25515Y664767D01*
X25208Y664664D01*
X24978Y664457D01*
X24825Y664147D01*
X24748Y663734D01*
X24825Y663372D01*
X25017Y663010D01*
X25247Y662804D01*
X25515Y662752D01*
X25822Y662855D01*
X26052Y663114D01*
X26282Y663579D01*
G01X28538Y661667D02*
X28615Y662339D01*
X28730Y662907D01*
X28883Y663424D01*
X29075Y663992D01*
X29382Y664767D01*
X27848D01*
G01X18495Y660551D02*
X24695D01*
G01X37198Y-238524D02*
X37825Y-239049D01*
X38530Y-239364D01*
X39156D01*
X39783Y-239049D01*
X40253Y-238524D01*
X40488Y-237789D01*
X40331Y-237054D01*
X39940Y-236424D01*
X39235Y-236004D01*
X38295Y-235794D01*
X37746Y-235374D01*
X37511Y-234639D01*
X37668Y-233904D01*
X38060Y-233379D01*
X38608Y-233064D01*
X39156D01*
X39705Y-233274D01*
X40175Y-233799D01*
G01X43498Y-239364D02*
Y-233064D01*
G01X46788D02*
Y-239364D01*
G01Y-236214D02*
X43498D01*
G01X50503Y-233064D02*
X52383D01*
G01X51443D02*
Y-239364D01*
G01X50503D02*
X52383D01*
G01X59310D02*
X56176D01*
Y-233064D01*
X59310D01*
G01X58056Y-236109D02*
X56176D01*
G01X62241Y-239364D02*
Y-233064D01*
X65845Y-239364D01*
Y-233064D01*
G01X70186Y-240519D02*
X70500Y-239154D01*
G01X76643Y-233064D02*
Y-239364D01*
G01X74841Y-233064D02*
X78445D01*
G01X80985Y-239364D02*
X82943Y-233064D01*
X84901Y-239364D01*
G01X84196Y-237159D02*
X81690D01*
G01X88303Y-233064D02*
X90183D01*
G01X89243D02*
Y-239364D01*
G01X88303D02*
X90183D01*
G01X93193Y-233064D02*
X94290Y-239364D01*
X95543Y-233064D01*
X96796Y-239364D01*
X97893Y-233064D01*
G01X99885Y-239364D02*
X101843Y-233064D01*
X103801Y-239364D01*
G01X103096Y-237159D02*
X100590D01*
G01X106341Y-239364D02*
Y-233064D01*
X109945Y-239364D01*
Y-233064D01*
G01X119176Y-239364D02*
Y-233064D01*
X121135D01*
X121761Y-233379D01*
X122153Y-233799D01*
X122310Y-234639D01*
X122153Y-235479D01*
X121683Y-236004D01*
X121135Y-236319D01*
X119176D01*
G01X121135D02*
X122310Y-239364D01*
G01X127043Y-239574D02*
X126886Y-239469D01*
Y-239259D01*
X127043Y-239154D01*
X127200Y-239259D01*
Y-239469D01*
X127043Y-239574D01*
G01X133343Y-239364D02*
X132716Y-239259D01*
X132168Y-238839D01*
X131698Y-238209D01*
X131385Y-237474D01*
X131228Y-236634D01*
Y-235794D01*
X131385Y-234954D01*
X131698Y-234219D01*
X132168Y-233589D01*
X132716Y-233169D01*
X133343Y-233064D01*
X133970Y-233169D01*
X134518Y-233589D01*
X134988Y-234219D01*
X135301Y-234954D01*
X135458Y-235794D01*
Y-236634D01*
X135301Y-237474D01*
X134988Y-238209D01*
X134518Y-238839D01*
X133970Y-239259D01*
X133343Y-239364D01*
G01X139643Y-239574D02*
X139486Y-239469D01*
Y-239259D01*
X139643Y-239154D01*
X139800Y-239259D01*
Y-239469D01*
X139643Y-239574D01*
G01X147666Y-233589D02*
X147196Y-233274D01*
X146648Y-233064D01*
X146021D01*
X145316Y-233379D01*
X144768Y-233904D01*
X144376Y-234534D01*
X144063Y-235584D01*
X143985Y-236529D01*
X144141Y-237474D01*
X144376Y-238104D01*
X144846Y-238734D01*
X145395Y-239154D01*
X145943Y-239364D01*
X146491D01*
X147040Y-239154D01*
X147510Y-238839D01*
X147901Y-238419D01*
G01X152243Y-239574D02*
X152086Y-239469D01*
Y-239259D01*
X152243Y-239154D01*
X152400Y-239259D01*
Y-239469D01*
X152243Y-239574D01*
G01X37120Y-229364D02*
Y-223064D01*
G01X40096D02*
X37120Y-226949D01*
G01X40566Y-229364D02*
X38451Y-225164D01*
G01X43420Y-223064D02*
Y-227579D01*
X43733Y-228524D01*
X44360Y-229154D01*
X45143Y-229364D01*
X45926Y-229154D01*
X46553Y-228524D01*
X46866Y-227579D01*
Y-223064D01*
G01X53010Y-229364D02*
X49876D01*
Y-223064D01*
X53010D01*
G01X51756Y-226109D02*
X49876D01*
G01X56803Y-223064D02*
X58683D01*
G01X57743D02*
Y-229364D01*
G01X56803D02*
X58683D01*
G01X68698Y-228524D02*
X69325Y-229049D01*
X70030Y-229364D01*
X70656D01*
X71283Y-229049D01*
X71753Y-228524D01*
X71988Y-227789D01*
X71831Y-227054D01*
X71440Y-226424D01*
X70735Y-226004D01*
X69795Y-225794D01*
X69246Y-225374D01*
X69011Y-224639D01*
X69168Y-223904D01*
X69560Y-223379D01*
X70108Y-223064D01*
X70656D01*
X71205Y-223274D01*
X71675Y-223799D01*
G01X74998Y-229364D02*
Y-223064D01*
G01X78288D02*
Y-229364D01*
G01Y-226214D02*
X74998D01*
G01X80985Y-229364D02*
X82943Y-223064D01*
X84901Y-229364D01*
G01X84196Y-227159D02*
X81690D01*
G01X87441Y-229364D02*
Y-223064D01*
X91045Y-229364D01*
Y-223064D01*
G01X100198Y-229364D02*
Y-223064D01*
G01X103488D02*
Y-229364D01*
G01Y-226214D02*
X100198D01*
G01X106498Y-228524D02*
X107125Y-229049D01*
X107830Y-229364D01*
X108456D01*
X109083Y-229049D01*
X109553Y-228524D01*
X109788Y-227789D01*
X109631Y-227054D01*
X109240Y-226424D01*
X108535Y-226004D01*
X107595Y-225794D01*
X107046Y-225374D01*
X106811Y-224639D01*
X106968Y-223904D01*
X107360Y-223379D01*
X107908Y-223064D01*
X108456D01*
X109005Y-223274D01*
X109475Y-223799D01*
G01X113503Y-223064D02*
X115383D01*
G01X114443D02*
Y-229364D01*
G01X113503D02*
X115383D01*
G01X118785D02*
X120743Y-223064D01*
X122701Y-229364D01*
G01X121996Y-227159D02*
X119490D01*
G01X125241Y-229364D02*
Y-223064D01*
X128845Y-229364D01*
Y-223064D01*
G01X133813Y-226214D02*
X135380D01*
Y-228104D01*
X134910Y-228734D01*
X134361Y-229154D01*
X133578Y-229364D01*
X132795Y-229154D01*
X132246Y-228734D01*
X131776Y-228104D01*
X131463Y-227369D01*
X131306Y-226529D01*
Y-225794D01*
X131463Y-225164D01*
X131776Y-224429D01*
X132246Y-223799D01*
X132716Y-223379D01*
X133343Y-223064D01*
X133891D01*
X134518Y-223274D01*
X134988Y-223694D01*
G01X139486Y-230519D02*
X139800Y-229154D01*
G01X145943Y-223064D02*
Y-229364D01*
G01X144141Y-223064D02*
X147745D01*
G01X150285Y-229364D02*
X152243Y-223064D01*
X154201Y-229364D01*
G01X153496Y-227159D02*
X150990D01*
G01X158543Y-229364D02*
X157916Y-229259D01*
X157368Y-228839D01*
X156898Y-228209D01*
X156585Y-227474D01*
X156428Y-226634D01*
Y-225794D01*
X156585Y-224954D01*
X156898Y-224219D01*
X157368Y-223589D01*
X157916Y-223169D01*
X158543Y-223064D01*
X159170Y-223169D01*
X159718Y-223589D01*
X160188Y-224219D01*
X160501Y-224954D01*
X160658Y-225794D01*
Y-226634D01*
X160501Y-227474D01*
X160188Y-228209D01*
X159718Y-228839D01*
X159170Y-229259D01*
X158543Y-229364D01*
G01X171143D02*
Y-226529D01*
X169576Y-223064D01*
G01X172710D02*
X171143Y-226529D01*
G01X175720Y-223064D02*
Y-227579D01*
X176033Y-228524D01*
X176660Y-229154D01*
X177443Y-229364D01*
X178226Y-229154D01*
X178853Y-228524D01*
X179166Y-227579D01*
Y-223064D01*
G01X181785Y-229364D02*
X183743Y-223064D01*
X185701Y-229364D01*
G01X184996Y-227159D02*
X182490D01*
G01X188241Y-229364D02*
Y-223064D01*
X191845Y-229364D01*
Y-223064D01*
G01X37041Y-219364D02*
Y-213064D01*
X40645Y-219364D01*
Y-213064D01*
G01X45143Y-219364D02*
X44516Y-219259D01*
X43968Y-218839D01*
X43498Y-218209D01*
X43185Y-217474D01*
X43028Y-216634D01*
Y-215794D01*
X43185Y-214954D01*
X43498Y-214219D01*
X43968Y-213589D01*
X44516Y-213169D01*
X45143Y-213064D01*
X45770Y-213169D01*
X46318Y-213589D01*
X46788Y-214219D01*
X47101Y-214954D01*
X47258Y-215794D01*
Y-216634D01*
X47101Y-217474D01*
X46788Y-218209D01*
X46318Y-218839D01*
X45770Y-219259D01*
X45143Y-219364D01*
G01X51443Y-219574D02*
X51286Y-219469D01*
Y-219259D01*
X51443Y-219154D01*
X51600Y-219259D01*
Y-219469D01*
X51443Y-219574D01*
G01X57743Y-219364D02*
Y-213064D01*
X56803Y-214324D01*
G01Y-219364D02*
X58683D01*
G01X64043D02*
X64591Y-219259D01*
X65218Y-218944D01*
X65610Y-218419D01*
X65766Y-217684D01*
X65610Y-216949D01*
X65140Y-216319D01*
X64435Y-216004D01*
X63651D01*
X63181Y-215794D01*
X62790Y-215269D01*
X62633Y-214534D01*
X62868Y-213799D01*
X63416Y-213274D01*
X64043Y-213064D01*
X64670Y-213274D01*
X65218Y-213799D01*
X65453Y-214534D01*
X65296Y-215269D01*
X64905Y-215794D01*
X64435Y-216004D01*
X63651D01*
X62946Y-216319D01*
X62476Y-216949D01*
X62320Y-217684D01*
X62476Y-218419D01*
X62868Y-218944D01*
X63495Y-219259D01*
X64043Y-219364D01*
G01X70343D02*
X70891Y-219259D01*
X71518Y-218944D01*
X71910Y-218419D01*
X72066Y-217684D01*
X71910Y-216949D01*
X71440Y-216319D01*
X70735Y-216004D01*
X69951D01*
X69481Y-215794D01*
X69090Y-215269D01*
X68933Y-214534D01*
X69168Y-213799D01*
X69716Y-213274D01*
X70343Y-213064D01*
X70970Y-213274D01*
X71518Y-213799D01*
X71753Y-214534D01*
X71596Y-215269D01*
X71205Y-215794D01*
X70735Y-216004D01*
X69951D01*
X69246Y-216319D01*
X68776Y-216949D01*
X68620Y-217684D01*
X68776Y-218419D01*
X69168Y-218944D01*
X69795Y-219259D01*
X70343Y-219364D01*
G01X76486Y-220519D02*
X76800Y-219154D01*
G01X80593Y-213064D02*
X81690Y-219364D01*
X82943Y-213064D01*
X84196Y-219364D01*
X85293Y-213064D01*
G01X90810Y-219364D02*
X87676D01*
Y-213064D01*
X90810D01*
G01X89556Y-216109D02*
X87676D01*
G01X93741Y-219364D02*
Y-213064D01*
X97345Y-219364D01*
Y-213064D01*
G01X106498Y-219364D02*
Y-213064D01*
G01X109788D02*
Y-219364D01*
G01Y-216214D02*
X106498D01*
G01X112093Y-213064D02*
X113190Y-219364D01*
X114443Y-213064D01*
X115696Y-219364D01*
X116793Y-213064D01*
G01X118785Y-219364D02*
X120743Y-213064D01*
X122701Y-219364D01*
G01X121996Y-217159D02*
X119490D01*
G01X131855Y-214114D02*
X132325Y-213484D01*
X132873Y-213169D01*
X133500Y-213064D01*
X134283Y-213274D01*
X134831Y-213799D01*
X134988Y-214429D01*
X134910Y-215059D01*
X134596Y-215584D01*
X133030Y-216634D01*
X132325Y-217369D01*
X131855Y-218419D01*
X131698Y-219364D01*
X134988D01*
G01X137841D02*
Y-213064D01*
X141445Y-219364D01*
Y-213064D01*
G01X144220Y-219364D02*
Y-213064D01*
X145786D01*
X146413Y-213379D01*
X146883Y-213799D01*
X147275Y-214429D01*
X147588Y-215164D01*
X147666Y-216214D01*
X147588Y-217264D01*
X147275Y-217999D01*
X146883Y-218629D01*
X146413Y-219049D01*
X145786Y-219364D01*
X144220D01*
G01X156976D02*
Y-213064D01*
X158935D01*
X159561Y-213379D01*
X159953Y-213799D01*
X160110Y-214639D01*
X159953Y-215479D01*
X159483Y-216004D01*
X158935Y-216319D01*
X156976D01*
G01X158935D02*
X160110Y-219364D01*
G01X163120D02*
Y-213064D01*
X164686D01*
X165313Y-213379D01*
X165783Y-213799D01*
X166175Y-214429D01*
X166488Y-215164D01*
X166566Y-216214D01*
X166488Y-217264D01*
X166175Y-217999D01*
X165783Y-218629D01*
X165313Y-219049D01*
X164686Y-219364D01*
X163120D01*
G01X171143Y-219574D02*
X170986Y-219469D01*
Y-219259D01*
X171143Y-219154D01*
X171300Y-219259D01*
Y-219469D01*
X171143Y-219574D01*
G01X28618Y17711D02*
Y11511D01*
G01D02*
X25418D01*
G01D02*
Y17711D01*
G01X38741Y10020D02*
X29941D01*
G01Y15820D02*
Y10020D01*
G01X25418Y17711D02*
X28618D01*
G01X25518Y14611D02*
X28518D01*
G01X35935Y32014D02*
Y28814D01*
G01D02*
X29735D01*
G01D02*
Y32014D01*
G01Y28014D02*
X35935D01*
G01D02*
Y24814D01*
G01D02*
X29735D01*
G01D02*
Y28014D01*
G01X24272Y28197D02*
X26494D01*
X26959Y28350D01*
X27269Y28657D01*
X27372Y29040D01*
X27269Y29423D01*
X26959Y29730D01*
X26494Y29883D01*
X24272D01*
G01X27372Y32140D02*
X24272D01*
X24892Y31680D01*
G01X27372D02*
Y32600D01*
G01Y35240D02*
X24272D01*
X24892Y34780D01*
G01X27372D02*
Y35700D01*
G01X49980Y24785D02*
X36980D01*
G01D02*
Y31385D01*
G01X29941Y23620D02*
X38741D01*
G01X31441Y16820D02*
X29941Y15820D01*
G01Y17820D02*
X31441Y16820D01*
G01X29941Y23620D02*
Y17820D01*
G01X35999Y42624D02*
Y48824D01*
G01X39199Y42624D02*
X35999D01*
G01X32077Y39239D02*
X35277D01*
G01X35177Y36139D02*
X32177D01*
G01X32077Y33039D02*
Y39239D01*
G01X35277D02*
Y33039D01*
G01D02*
X32077D01*
G01X28579Y42230D02*
X25479D01*
Y43189D01*
X25634Y43495D01*
X25841Y43687D01*
X26254Y43764D01*
X26667Y43687D01*
X26926Y43457D01*
X27081Y43189D01*
Y42230D01*
G01Y43189D02*
X28579Y43764D01*
G01X25996Y45369D02*
X25686Y45599D01*
X25531Y45867D01*
X25479Y46174D01*
X25582Y46557D01*
X25841Y46825D01*
X26151Y46902D01*
X26461Y46864D01*
X26719Y46710D01*
X27236Y45944D01*
X27597Y45599D01*
X28114Y45369D01*
X28579Y45292D01*
Y46902D01*
G01Y49197D02*
X25479D01*
X26099Y48737D01*
G01X28579D02*
Y49657D01*
G01Y52297D02*
X28527Y52565D01*
X28372Y52872D01*
X28114Y53064D01*
X27752Y53140D01*
X27391Y53064D01*
X27081Y52834D01*
X26926Y52489D01*
Y52105D01*
X26822Y51875D01*
X26564Y51684D01*
X26202Y51607D01*
X25841Y51722D01*
X25582Y51990D01*
X25479Y52297D01*
X25582Y52604D01*
X25841Y52872D01*
X26202Y52987D01*
X26564Y52910D01*
X26822Y52719D01*
X26926Y52489D01*
Y52105D01*
X27081Y51760D01*
X27391Y51530D01*
X27752Y51454D01*
X28114Y51530D01*
X28372Y51722D01*
X28527Y52029D01*
X28579Y52297D01*
G01X32757Y42230D02*
X29657D01*
Y43189D01*
X29812Y43495D01*
X30019Y43687D01*
X30432Y43764D01*
X30845Y43687D01*
X31104Y43457D01*
X31259Y43189D01*
Y42230D01*
G01Y43189D02*
X32757Y43764D01*
G01X30174Y45369D02*
X29864Y45599D01*
X29709Y45867D01*
X29657Y46174D01*
X29760Y46557D01*
X30019Y46825D01*
X30329Y46902D01*
X30639Y46864D01*
X30897Y46710D01*
X31414Y45944D01*
X31775Y45599D01*
X32292Y45369D01*
X32757Y45292D01*
Y46902D01*
G01Y49197D02*
X29657D01*
X30277Y48737D01*
G01X32757D02*
Y49657D01*
G01X32292Y51454D02*
X32550Y51684D01*
X32705Y51952D01*
X32757Y52297D01*
X32654Y52642D01*
X32447Y52910D01*
X32085Y53102D01*
X31672Y53140D01*
X31259Y53064D01*
X31000Y52872D01*
X30794Y52604D01*
X30742Y52335D01*
X30794Y52067D01*
X31000Y51722D01*
X29657Y51837D01*
Y52872D01*
G01X29735Y32014D02*
X35935D01*
G01X36980Y31385D02*
X39480Y32885D01*
G01D02*
X36980Y34385D01*
G01Y40985D02*
X49980D01*
G01X36980Y34385D02*
Y40985D01*
G01X39099Y45724D02*
X36099D01*
G01X35999Y48824D02*
X39199D01*
G01X37244Y60105D02*
X37089Y59875D01*
X36986Y59607D01*
Y59300D01*
X37141Y58955D01*
X37399Y58687D01*
X37709Y58495D01*
X38226Y58342D01*
X38691Y58304D01*
X39156Y58380D01*
X39466Y58495D01*
X39776Y58725D01*
X39983Y58994D01*
X40086Y59262D01*
Y59530D01*
X39983Y59799D01*
X39828Y60029D01*
X39621Y60220D01*
G01Y61519D02*
X39879Y61749D01*
X40034Y62017D01*
X40086Y62362D01*
X39983Y62707D01*
X39776Y62975D01*
X39414Y63167D01*
X39001Y63205D01*
X38588Y63129D01*
X38329Y62937D01*
X38123Y62669D01*
X38071Y62400D01*
X38123Y62132D01*
X38329Y61787D01*
X36986Y61902D01*
Y62937D01*
G01X40086Y65922D02*
X36986D01*
X39208Y64504D01*
Y66420D01*
G01X39466Y67719D02*
X39828Y67949D01*
X40034Y68255D01*
X40086Y68600D01*
X40034Y68907D01*
X39776Y69214D01*
X39466Y69405D01*
X39156Y69444D01*
X38794Y69367D01*
X38536Y69099D01*
X38433Y68830D01*
Y68485D01*
G01Y68830D02*
X38278Y69060D01*
X38019Y69252D01*
X37709Y69329D01*
X37399Y69252D01*
X37141Y69060D01*
X36986Y68715D01*
X37038Y68370D01*
X37244Y68025D01*
G01X28953Y60105D02*
X28798Y59875D01*
X28695Y59607D01*
Y59300D01*
X28850Y58955D01*
X29108Y58687D01*
X29418Y58495D01*
X29935Y58342D01*
X30400Y58304D01*
X30865Y58380D01*
X31175Y58495D01*
X31485Y58725D01*
X31692Y58994D01*
X31795Y59262D01*
Y59530D01*
X31692Y59799D01*
X31537Y60029D01*
X31330Y60220D01*
G01Y61519D02*
X31588Y61749D01*
X31743Y62017D01*
X31795Y62362D01*
X31692Y62707D01*
X31485Y62975D01*
X31123Y63167D01*
X30710Y63205D01*
X30297Y63129D01*
X30038Y62937D01*
X29832Y62669D01*
X29780Y62400D01*
X29832Y62132D01*
X30038Y61787D01*
X28695Y61902D01*
Y62937D01*
G01X31795Y65922D02*
X28695D01*
X30917Y64504D01*
Y66420D01*
G01X30503Y67834D02*
X30142Y68102D01*
X29935Y68332D01*
X29832Y68639D01*
X29935Y68907D01*
X30142Y69099D01*
X30452Y69252D01*
X30813Y69290D01*
X31123Y69252D01*
X31433Y69099D01*
X31692Y68869D01*
X31795Y68600D01*
X31692Y68294D01*
X31382Y68025D01*
X30917Y67872D01*
X30400Y67834D01*
X29728Y67910D01*
X29367Y68025D01*
X29005Y68217D01*
X28747Y68485D01*
X28695Y68754D01*
X28798Y69022D01*
X29057Y69214D01*
G01X27755Y58495D02*
X24655D01*
Y59454D01*
X24810Y59760D01*
X25017Y59952D01*
X25430Y60029D01*
X25843Y59952D01*
X26102Y59722D01*
X26257Y59454D01*
Y58495D01*
G01Y59454D02*
X27755Y60029D01*
G01X26463Y61634D02*
X26102Y61902D01*
X25895Y62132D01*
X25792Y62439D01*
X25895Y62707D01*
X26102Y62899D01*
X26412Y63052D01*
X26773Y63090D01*
X27083Y63052D01*
X27393Y62899D01*
X27652Y62669D01*
X27755Y62400D01*
X27652Y62094D01*
X27342Y61825D01*
X26877Y61672D01*
X26360Y61634D01*
X25688Y61710D01*
X25327Y61825D01*
X24965Y62017D01*
X24707Y62285D01*
X24655Y62554D01*
X24758Y62822D01*
X25017Y63014D01*
G01X27290Y64619D02*
X27548Y64849D01*
X27703Y65117D01*
X27755Y65462D01*
X27652Y65807D01*
X27445Y66075D01*
X27083Y66267D01*
X26670Y66305D01*
X26257Y66229D01*
X25998Y66037D01*
X25792Y65769D01*
X25740Y65500D01*
X25792Y65232D01*
X25998Y64887D01*
X24655Y65002D01*
Y66037D01*
G01X27755Y68562D02*
X24655D01*
X25275Y68102D01*
G01X27755D02*
Y69022D01*
G01X24286Y87898D02*
X26508D01*
X26973Y88051D01*
X27283Y88358D01*
X27386Y88741D01*
X27283Y89124D01*
X26973Y89431D01*
X26508Y89584D01*
X24286D01*
G01X26921Y90998D02*
X27179Y91228D01*
X27334Y91496D01*
X27386Y91841D01*
X27283Y92186D01*
X27076Y92454D01*
X26714Y92646D01*
X26301Y92684D01*
X25888Y92608D01*
X25629Y92416D01*
X25423Y92148D01*
X25371Y91879D01*
X25423Y91611D01*
X25629Y91266D01*
X24286Y91381D01*
Y92416D01*
G01X24803Y94213D02*
X24493Y94443D01*
X24338Y94711D01*
X24286Y95018D01*
X24389Y95401D01*
X24648Y95669D01*
X24958Y95746D01*
X25268Y95708D01*
X25526Y95554D01*
X26043Y94788D01*
X26404Y94443D01*
X26921Y94213D01*
X27386Y94136D01*
Y95746D01*
G01X28783Y83140D02*
Y98940D01*
G01X67383Y83140D02*
X28783D01*
G01Y98940D02*
X67383D01*
G01X28422Y110983D02*
X28652Y111293D01*
X28920Y111448D01*
X29227Y111500D01*
X29610Y111397D01*
X29878Y111138D01*
X29955Y110828D01*
X29917Y110518D01*
X29763Y110260D01*
X28997Y109743D01*
X28652Y109382D01*
X28422Y108865D01*
X28345Y108400D01*
X29955D01*
G01X34327Y134865D02*
Y137965D01*
X33867Y137345D01*
G01Y134865D02*
X34787D01*
G01X37427D02*
Y137965D01*
X36967Y137345D01*
G01Y134865D02*
X37887D01*
G01X29725Y261024D02*
Y138977D01*
G01X31300Y261024D02*
Y138977D01*
G01X37183Y281197D02*
X37254D01*
Y265094D01*
X39901Y267741D01*
Y267812D01*
X35066D01*
X34995Y267741D01*
Y267388D01*
X37148Y265235D01*
G01X32755Y310932D02*
Y295832D01*
G01Y349132D02*
Y364132D01*
G01X26750Y370584D02*
X37750D01*
G01X26750Y396584D02*
Y370584D01*
G01X37750D02*
Y396584D01*
G01X25487Y370584D02*
Y396584D01*
G01X30281Y384265D02*
X34219D01*
G01X32250Y383871D02*
X30281Y381903D01*
G01X34219D02*
X32250Y383871D01*
G01X30281Y381903D02*
X34219D01*
G01X33883Y397933D02*
X30783D01*
Y398699D01*
X30938Y399006D01*
X31145Y399236D01*
X31455Y399428D01*
X31816Y399581D01*
X32333Y399619D01*
X32850Y399581D01*
X33211Y399428D01*
X33521Y399236D01*
X33728Y399006D01*
X33883Y398699D01*
Y397933D01*
G01X31300Y401148D02*
X30990Y401378D01*
X30835Y401646D01*
X30783Y401953D01*
X30886Y402336D01*
X31145Y402604D01*
X31455Y402681D01*
X31765Y402643D01*
X32023Y402489D01*
X32540Y401723D01*
X32901Y401378D01*
X33418Y401148D01*
X33883Y401071D01*
Y402681D01*
G01X33521Y404324D02*
X33780Y404593D01*
X33883Y404899D01*
X33780Y405206D01*
X33470Y405474D01*
X33005Y405666D01*
X32540Y405743D01*
X31971D01*
X31506Y405666D01*
X31093Y405474D01*
X30886Y405244D01*
X30783Y404976D01*
X30886Y404669D01*
X31093Y404439D01*
X31403Y404286D01*
X31816Y404209D01*
X32178Y404286D01*
X32540Y404478D01*
X32746Y404708D01*
X32798Y404976D01*
X32695Y405283D01*
X32436Y405513D01*
X31971Y405743D01*
G01X37750Y396584D02*
X26750D01*
G01X37750Y396084D02*
X37762Y396076D01*
G01X26750Y396084D02*
X37750D01*
G01Y395584D02*
X26750D01*
G01X25487Y396084D02*
X25499Y396076D01*
G01X29744Y483843D02*
Y486943D01*
X30664D01*
X30971Y486788D01*
X31201Y486426D01*
X31278Y486013D01*
X31201Y485600D01*
X31009Y485290D01*
X30664Y485135D01*
X29744D01*
G01X34454Y486685D02*
X34224Y486840D01*
X33956Y486943D01*
X33649D01*
X33304Y486788D01*
X33036Y486530D01*
X32844Y486220D01*
X32691Y485703D01*
X32653Y485238D01*
X32729Y484773D01*
X32844Y484463D01*
X33074Y484153D01*
X33343Y483946D01*
X33611Y483843D01*
X33879D01*
X34148Y483946D01*
X34378Y484101D01*
X34569Y484308D01*
G01X35868D02*
X36098Y484050D01*
X36366Y483895D01*
X36711Y483843D01*
X37056Y483946D01*
X37324Y484153D01*
X37516Y484515D01*
X37554Y484928D01*
X37478Y485341D01*
X37286Y485600D01*
X37018Y485806D01*
X36749Y485858D01*
X36481Y485806D01*
X36136Y485600D01*
X36251Y486943D01*
X37286D01*
G01X39083Y485135D02*
X39351Y485496D01*
X39581Y485703D01*
X39888Y485806D01*
X40156Y485703D01*
X40348Y485496D01*
X40501Y485186D01*
X40539Y484825D01*
X40501Y484515D01*
X40348Y484205D01*
X40118Y483946D01*
X39849Y483843D01*
X39543Y483946D01*
X39274Y484256D01*
X39121Y484721D01*
X39083Y485238D01*
X39159Y485910D01*
X39274Y486271D01*
X39466Y486633D01*
X39734Y486891D01*
X40003Y486943D01*
X40271Y486840D01*
X40463Y486581D01*
G01X29761Y479796D02*
Y482896D01*
X30681D01*
X30988Y482741D01*
X31218Y482379D01*
X31295Y481966D01*
X31218Y481553D01*
X31026Y481243D01*
X30681Y481088D01*
X29761D01*
G01X34471Y482638D02*
X34241Y482793D01*
X33973Y482896D01*
X33666D01*
X33321Y482741D01*
X33053Y482483D01*
X32861Y482173D01*
X32708Y481656D01*
X32670Y481191D01*
X32746Y480726D01*
X32861Y480416D01*
X33091Y480106D01*
X33360Y479899D01*
X33628Y479796D01*
X33896D01*
X34165Y479899D01*
X34395Y480054D01*
X34586Y480261D01*
G01X35885D02*
X36115Y480003D01*
X36383Y479848D01*
X36728Y479796D01*
X37073Y479899D01*
X37341Y480106D01*
X37533Y480468D01*
X37571Y480881D01*
X37495Y481294D01*
X37303Y481553D01*
X37035Y481759D01*
X36766Y481811D01*
X36498Y481759D01*
X36153Y481553D01*
X36268Y482896D01*
X37303D01*
G01X38985Y480261D02*
X39215Y480003D01*
X39483Y479848D01*
X39828Y479796D01*
X40173Y479899D01*
X40441Y480106D01*
X40633Y480468D01*
X40671Y480881D01*
X40595Y481294D01*
X40403Y481553D01*
X40135Y481759D01*
X39866Y481811D01*
X39598Y481759D01*
X39253Y481553D01*
X39368Y482896D01*
X40403D01*
G01X29721Y475753D02*
Y478853D01*
X30641D01*
X30948Y478698D01*
X31178Y478336D01*
X31255Y477923D01*
X31178Y477510D01*
X30986Y477200D01*
X30641Y477045D01*
X29721D01*
G01X32821Y475753D02*
Y478853D01*
X33780D01*
X34086Y478698D01*
X34278Y478491D01*
X34355Y478078D01*
X34278Y477665D01*
X34048Y477406D01*
X33780Y477251D01*
X32821D01*
G01X33780D02*
X34355Y475753D01*
G01X35960Y478336D02*
X36190Y478646D01*
X36458Y478801D01*
X36765Y478853D01*
X37148Y478750D01*
X37416Y478491D01*
X37493Y478181D01*
X37455Y477871D01*
X37301Y477613D01*
X36535Y477096D01*
X36190Y476735D01*
X35960Y476218D01*
X35883Y475753D01*
X37493D01*
G01X39060Y478336D02*
X39290Y478646D01*
X39558Y478801D01*
X39865Y478853D01*
X40248Y478750D01*
X40516Y478491D01*
X40593Y478181D01*
X40555Y477871D01*
X40401Y477613D01*
X39635Y477096D01*
X39290Y476735D01*
X39060Y476218D01*
X38983Y475753D01*
X40593D01*
G01X34751Y494919D02*
Y498019D01*
X35671D01*
X35978Y497864D01*
X36208Y497502D01*
X36285Y497089D01*
X36208Y496676D01*
X36016Y496366D01*
X35671Y496211D01*
X34751D01*
G01X39461Y497761D02*
X39231Y497916D01*
X38963Y498019D01*
X38656D01*
X38311Y497864D01*
X38043Y497606D01*
X37851Y497296D01*
X37698Y496779D01*
X37660Y496314D01*
X37736Y495849D01*
X37851Y495539D01*
X38081Y495229D01*
X38350Y495022D01*
X38618Y494919D01*
X38886D01*
X39155Y495022D01*
X39385Y495177D01*
X39576Y495384D01*
G01X40875D02*
X41105Y495126D01*
X41373Y494971D01*
X41718Y494919D01*
X42063Y495022D01*
X42331Y495229D01*
X42523Y495591D01*
X42561Y496004D01*
X42485Y496417D01*
X42293Y496676D01*
X42025Y496882D01*
X41756Y496934D01*
X41488Y496882D01*
X41143Y496676D01*
X41258Y498019D01*
X42293D01*
G01X44818Y494919D02*
X45086Y494971D01*
X45393Y495126D01*
X45585Y495384D01*
X45661Y495746D01*
X45585Y496107D01*
X45355Y496417D01*
X45010Y496572D01*
X44626D01*
X44396Y496676D01*
X44205Y496934D01*
X44128Y497296D01*
X44243Y497657D01*
X44511Y497916D01*
X44818Y498019D01*
X45125Y497916D01*
X45393Y497657D01*
X45508Y497296D01*
X45431Y496934D01*
X45240Y496676D01*
X45010Y496572D01*
X44626D01*
X44281Y496417D01*
X44051Y496107D01*
X43975Y495746D01*
X44051Y495384D01*
X44243Y495126D01*
X44550Y494971D01*
X44818Y494919D01*
G01X35201Y498919D02*
Y502019D01*
X36121D01*
X36428Y501864D01*
X36658Y501502D01*
X36735Y501089D01*
X36658Y500676D01*
X36466Y500366D01*
X36121Y500211D01*
X35201D01*
G01X39911Y501761D02*
X39681Y501916D01*
X39413Y502019D01*
X39106D01*
X38761Y501864D01*
X38493Y501606D01*
X38301Y501296D01*
X38148Y500779D01*
X38110Y500314D01*
X38186Y499849D01*
X38301Y499539D01*
X38531Y499229D01*
X38800Y499022D01*
X39068Y498919D01*
X39336D01*
X39605Y499022D01*
X39835Y499177D01*
X40026Y499384D01*
G01X41325D02*
X41555Y499126D01*
X41823Y498971D01*
X42168Y498919D01*
X42513Y499022D01*
X42781Y499229D01*
X42973Y499591D01*
X43011Y500004D01*
X42935Y500417D01*
X42743Y500676D01*
X42475Y500882D01*
X42206Y500934D01*
X41938Y500882D01*
X41593Y500676D01*
X41708Y502019D01*
X42743D01*
G01X44616Y499281D02*
X44885Y499022D01*
X45191Y498919D01*
X45498Y499022D01*
X45766Y499332D01*
X45958Y499797D01*
X46035Y500262D01*
Y500831D01*
X45958Y501296D01*
X45766Y501709D01*
X45536Y501916D01*
X45268Y502019D01*
X44961Y501916D01*
X44731Y501709D01*
X44578Y501399D01*
X44501Y500986D01*
X44578Y500624D01*
X44770Y500262D01*
X45000Y500056D01*
X45268Y500004D01*
X45575Y500107D01*
X45805Y500366D01*
X46035Y500831D01*
G01X34280Y516628D02*
Y519728D01*
X35200D01*
X35507Y519573D01*
X35737Y519211D01*
X35814Y518798D01*
X35737Y518385D01*
X35545Y518075D01*
X35200Y517920D01*
X34280D01*
G01X37380Y516628D02*
Y519728D01*
X38339D01*
X38645Y519573D01*
X38837Y519366D01*
X38914Y518953D01*
X38837Y518540D01*
X38607Y518281D01*
X38339Y518126D01*
X37380D01*
G01X38339D02*
X38914Y516628D01*
G01X40404Y517248D02*
X40634Y516886D01*
X40940Y516680D01*
X41285Y516628D01*
X41592Y516680D01*
X41899Y516938D01*
X42090Y517248D01*
X42129Y517558D01*
X42052Y517920D01*
X41784Y518178D01*
X41515Y518281D01*
X41170D01*
G01X41515D02*
X41745Y518436D01*
X41937Y518695D01*
X42014Y519005D01*
X41937Y519315D01*
X41745Y519573D01*
X41400Y519728D01*
X41055Y519676D01*
X40710Y519470D01*
G01X44347Y519728D02*
X44040Y519625D01*
X43810Y519366D01*
X43657Y519056D01*
X43542Y518643D01*
X43504Y518178D01*
X43542Y517713D01*
X43657Y517300D01*
X43810Y516990D01*
X44040Y516731D01*
X44347Y516628D01*
X44654Y516731D01*
X44884Y516990D01*
X45037Y517300D01*
X45152Y517713D01*
X45190Y518178D01*
X45152Y518643D01*
X45037Y519056D01*
X44884Y519366D01*
X44654Y519625D01*
X44347Y519728D01*
G01X24630Y531000D02*
X24475Y530770D01*
X24372Y530502D01*
Y530195D01*
X24527Y529850D01*
X24785Y529582D01*
X25095Y529390D01*
X25612Y529237D01*
X26077Y529199D01*
X26542Y529275D01*
X26852Y529390D01*
X27162Y529620D01*
X27369Y529889D01*
X27472Y530157D01*
Y530425D01*
X27369Y530694D01*
X27214Y530924D01*
X27007Y531115D01*
G01Y532414D02*
X27265Y532644D01*
X27420Y532912D01*
X27472Y533257D01*
X27369Y533602D01*
X27162Y533870D01*
X26800Y534062D01*
X26387Y534100D01*
X25974Y534024D01*
X25715Y533832D01*
X25509Y533564D01*
X25457Y533295D01*
X25509Y533027D01*
X25715Y532682D01*
X24372Y532797D01*
Y533832D01*
G01X26180Y535629D02*
X25819Y535897D01*
X25612Y536127D01*
X25509Y536434D01*
X25612Y536702D01*
X25819Y536894D01*
X26129Y537047D01*
X26490Y537085D01*
X26800Y537047D01*
X27110Y536894D01*
X27369Y536664D01*
X27472Y536395D01*
X27369Y536089D01*
X27059Y535820D01*
X26594Y535667D01*
X26077Y535629D01*
X25405Y535705D01*
X25044Y535820D01*
X24682Y536012D01*
X24424Y536280D01*
X24372Y536549D01*
X24475Y536817D01*
X24734Y537009D01*
G01X24889Y538729D02*
X24579Y538959D01*
X24424Y539227D01*
X24372Y539534D01*
X24475Y539917D01*
X24734Y540185D01*
X25044Y540262D01*
X25354Y540224D01*
X25612Y540070D01*
X26129Y539304D01*
X26490Y538959D01*
X27007Y538729D01*
X27472Y538652D01*
Y540262D01*
G01X29250Y531000D02*
X29095Y530770D01*
X28992Y530502D01*
Y530195D01*
X29147Y529850D01*
X29405Y529582D01*
X29715Y529390D01*
X30232Y529237D01*
X30697Y529199D01*
X31162Y529275D01*
X31472Y529390D01*
X31782Y529620D01*
X31989Y529889D01*
X32092Y530157D01*
Y530425D01*
X31989Y530694D01*
X31834Y530924D01*
X31627Y531115D01*
G01Y532414D02*
X31885Y532644D01*
X32040Y532912D01*
X32092Y533257D01*
X31989Y533602D01*
X31782Y533870D01*
X31420Y534062D01*
X31007Y534100D01*
X30594Y534024D01*
X30335Y533832D01*
X30129Y533564D01*
X30077Y533295D01*
X30129Y533027D01*
X30335Y532682D01*
X28992Y532797D01*
Y533832D01*
G01X31627Y535514D02*
X31885Y535744D01*
X32040Y536012D01*
X32092Y536357D01*
X31989Y536702D01*
X31782Y536970D01*
X31420Y537162D01*
X31007Y537200D01*
X30594Y537124D01*
X30335Y536932D01*
X30129Y536664D01*
X30077Y536395D01*
X30129Y536127D01*
X30335Y535782D01*
X28992Y535897D01*
Y536932D01*
G01X32092Y539917D02*
X28992D01*
X31214Y538499D01*
Y540415D01*
G01X37282Y545434D02*
Y548634D01*
G01X43482Y545434D02*
X37282D01*
G01Y548634D02*
X43482D01*
G01X32540Y548849D02*
X35740D01*
G01X32540Y542649D02*
Y548849D01*
G01X35740Y542649D02*
X32540D01*
G01X35740Y548849D02*
Y542649D01*
G01X28540Y548849D02*
X31740D01*
G01X28540Y542649D02*
Y548849D01*
G01X31740Y542649D02*
X28540D01*
G01X31740Y548849D02*
Y542649D01*
G01X27745Y548896D02*
Y542696D01*
X24545D01*
Y548896D01*
X27745D01*
G01X35672Y595685D02*
Y598885D01*
G01X41872Y595685D02*
X35672D01*
G01X30843Y590592D02*
Y593692D01*
X31802D01*
X32108Y593537D01*
X32300Y593330D01*
X32377Y592917D01*
X32300Y592504D01*
X32070Y592245D01*
X31802Y592090D01*
X30843D01*
G01X31802D02*
X32377Y590592D01*
G01X34710D02*
Y593692D01*
X34250Y593072D01*
G01Y590592D02*
X35170D01*
G01X36967Y591212D02*
X37197Y590850D01*
X37503Y590644D01*
X37848Y590592D01*
X38155Y590644D01*
X38462Y590902D01*
X38653Y591212D01*
X38692Y591522D01*
X38615Y591884D01*
X38347Y592142D01*
X38078Y592245D01*
X37733D01*
G01X38078D02*
X38308Y592400D01*
X38500Y592659D01*
X38577Y592969D01*
X38500Y593279D01*
X38308Y593537D01*
X37963Y593692D01*
X37618Y593640D01*
X37273Y593434D01*
G01X40910Y593692D02*
X40603Y593589D01*
X40373Y593330D01*
X40220Y593020D01*
X40105Y592607D01*
X40067Y592142D01*
X40105Y591677D01*
X40220Y591264D01*
X40373Y590954D01*
X40603Y590695D01*
X40910Y590592D01*
X41217Y590695D01*
X41447Y590954D01*
X41600Y591264D01*
X41715Y591677D01*
X41753Y592142D01*
X41715Y592607D01*
X41600Y593020D01*
X41447Y593330D01*
X41217Y593589D01*
X40910Y593692D01*
G01X44010D02*
X43703Y593589D01*
X43473Y593330D01*
X43320Y593020D01*
X43205Y592607D01*
X43167Y592142D01*
X43205Y591677D01*
X43320Y591264D01*
X43473Y590954D01*
X43703Y590695D01*
X44010Y590592D01*
X44317Y590695D01*
X44547Y590954D01*
X44700Y591264D01*
X44815Y591677D01*
X44853Y592142D01*
X44815Y592607D01*
X44700Y593020D01*
X44547Y593330D01*
X44317Y593589D01*
X44010Y593692D01*
G01X29630Y597392D02*
Y594192D01*
G01X23430D02*
Y597392D01*
G01X29630Y594192D02*
X23430D01*
G01X25240Y600770D02*
X59920D01*
G01X25240Y611700D02*
Y600770D01*
G01X48470Y611700D02*
X25240D01*
G01X35412Y606525D02*
Y609725D01*
G01X41612Y606525D02*
X35412D01*
G01Y609725D02*
X41612D01*
G01X35672Y598885D02*
X41872D01*
G01X30670Y609940D02*
X33870D01*
G01X30670Y603740D02*
Y609940D01*
G01X33870Y603740D02*
X30670D01*
G01X33870Y609940D02*
Y603740D01*
G01X26670Y609940D02*
X29870D01*
G01X26670Y603740D02*
Y609940D01*
G01X29870Y603740D02*
X26670D01*
G01X29870Y609940D02*
Y603740D01*
G01X23430Y597392D02*
X29630D01*
G01X34385Y660451D02*
Y657451D01*
G01X37485Y660551D02*
Y657351D01*
G01X31285D02*
Y660551D01*
G01X37485Y657351D02*
X31285D01*
G01X24695Y660551D02*
Y657351D01*
G01X33068Y666292D02*
X32838Y666447D01*
X32570Y666550D01*
X32263D01*
X31918Y666395D01*
X31650Y666137D01*
X31458Y665827D01*
X31305Y665310D01*
X31267Y664845D01*
X31343Y664380D01*
X31458Y664070D01*
X31688Y663760D01*
X31957Y663553D01*
X32225Y663450D01*
X32493D01*
X32762Y663553D01*
X32992Y663708D01*
X33183Y663915D01*
G01X34482D02*
X34712Y663657D01*
X34980Y663502D01*
X35325Y663450D01*
X35670Y663553D01*
X35938Y663760D01*
X36130Y664122D01*
X36168Y664535D01*
X36092Y664948D01*
X35900Y665207D01*
X35632Y665413D01*
X35363Y665465D01*
X35095Y665413D01*
X34750Y665207D01*
X34865Y666550D01*
X35900D01*
G01X38885Y663450D02*
Y666550D01*
X37467Y664328D01*
X39383D01*
G01X41525Y663450D02*
X41793Y663502D01*
X42100Y663657D01*
X42292Y663915D01*
X42368Y664277D01*
X42292Y664638D01*
X42062Y664948D01*
X41717Y665103D01*
X41333D01*
X41103Y665207D01*
X40912Y665465D01*
X40835Y665827D01*
X40950Y666188D01*
X41218Y666447D01*
X41525Y666550D01*
X41832Y666447D01*
X42100Y666188D01*
X42215Y665827D01*
X42138Y665465D01*
X41947Y665207D01*
X41717Y665103D01*
X41333D01*
X40988Y664948D01*
X40758Y664638D01*
X40682Y664277D01*
X40758Y663915D01*
X40950Y663657D01*
X41257Y663502D01*
X41525Y663450D01*
G01X31285Y660551D02*
X37485D01*
G01X61143Y-206664D02*
X58623Y-206247D01*
X56418Y-204581D01*
X54528Y-202081D01*
X53268Y-199164D01*
X52638Y-195831D01*
Y-192497D01*
X53268Y-189164D01*
X54528Y-186247D01*
X56418Y-183748D01*
X58623Y-182081D01*
X61143Y-181664D01*
X63663Y-182081D01*
X65868Y-183748D01*
X67758Y-186247D01*
X69018Y-189164D01*
X69648Y-192497D01*
Y-195831D01*
X69018Y-199164D01*
X67758Y-202081D01*
X65868Y-204581D01*
X63663Y-206247D01*
X61143Y-206664D01*
G01X63663Y-199997D02*
X67443Y-206664D01*
G01X80988Y-189998D02*
Y-201664D01*
X82248Y-204581D01*
X84138Y-206247D01*
X86343Y-206664D01*
X88548Y-206247D01*
X90438Y-204581D01*
X91698Y-201664D01*
G01Y-206664D02*
Y-189998D01*
G01X117213Y-206664D02*
Y-189998D01*
G01Y-192914D02*
X115953Y-191248D01*
X114063Y-190414D01*
X111858Y-189998D01*
X109653Y-190831D01*
X107763Y-192497D01*
X106503Y-194998D01*
X105873Y-198331D01*
X106503Y-201664D01*
X107763Y-204165D01*
X109653Y-205831D01*
X111858Y-206664D01*
X114063Y-206247D01*
X115953Y-204998D01*
X117213Y-203331D01*
G01X131388Y-206664D02*
Y-189998D01*
G01Y-194164D02*
X132648Y-192081D01*
X134538Y-190414D01*
X137058Y-189998D01*
X139263Y-190414D01*
X141153Y-192081D01*
X142098Y-194998D01*
Y-206664D01*
G01X161943Y-181664D02*
Y-206664D01*
G01X157533Y-189998D02*
X166353D01*
G01X192813Y-206664D02*
Y-189998D01*
G01Y-192914D02*
X191553Y-191248D01*
X189663Y-190414D01*
X187458Y-189998D01*
X185253Y-190831D01*
X183363Y-192497D01*
X182103Y-194998D01*
X181473Y-198331D01*
X182103Y-201664D01*
X183363Y-204165D01*
X185253Y-205831D01*
X187458Y-206664D01*
X189663Y-206247D01*
X191553Y-204998D01*
X192813Y-203331D01*
G01X39685Y7937D02*
Y11037D01*
X40644D01*
X40950Y10882D01*
X41142Y10675D01*
X41219Y10262D01*
X41142Y9849D01*
X40912Y9590D01*
X40644Y9435D01*
X39685D01*
G01X40644D02*
X41219Y7937D01*
G01X44012D02*
Y11037D01*
X42594Y8815D01*
X44510D01*
G01X46575Y7937D02*
X46652Y8609D01*
X46767Y9177D01*
X46920Y9694D01*
X47112Y10262D01*
X47419Y11037D01*
X45885D01*
G01X49024Y10520D02*
X49254Y10830D01*
X49522Y10985D01*
X49829Y11037D01*
X50212Y10934D01*
X50480Y10675D01*
X50557Y10365D01*
X50519Y10055D01*
X50365Y9797D01*
X49599Y9280D01*
X49254Y8919D01*
X49024Y8402D01*
X48947Y7937D01*
X50557D01*
G01X39685Y3900D02*
Y7000D01*
X40644D01*
X40950Y6845D01*
X41142Y6638D01*
X41219Y6225D01*
X41142Y5812D01*
X40912Y5553D01*
X40644Y5398D01*
X39685D01*
G01X40644D02*
X41219Y3900D01*
G01X44012D02*
Y7000D01*
X42594Y4778D01*
X44510D01*
G01X46575Y3900D02*
X46652Y4572D01*
X46767Y5140D01*
X46920Y5657D01*
X47112Y6225D01*
X47419Y7000D01*
X45885D01*
G01X49752Y3900D02*
Y7000D01*
X49292Y6380D01*
G01Y3900D02*
X50212D01*
G01X40680Y12988D02*
Y16188D01*
G01X46880Y12988D02*
X40680D01*
G01X46880Y16188D02*
Y12988D01*
G01X38741Y23620D02*
Y10020D01*
G01X40680Y16988D02*
Y20188D01*
G01X46880Y16988D02*
X40680D01*
G01Y20188D02*
X46880D01*
G01D02*
Y16988D01*
G01X40680Y16188D02*
X46880D01*
G01X49980Y40985D02*
Y24785D01*
G01X39199Y48824D02*
Y42624D01*
G01X43199Y48824D02*
Y42624D01*
G01D02*
X39999D01*
G01D02*
Y48824D01*
G01X47178D02*
Y42624D01*
G01D02*
X43978D01*
G01D02*
Y48824D01*
G01X51159D02*
Y42624D01*
G01X47959D02*
Y48824D01*
G01X51159Y42624D02*
X47959D01*
G01X51468Y51352D02*
X53051Y56352D01*
X54634Y51352D01*
G01X54064Y53102D02*
X52038D01*
G01X58151Y56352D02*
Y51352D01*
G01X56694Y56352D02*
X59608D01*
G01X63251D02*
Y51352D01*
G01X61794Y56352D02*
X64708D01*
G01X69618Y51352D02*
X67084D01*
Y56352D01*
X69618D01*
G01X68604Y53935D02*
X67084D01*
G01X71994Y51352D02*
Y56352D01*
X74908Y51352D01*
Y56352D01*
G01X78551D02*
Y51352D01*
G01X77094Y56352D02*
X80008D01*
G01X82891D02*
X84411D01*
G01X83651D02*
Y51352D01*
G01X82891D02*
X84411D01*
G01X88751D02*
X88244Y51435D01*
X87801Y51769D01*
X87421Y52269D01*
X87168Y52852D01*
X87041Y53519D01*
Y54185D01*
X87168Y54852D01*
X87421Y55435D01*
X87801Y55935D01*
X88244Y56269D01*
X88751Y56352D01*
X89258Y56269D01*
X89701Y55935D01*
X90081Y55435D01*
X90334Y54852D01*
X90461Y54185D01*
Y53519D01*
X90334Y52852D01*
X90081Y52269D01*
X89701Y51769D01*
X89258Y51435D01*
X88751Y51352D01*
G01X92394D02*
Y56352D01*
X95308Y51352D01*
Y56352D01*
G01X102784D02*
Y51352D01*
X105318D01*
G01X110418D02*
X107884D01*
Y56352D01*
X110418D01*
G01X109404Y53935D02*
X107884D01*
G01X112858Y51352D02*
Y56352D01*
X114124D01*
X114631Y56102D01*
X115011Y55769D01*
X115328Y55269D01*
X115581Y54685D01*
X115644Y53852D01*
X115581Y53019D01*
X115328Y52435D01*
X115011Y51935D01*
X114631Y51602D01*
X114124Y51352D01*
X112858D01*
G01X52545Y57509D02*
X122200D01*
Y50528D01*
X51048D01*
Y57509D01*
X52545D01*
G01X41374Y60105D02*
X41219Y59875D01*
X41116Y59607D01*
Y59300D01*
X41271Y58955D01*
X41529Y58687D01*
X41839Y58495D01*
X42356Y58342D01*
X42821Y58304D01*
X43286Y58380D01*
X43596Y58495D01*
X43906Y58725D01*
X44113Y58994D01*
X44216Y59262D01*
Y59530D01*
X44113Y59799D01*
X43958Y60029D01*
X43751Y60220D01*
G01Y61519D02*
X44009Y61749D01*
X44164Y62017D01*
X44216Y62362D01*
X44113Y62707D01*
X43906Y62975D01*
X43544Y63167D01*
X43131Y63205D01*
X42718Y63129D01*
X42459Y62937D01*
X42253Y62669D01*
X42201Y62400D01*
X42253Y62132D01*
X42459Y61787D01*
X41116Y61902D01*
Y62937D01*
G01X44216Y65922D02*
X41116D01*
X43338Y64504D01*
Y66420D01*
G01X44216Y69022D02*
X41116D01*
X43338Y67604D01*
Y69520D01*
G01X56581Y60918D02*
X53381D01*
G01D02*
Y67118D01*
G01X48581D02*
Y60918D01*
G01D02*
X45381D01*
G01D02*
Y67118D01*
G01X52581D02*
Y60918D01*
G01D02*
X49381D01*
G01D02*
Y67118D01*
G01X39999Y48824D02*
X43199D01*
G01X43978D02*
X47178D01*
G01X47959D02*
X51159D01*
G01X53481Y64018D02*
X56481D01*
G01X53381Y67118D02*
X56581D01*
G01X45381D02*
X48581D01*
G01X49381D02*
X52581D01*
G01X49539Y114488D02*
X49384Y114258D01*
X49281Y113990D01*
Y113683D01*
X49436Y113338D01*
X49694Y113070D01*
X50004Y112878D01*
X50521Y112725D01*
X50986Y112687D01*
X51451Y112763D01*
X51761Y112878D01*
X52071Y113108D01*
X52278Y113377D01*
X52381Y113645D01*
Y113913D01*
X52278Y114182D01*
X52123Y114412D01*
X51916Y114603D01*
G01Y115902D02*
X52174Y116132D01*
X52329Y116400D01*
X52381Y116745D01*
X52278Y117090D01*
X52071Y117358D01*
X51709Y117550D01*
X51296Y117588D01*
X50883Y117512D01*
X50624Y117320D01*
X50418Y117052D01*
X50366Y116783D01*
X50418Y116515D01*
X50624Y116170D01*
X49281Y116285D01*
Y117320D01*
G01X52381Y120305D02*
X49281D01*
X51503Y118887D01*
Y120803D01*
G01X51916Y122102D02*
X52174Y122332D01*
X52329Y122600D01*
X52381Y122945D01*
X52278Y123290D01*
X52071Y123558D01*
X51709Y123750D01*
X51296Y123788D01*
X50883Y123712D01*
X50624Y123520D01*
X50418Y123252D01*
X50366Y122983D01*
X50418Y122715D01*
X50624Y122370D01*
X49281Y122485D01*
Y123520D01*
G01X56203Y117521D02*
X53203D01*
G01X53103Y114421D02*
Y120621D01*
G01D02*
X56303D01*
G01Y114421D02*
X53103D01*
G01X44063Y113186D02*
X40963D01*
Y114145D01*
X41118Y114451D01*
X41325Y114643D01*
X41738Y114720D01*
X42151Y114643D01*
X42410Y114413D01*
X42565Y114145D01*
Y113186D01*
G01Y114145D02*
X44063Y114720D01*
G01X42771Y116325D02*
X42410Y116593D01*
X42203Y116823D01*
X42100Y117130D01*
X42203Y117398D01*
X42410Y117590D01*
X42720Y117743D01*
X43081Y117781D01*
X43391Y117743D01*
X43701Y117590D01*
X43960Y117360D01*
X44063Y117091D01*
X43960Y116785D01*
X43650Y116516D01*
X43185Y116363D01*
X42668Y116325D01*
X41996Y116401D01*
X41635Y116516D01*
X41273Y116708D01*
X41015Y116976D01*
X40963Y117245D01*
X41066Y117513D01*
X41325Y117705D01*
G01X43598Y119310D02*
X43856Y119540D01*
X44011Y119808D01*
X44063Y120153D01*
X43960Y120498D01*
X43753Y120766D01*
X43391Y120958D01*
X42978Y120996D01*
X42565Y120920D01*
X42306Y120728D01*
X42100Y120460D01*
X42048Y120191D01*
X42100Y119923D01*
X42306Y119578D01*
X40963Y119693D01*
Y120728D01*
G01X44063Y123713D02*
X40963D01*
X43185Y122295D01*
Y124211D01*
G01X45211Y114139D02*
Y120339D01*
G01D02*
X48411D01*
G01D02*
Y114139D01*
G01D02*
X45211D01*
G01X47048Y138977D02*
Y145493D01*
G01X53347D02*
Y156123D01*
G01X47048Y145493D02*
X53347D01*
G01X47048Y156123D02*
Y165659D01*
G01X53347Y156123D02*
X47048D01*
G01Y171444D02*
Y228568D01*
G01X50728Y186131D02*
X51038Y186323D01*
X51245Y186553D01*
X51348Y186821D01*
X51245Y187128D01*
X51038Y187358D01*
X50728Y187588D01*
X50315Y187665D01*
X48248D01*
G01X50986Y189346D02*
X51245Y189615D01*
X51348Y189921D01*
X51245Y190228D01*
X50935Y190496D01*
X50470Y190688D01*
X50005Y190765D01*
X49436D01*
X48971Y190688D01*
X48558Y190496D01*
X48351Y190266D01*
X48248Y189998D01*
X48351Y189691D01*
X48558Y189461D01*
X48868Y189308D01*
X49281Y189231D01*
X49643Y189308D01*
X50005Y189500D01*
X50211Y189730D01*
X50263Y189998D01*
X50160Y190305D01*
X49901Y190535D01*
X49436Y190765D01*
G01X48137Y179894D02*
X48405Y180255D01*
X48635Y180462D01*
X48942Y180565D01*
X49210Y180462D01*
X49402Y180255D01*
X49555Y179945D01*
X49593Y179584D01*
X49555Y179274D01*
X49402Y178964D01*
X49172Y178705D01*
X48903Y178602D01*
X48597Y178705D01*
X48328Y179015D01*
X48175Y179480D01*
X48137Y179997D01*
X48213Y180669D01*
X48328Y181030D01*
X48520Y181392D01*
X48788Y181650D01*
X49057Y181702D01*
X49325Y181599D01*
X49517Y181340D01*
G01X53532Y220263D02*
X53377Y220033D01*
X53274Y219765D01*
Y219458D01*
X53429Y219113D01*
X53687Y218845D01*
X53997Y218653D01*
X54514Y218500D01*
X54979Y218462D01*
X55444Y218538D01*
X55754Y218653D01*
X56064Y218883D01*
X56271Y219152D01*
X56374Y219420D01*
Y219688D01*
X56271Y219957D01*
X56116Y220187D01*
X55909Y220378D01*
G01Y221677D02*
X56167Y221907D01*
X56322Y222175D01*
X56374Y222520D01*
X56271Y222865D01*
X56064Y223133D01*
X55702Y223325D01*
X55289Y223363D01*
X54876Y223287D01*
X54617Y223095D01*
X54411Y222827D01*
X54359Y222558D01*
X54411Y222290D01*
X54617Y221945D01*
X53274Y222060D01*
Y223095D01*
G01Y225620D02*
X53377Y225313D01*
X53636Y225083D01*
X53946Y224930D01*
X54359Y224815D01*
X54824Y224777D01*
X55289Y224815D01*
X55702Y224930D01*
X56012Y225083D01*
X56271Y225313D01*
X56374Y225620D01*
X56271Y225927D01*
X56012Y226157D01*
X55702Y226310D01*
X55289Y226425D01*
X54824Y226463D01*
X54359Y226425D01*
X53946Y226310D01*
X53636Y226157D01*
X53377Y225927D01*
X53274Y225620D01*
G01X56374Y228643D02*
X55702Y228720D01*
X55134Y228835D01*
X54617Y228988D01*
X54049Y229180D01*
X53274Y229487D01*
Y227953D01*
G01X48494Y225363D02*
X48724Y225105D01*
X48992Y224950D01*
X49337Y224898D01*
X49682Y225001D01*
X49950Y225208D01*
X50142Y225570D01*
X50180Y225983D01*
X50104Y226396D01*
X49912Y226655D01*
X49644Y226861D01*
X49375Y226913D01*
X49107Y226861D01*
X48762Y226655D01*
X48877Y227998D01*
X49912D01*
G01X47048Y234333D02*
Y243879D01*
G01X53347D02*
Y254509D01*
G01X47048Y243879D02*
X53347D01*
G01X43397Y262507D02*
Y265607D01*
X42937Y264987D01*
G01Y262507D02*
X43857D01*
G01X45654Y262972D02*
X45884Y262714D01*
X46152Y262559D01*
X46497Y262507D01*
X46842Y262610D01*
X47110Y262817D01*
X47302Y263179D01*
X47340Y263592D01*
X47264Y264005D01*
X47072Y264264D01*
X46804Y264470D01*
X46535Y264522D01*
X46267Y264470D01*
X45922Y264264D01*
X46037Y265607D01*
X47072D01*
G01X47048Y254509D02*
Y261024D01*
G01X53347Y254509D02*
X47048D01*
G01X50033Y262588D02*
X49803Y262743D01*
X49535Y262846D01*
X49228D01*
X48883Y262691D01*
X48615Y262433D01*
X48423Y262123D01*
X48270Y261606D01*
X48232Y261141D01*
X48308Y260676D01*
X48423Y260366D01*
X48653Y260056D01*
X48922Y259849D01*
X49190Y259746D01*
X49458D01*
X49727Y259849D01*
X49957Y260004D01*
X50148Y260211D01*
G01X51447D02*
X51677Y259953D01*
X51945Y259798D01*
X52290Y259746D01*
X52635Y259849D01*
X52903Y260056D01*
X53095Y260418D01*
X53133Y260831D01*
X53057Y261244D01*
X52865Y261503D01*
X52597Y261709D01*
X52328Y261761D01*
X52060Y261709D01*
X51715Y261503D01*
X51830Y262846D01*
X52865D01*
G01X55390D02*
X55083Y262743D01*
X54853Y262484D01*
X54700Y262174D01*
X54585Y261761D01*
X54547Y261296D01*
X54585Y260831D01*
X54700Y260418D01*
X54853Y260108D01*
X55083Y259849D01*
X55390Y259746D01*
X55697Y259849D01*
X55927Y260108D01*
X56080Y260418D01*
X56195Y260831D01*
X56233Y261296D01*
X56195Y261761D01*
X56080Y262174D01*
X55927Y262484D01*
X55697Y262743D01*
X55390Y262846D01*
G01X58490Y259746D02*
X58758Y259798D01*
X59065Y259953D01*
X59257Y260211D01*
X59333Y260573D01*
X59257Y260934D01*
X59027Y261244D01*
X58682Y261399D01*
X58298D01*
X58068Y261503D01*
X57877Y261761D01*
X57800Y262123D01*
X57915Y262484D01*
X58183Y262743D01*
X58490Y262846D01*
X58797Y262743D01*
X59065Y262484D01*
X59180Y262123D01*
X59103Y261761D01*
X58912Y261503D01*
X58682Y261399D01*
X58298D01*
X57953Y261244D01*
X57723Y260934D01*
X57647Y260573D01*
X57723Y260211D01*
X57915Y259953D01*
X58222Y259798D01*
X58490Y259746D01*
G01X50755Y293460D02*
X52791D01*
G01X56802Y356622D02*
X50119D01*
Y356643D01*
X52312Y358836D01*
X52333Y358815D01*
Y353987D01*
X50098Y356222D01*
Y356559D01*
G01X43763Y350731D02*
X43955Y350421D01*
X44185Y350214D01*
X44453Y350111D01*
X44760Y350214D01*
X44990Y350421D01*
X45220Y350731D01*
X45297Y351144D01*
Y353211D01*
G01X47630Y350111D02*
Y353211D01*
X47170Y352591D01*
G01Y350111D02*
X48090D01*
G01X50078Y350473D02*
X50347Y350214D01*
X50653Y350111D01*
X50960Y350214D01*
X51228Y350524D01*
X51420Y350989D01*
X51497Y351454D01*
Y352023D01*
X51420Y352488D01*
X51228Y352901D01*
X50998Y353108D01*
X50730Y353211D01*
X50423Y353108D01*
X50193Y352901D01*
X50040Y352591D01*
X49963Y352178D01*
X50040Y351816D01*
X50232Y351454D01*
X50462Y351248D01*
X50730Y351196D01*
X51037Y351299D01*
X51267Y351558D01*
X51497Y352023D01*
G01X49579Y370584D02*
X38979D01*
G01X49579Y395984D02*
Y370584D01*
G01X38979D02*
Y395984D01*
G01X43024Y396683D02*
X39924D01*
Y397642D01*
X40079Y397948D01*
X40286Y398140D01*
X40699Y398217D01*
X41112Y398140D01*
X41371Y397910D01*
X41526Y397642D01*
Y396683D01*
G01Y397642D02*
X43024Y398217D01*
G01Y400550D02*
X39924D01*
X40544Y400090D01*
G01X43024D02*
Y401010D01*
G01X39924Y403650D02*
X40027Y403343D01*
X40286Y403113D01*
X40596Y402960D01*
X41009Y402845D01*
X41474Y402807D01*
X41939Y402845D01*
X42352Y402960D01*
X42662Y403113D01*
X42921Y403343D01*
X43024Y403650D01*
X42921Y403957D01*
X42662Y404187D01*
X42352Y404340D01*
X41939Y404455D01*
X41474Y404493D01*
X41009Y404455D01*
X40596Y404340D01*
X40286Y404187D01*
X40027Y403957D01*
X39924Y403650D01*
G01X43024Y406673D02*
X42352Y406750D01*
X41784Y406865D01*
X41267Y407018D01*
X40699Y407210D01*
X39924Y407517D01*
Y405983D01*
G01X43024Y409850D02*
X39924D01*
X40544Y409390D01*
G01X43024D02*
Y410310D01*
G01X38979Y395984D02*
X49579D01*
G01X42042Y413772D02*
Y431488D01*
G01X77738Y413772D02*
X42042D01*
G01Y431488D02*
X77738D01*
G01X42042Y432588D02*
Y450304D01*
G01X77738Y432588D02*
X42042D01*
G01X43903Y451307D02*
Y454407D01*
X44823D01*
X45130Y454252D01*
X45360Y453890D01*
X45437Y453477D01*
X45360Y453064D01*
X45168Y452754D01*
X44823Y452599D01*
X43903D01*
G01X48613Y454149D02*
X48383Y454304D01*
X48115Y454407D01*
X47808D01*
X47463Y454252D01*
X47195Y453994D01*
X47003Y453684D01*
X46850Y453167D01*
X46812Y452702D01*
X46888Y452237D01*
X47003Y451927D01*
X47233Y451617D01*
X47502Y451410D01*
X47770Y451307D01*
X48038D01*
X48307Y451410D01*
X48537Y451565D01*
X48728Y451772D01*
G01X50142Y452599D02*
X50410Y452960D01*
X50640Y453167D01*
X50947Y453270D01*
X51215Y453167D01*
X51407Y452960D01*
X51560Y452650D01*
X51598Y452289D01*
X51560Y451979D01*
X51407Y451669D01*
X51177Y451410D01*
X50908Y451307D01*
X50602Y451410D01*
X50333Y451720D01*
X50180Y452185D01*
X50142Y452702D01*
X50218Y453374D01*
X50333Y453735D01*
X50525Y454097D01*
X50793Y454355D01*
X51062Y454407D01*
X51330Y454304D01*
X51522Y454045D01*
G01X54430Y451307D02*
Y454407D01*
X53012Y452185D01*
X54928D01*
G01X42042Y450304D02*
X77738D01*
G01X42320Y468285D02*
Y475685D01*
G01X59720Y468285D02*
X42320D01*
G01X51346Y492256D02*
Y484856D01*
G01X42646D02*
Y492256D01*
G01X60046Y484856D02*
X42646D01*
G01X51130Y483933D02*
Y476533D01*
G01X42430D02*
Y483933D01*
G01X59830Y476533D02*
X42430D01*
G01Y483933D02*
X59830D01*
G01X42320Y475685D02*
X59720D01*
G01X48292Y492970D02*
Y496170D01*
G01X54492Y492970D02*
X48292D01*
G01X51392Y493070D02*
Y496070D01*
G01X48292Y496170D02*
X54492D01*
G01X49195Y498540D02*
Y503140D01*
G01X59395Y498540D02*
X49195D01*
G01X42646Y492256D02*
X60046D01*
G01X53404Y514998D02*
X53564Y514790D01*
X53751Y514665D01*
X53991Y514623D01*
X54231Y514706D01*
X54418Y514873D01*
X54551Y515165D01*
X54578Y515498D01*
X54524Y515831D01*
X54391Y516040D01*
X54204Y516206D01*
X54018Y516248D01*
X53831Y516206D01*
X53591Y516040D01*
X53671Y517123D01*
X54391D01*
G01X49195Y503140D02*
X59395D01*
G01X52850Y519672D02*
Y516472D01*
G01X46650D02*
Y519672D01*
G01X52850Y516472D02*
X46650D01*
G01X48055Y504525D02*
X44955D01*
Y505445D01*
X45110Y505752D01*
X45472Y505982D01*
X45885Y506059D01*
X46298Y505982D01*
X46608Y505790D01*
X46763Y505445D01*
Y504525D01*
G01X48055Y507625D02*
X44955D01*
Y508584D01*
X45110Y508890D01*
X45317Y509082D01*
X45730Y509159D01*
X46143Y509082D01*
X46402Y508852D01*
X46557Y508584D01*
Y507625D01*
G01Y508584D02*
X48055Y509159D01*
G01X45472Y510764D02*
X45162Y510994D01*
X45007Y511262D01*
X44955Y511569D01*
X45058Y511952D01*
X45317Y512220D01*
X45627Y512297D01*
X45937Y512259D01*
X46195Y512105D01*
X46712Y511339D01*
X47073Y510994D01*
X47590Y510764D01*
X48055Y510687D01*
Y512297D01*
G01Y514592D02*
X48003Y514860D01*
X47848Y515167D01*
X47590Y515359D01*
X47228Y515435D01*
X46867Y515359D01*
X46557Y515129D01*
X46402Y514784D01*
Y514400D01*
X46298Y514170D01*
X46040Y513979D01*
X45678Y513902D01*
X45317Y514017D01*
X45058Y514285D01*
X44955Y514592D01*
X45058Y514899D01*
X45317Y515167D01*
X45678Y515282D01*
X46040Y515205D01*
X46298Y515014D01*
X46402Y514784D01*
Y514400D01*
X46557Y514055D01*
X46867Y513825D01*
X47228Y513749D01*
X47590Y513825D01*
X47848Y514017D01*
X48003Y514324D01*
X48055Y514592D01*
G01X52506Y509184D02*
X49306D01*
G01X52506Y515384D02*
Y509184D01*
G01X49306D02*
Y515384D01*
G01D02*
X52506D01*
G01X48322Y522917D02*
X45222D01*
Y523837D01*
X45377Y524144D01*
X45739Y524374D01*
X46152Y524451D01*
X46565Y524374D01*
X46875Y524182D01*
X47030Y523837D01*
Y522917D01*
G01X45480Y527627D02*
X45325Y527397D01*
X45222Y527129D01*
Y526822D01*
X45377Y526477D01*
X45635Y526209D01*
X45945Y526017D01*
X46462Y525864D01*
X46927Y525826D01*
X47392Y525902D01*
X47702Y526017D01*
X48012Y526247D01*
X48219Y526516D01*
X48322Y526784D01*
Y527052D01*
X48219Y527321D01*
X48064Y527551D01*
X47857Y527742D01*
G01X47030Y529156D02*
X46669Y529424D01*
X46462Y529654D01*
X46359Y529961D01*
X46462Y530229D01*
X46669Y530421D01*
X46979Y530574D01*
X47340Y530612D01*
X47650Y530574D01*
X47960Y530421D01*
X48219Y530191D01*
X48322Y529922D01*
X48219Y529616D01*
X47909Y529347D01*
X47444Y529194D01*
X46927Y529156D01*
X46255Y529232D01*
X45894Y529347D01*
X45532Y529539D01*
X45274Y529807D01*
X45222Y530076D01*
X45325Y530344D01*
X45584Y530536D01*
G01X47960Y532332D02*
X48219Y532601D01*
X48322Y532907D01*
X48219Y533214D01*
X47909Y533482D01*
X47444Y533674D01*
X46979Y533751D01*
X46410D01*
X45945Y533674D01*
X45532Y533482D01*
X45325Y533252D01*
X45222Y532984D01*
X45325Y532677D01*
X45532Y532447D01*
X45842Y532294D01*
X46255Y532217D01*
X46617Y532294D01*
X46979Y532486D01*
X47185Y532716D01*
X47237Y532984D01*
X47134Y533291D01*
X46875Y533521D01*
X46410Y533751D01*
G01X53751Y527582D02*
X56951D01*
G01Y521382D02*
X53751D01*
G01D02*
Y527582D01*
G01X56851Y524482D02*
X53851D01*
G01X44385Y522878D02*
X41285D01*
Y523798D01*
X41440Y524105D01*
X41802Y524335D01*
X42215Y524412D01*
X42628Y524335D01*
X42938Y524143D01*
X43093Y523798D01*
Y522878D01*
G01X44385Y525978D02*
X41285D01*
Y526937D01*
X41440Y527243D01*
X41647Y527435D01*
X42060Y527512D01*
X42473Y527435D01*
X42732Y527205D01*
X42887Y526937D01*
Y525978D01*
G01Y526937D02*
X44385Y527512D01*
G01X41802Y529117D02*
X41492Y529347D01*
X41337Y529615D01*
X41285Y529922D01*
X41388Y530305D01*
X41647Y530573D01*
X41957Y530650D01*
X42267Y530612D01*
X42525Y530458D01*
X43042Y529692D01*
X43403Y529347D01*
X43920Y529117D01*
X44385Y529040D01*
Y530650D01*
G01X44023Y532293D02*
X44282Y532562D01*
X44385Y532868D01*
X44282Y533175D01*
X43972Y533443D01*
X43507Y533635D01*
X43042Y533712D01*
X42473D01*
X42008Y533635D01*
X41595Y533443D01*
X41388Y533213D01*
X41285Y532945D01*
X41388Y532638D01*
X41595Y532408D01*
X41905Y532255D01*
X42318Y532178D01*
X42680Y532255D01*
X43042Y532447D01*
X43248Y532677D01*
X43300Y532945D01*
X43197Y533252D01*
X42938Y533482D01*
X42473Y533712D01*
G01X52937Y527585D02*
Y521385D01*
G01X49737Y527585D02*
X52937D01*
G01X49737Y521385D02*
Y527585D01*
G01X52937Y521385D02*
X49737D01*
G01X46650Y519672D02*
X52850D01*
G01X44640Y545749D02*
X47640D01*
G01X44540Y548849D02*
X47740D01*
G01X44540Y542649D02*
Y548849D01*
G01X47740Y542649D02*
X44540D01*
G01X47740Y548849D02*
Y542649D01*
G01X51640Y545749D02*
X48640D01*
G01X51740Y542649D02*
X48540D01*
G01X51740Y548849D02*
Y542649D01*
G01X48540Y548849D02*
X51740D01*
G01X48540Y542649D02*
Y548849D01*
G01X40382Y545534D02*
Y548534D01*
G01X43482Y548634D02*
Y545434D01*
G01X48692Y570423D02*
Y564823D01*
G01X54743Y564029D02*
X54513Y564184D01*
X54245Y564287D01*
X53938D01*
X53593Y564132D01*
X53325Y563874D01*
X53133Y563564D01*
X52980Y563047D01*
X52942Y562582D01*
X53018Y562117D01*
X53133Y561807D01*
X53363Y561497D01*
X53632Y561290D01*
X53900Y561187D01*
X54168D01*
X54437Y561290D01*
X54667Y561445D01*
X54858Y561652D01*
G01X57460Y561187D02*
Y564287D01*
X56042Y562065D01*
X57958D01*
G01X60100Y561187D02*
Y564287D01*
X59640Y563667D01*
G01Y561187D02*
X60560D01*
G01X63660D02*
Y564287D01*
X62242Y562065D01*
X64158D01*
G01X47392Y578723D02*
G02I-1000J0D01*
G01X46392Y572723D02*
X48692Y570423D01*
G01Y575023D02*
X46392Y572723D01*
G01X48692Y580623D02*
Y575023D01*
G01X53173Y577709D02*
X52943Y577864D01*
X52675Y577967D01*
X52368D01*
X52023Y577812D01*
X51755Y577554D01*
X51563Y577244D01*
X51410Y576727D01*
X51372Y576262D01*
X51448Y575797D01*
X51563Y575487D01*
X51793Y575177D01*
X52062Y574970D01*
X52330Y574867D01*
X52598D01*
X52867Y574970D01*
X53097Y575125D01*
X53288Y575332D01*
G01X55890Y574867D02*
Y577967D01*
X54472Y575745D01*
X56388D01*
G01X58530Y574867D02*
Y577967D01*
X58070Y577347D01*
G01Y574867D02*
X58990D01*
G01X60787Y575487D02*
X61017Y575125D01*
X61323Y574919D01*
X61668Y574867D01*
X61975Y574919D01*
X62282Y575177D01*
X62473Y575487D01*
X62512Y575797D01*
X62435Y576159D01*
X62167Y576417D01*
X61898Y576520D01*
X61553D01*
G01X61898D02*
X62128Y576675D01*
X62320Y576934D01*
X62397Y577244D01*
X62320Y577554D01*
X62128Y577812D01*
X61783Y577967D01*
X61438Y577915D01*
X61093Y577709D01*
G01X54093Y570179D02*
X53863Y570334D01*
X53595Y570437D01*
X53288D01*
X52943Y570282D01*
X52675Y570024D01*
X52483Y569714D01*
X52330Y569197D01*
X52292Y568732D01*
X52368Y568267D01*
X52483Y567957D01*
X52713Y567647D01*
X52982Y567440D01*
X53250Y567337D01*
X53518D01*
X53787Y567440D01*
X54017Y567595D01*
X54208Y567802D01*
G01X56810Y567337D02*
Y570437D01*
X55392Y568215D01*
X57308D01*
G01X59450Y567337D02*
Y570437D01*
X58990Y569817D01*
G01Y567337D02*
X59910D01*
G01X61707Y567802D02*
X61937Y567544D01*
X62205Y567389D01*
X62550Y567337D01*
X62895Y567440D01*
X63163Y567647D01*
X63355Y568009D01*
X63393Y568422D01*
X63317Y568835D01*
X63125Y569094D01*
X62857Y569300D01*
X62588Y569352D01*
X62320Y569300D01*
X61975Y569094D01*
X62090Y570437D01*
X63125D01*
G01X46082Y595785D02*
Y598785D01*
G01X42982Y595685D02*
Y598885D01*
G01X49182Y595685D02*
X42982D01*
G01X49182Y598885D02*
Y595685D01*
G01X52073Y589823D02*
X51918Y589593D01*
X51815Y589325D01*
Y589018D01*
X51970Y588673D01*
X52228Y588405D01*
X52538Y588213D01*
X53055Y588060D01*
X53520Y588022D01*
X53985Y588098D01*
X54295Y588213D01*
X54605Y588443D01*
X54812Y588712D01*
X54915Y588980D01*
Y589248D01*
X54812Y589517D01*
X54657Y589747D01*
X54450Y589938D01*
G01Y591237D02*
X54708Y591467D01*
X54863Y591735D01*
X54915Y592080D01*
X54812Y592425D01*
X54605Y592693D01*
X54243Y592885D01*
X53830Y592923D01*
X53417Y592847D01*
X53158Y592655D01*
X52952Y592387D01*
X52900Y592118D01*
X52952Y591850D01*
X53158Y591505D01*
X51815Y591620D01*
Y592655D01*
G01X54450Y594337D02*
X54708Y594567D01*
X54863Y594835D01*
X54915Y595180D01*
X54812Y595525D01*
X54605Y595793D01*
X54243Y595985D01*
X53830Y596023D01*
X53417Y595947D01*
X53158Y595755D01*
X52952Y595487D01*
X52900Y595218D01*
X52952Y594950D01*
X53158Y594605D01*
X51815Y594720D01*
Y595755D01*
G01X54295Y597437D02*
X54657Y597667D01*
X54863Y597973D01*
X54915Y598318D01*
X54863Y598625D01*
X54605Y598932D01*
X54295Y599123D01*
X53985Y599162D01*
X53623Y599085D01*
X53365Y598817D01*
X53262Y598548D01*
Y598203D01*
G01Y598548D02*
X53107Y598778D01*
X52848Y598970D01*
X52538Y599047D01*
X52228Y598970D01*
X51970Y598778D01*
X51815Y598433D01*
X51867Y598088D01*
X52073Y597743D01*
G01X38772Y598785D02*
Y595785D01*
G01X41872Y598885D02*
Y595685D01*
G01X50890Y602010D02*
Y603520D01*
G01X59470Y602010D02*
X50890D01*
G01X42982Y598885D02*
X49182D01*
G01X38512Y606625D02*
Y609625D01*
G01X41612Y609725D02*
Y606525D01*
G01X42770Y606840D02*
X45770D01*
G01X42670Y609940D02*
X45870D01*
G01X42670Y603740D02*
Y609940D01*
G01X45870Y603740D02*
X42670D01*
G01X45870Y609940D02*
Y603740D01*
G01X49770Y606840D02*
X46770D01*
G01X49870Y603740D02*
X46670D01*
G01X49870Y609940D02*
Y603740D01*
G01X46670Y609940D02*
X49870D01*
G01X46670Y603740D02*
Y609940D01*
G01X50540Y608863D02*
Y611963D01*
X51499D01*
X51805Y611808D01*
X51997Y611601D01*
X52074Y611188D01*
X51997Y610775D01*
X51767Y610516D01*
X51499Y610361D01*
X50540D01*
G01X51499D02*
X52074Y608863D01*
G01X54407D02*
Y611963D01*
X53947Y611343D01*
G01Y608863D02*
X54867D01*
G01X56779Y611446D02*
X57009Y611756D01*
X57277Y611911D01*
X57584Y611963D01*
X57967Y611860D01*
X58235Y611601D01*
X58312Y611291D01*
X58274Y610981D01*
X58120Y610723D01*
X57354Y610206D01*
X57009Y609845D01*
X56779Y609328D01*
X56702Y608863D01*
X58312D01*
G01X60530D02*
X60607Y609535D01*
X60722Y610103D01*
X60875Y610620D01*
X61067Y611188D01*
X61374Y611963D01*
X59840D01*
G01X64167Y608863D02*
Y611963D01*
X62749Y609741D01*
X64665D01*
G01X50540Y604681D02*
Y607781D01*
X51499D01*
X51805Y607626D01*
X51997Y607419D01*
X52074Y607006D01*
X51997Y606593D01*
X51767Y606334D01*
X51499Y606179D01*
X50540D01*
G01X51499D02*
X52074Y604681D01*
G01X54407D02*
Y607781D01*
X53947Y607161D01*
G01Y604681D02*
X54867D01*
G01X56779Y607264D02*
X57009Y607574D01*
X57277Y607729D01*
X57584Y607781D01*
X57967Y607678D01*
X58235Y607419D01*
X58312Y607109D01*
X58274Y606799D01*
X58120Y606541D01*
X57354Y606024D01*
X57009Y605663D01*
X56779Y605146D01*
X56702Y604681D01*
X58312D01*
G01X60530D02*
X60607Y605353D01*
X60722Y605921D01*
X60875Y606438D01*
X61067Y607006D01*
X61374Y607781D01*
X59840D01*
G01X62864Y605301D02*
X63094Y604939D01*
X63400Y604733D01*
X63745Y604681D01*
X64052Y604733D01*
X64359Y604991D01*
X64550Y605301D01*
X64589Y605611D01*
X64512Y605973D01*
X64244Y606231D01*
X63975Y606334D01*
X63630D01*
G01X63975D02*
X64205Y606489D01*
X64397Y606748D01*
X64474Y607058D01*
X64397Y607368D01*
X64205Y607626D01*
X63860Y607781D01*
X63515Y607729D01*
X63170Y607523D01*
G01X51556Y622832D02*
Y640232D01*
G01X58956Y622832D02*
X51556D01*
G01X46205Y632114D02*
Y626514D01*
G01X53433Y621007D02*
X59633D01*
G01X53433Y617807D02*
Y621007D01*
G01X59633Y617807D02*
X53433D01*
G01Y616507D02*
X59633D01*
G01X53433Y613307D02*
Y616507D01*
G01X59633Y613307D02*
X53433D01*
G01X51556Y640232D02*
X58956D01*
G01Y631532D02*
X51556D01*
G01X44905Y640414D02*
G02I-1000J0D01*
G01X43905Y634414D02*
X46205Y632114D01*
G01Y636714D02*
X43905Y634414D01*
G01X46205Y642314D02*
Y636714D01*
G01X52226Y642328D02*
Y645528D01*
G01X58426Y642328D02*
X52226D01*
G01X41892Y657451D02*
Y660451D01*
G01X38792Y657351D02*
Y660551D01*
G01X44992Y657351D02*
X38792D01*
G01X44992Y660551D02*
Y657351D01*
G01X48757Y655797D02*
Y658897D01*
X49716D01*
X50022Y658742D01*
X50214Y658535D01*
X50291Y658122D01*
X50214Y657709D01*
X49984Y657450D01*
X49716Y657295D01*
X48757D01*
G01X49716D02*
X50291Y655797D01*
G01X52624D02*
Y658897D01*
X52164Y658277D01*
G01Y655797D02*
X53084D01*
G01X54996Y658380D02*
X55226Y658690D01*
X55494Y658845D01*
X55801Y658897D01*
X56184Y658794D01*
X56452Y658535D01*
X56529Y658225D01*
X56491Y657915D01*
X56337Y657657D01*
X55571Y657140D01*
X55226Y656779D01*
X54996Y656262D01*
X54919Y655797D01*
X56529D01*
G01X58747D02*
X58824Y656469D01*
X58939Y657037D01*
X59092Y657554D01*
X59284Y658122D01*
X59591Y658897D01*
X58057D01*
G01X61196Y657089D02*
X61464Y657450D01*
X61694Y657657D01*
X62001Y657760D01*
X62269Y657657D01*
X62461Y657450D01*
X62614Y657140D01*
X62652Y656779D01*
X62614Y656469D01*
X62461Y656159D01*
X62231Y655900D01*
X61962Y655797D01*
X61656Y655900D01*
X61387Y656210D01*
X61234Y656675D01*
X61196Y657192D01*
X61272Y657864D01*
X61387Y658225D01*
X61579Y658587D01*
X61847Y658845D01*
X62116Y658897D01*
X62384Y658794D01*
X62576Y658535D01*
G01X52226Y650028D02*
X58426D01*
G01X52226Y646828D02*
Y650028D01*
G01X58426Y646828D02*
X52226D01*
G01X48677Y651533D02*
Y654633D01*
X49636D01*
X49942Y654478D01*
X50134Y654271D01*
X50211Y653858D01*
X50134Y653445D01*
X49904Y653186D01*
X49636Y653031D01*
X48677D01*
G01X49636D02*
X50211Y651533D01*
G01X52544D02*
Y654633D01*
X52084Y654013D01*
G01Y651533D02*
X53004D01*
G01X54916Y654116D02*
X55146Y654426D01*
X55414Y654581D01*
X55721Y654633D01*
X56104Y654530D01*
X56372Y654271D01*
X56449Y653961D01*
X56411Y653651D01*
X56257Y653393D01*
X55491Y652876D01*
X55146Y652515D01*
X54916Y651998D01*
X54839Y651533D01*
X56449D01*
G01X58667D02*
X58744Y652205D01*
X58859Y652773D01*
X59012Y653290D01*
X59204Y653858D01*
X59511Y654633D01*
X57977D01*
G01X61001Y651998D02*
X61231Y651740D01*
X61499Y651585D01*
X61844Y651533D01*
X62189Y651636D01*
X62457Y651843D01*
X62649Y652205D01*
X62687Y652618D01*
X62611Y653031D01*
X62419Y653290D01*
X62151Y653496D01*
X61882Y653548D01*
X61614Y653496D01*
X61269Y653290D01*
X61384Y654633D01*
X62419D01*
G01X52226Y645528D02*
X58426D01*
G01X45735Y666207D02*
X45505Y666362D01*
X45237Y666465D01*
X44930D01*
X44585Y666310D01*
X44317Y666052D01*
X44125Y665742D01*
X43972Y665225D01*
X43934Y664760D01*
X44010Y664295D01*
X44125Y663985D01*
X44355Y663675D01*
X44624Y663468D01*
X44892Y663365D01*
X45160D01*
X45429Y663468D01*
X45659Y663623D01*
X45850Y663830D01*
G01X47149D02*
X47379Y663572D01*
X47647Y663417D01*
X47992Y663365D01*
X48337Y663468D01*
X48605Y663675D01*
X48797Y664037D01*
X48835Y664450D01*
X48759Y664863D01*
X48567Y665122D01*
X48299Y665328D01*
X48030Y665380D01*
X47762Y665328D01*
X47417Y665122D01*
X47532Y666465D01*
X48567D01*
G01X51552Y663365D02*
Y666465D01*
X50134Y664243D01*
X52050D01*
G01X53464Y665948D02*
X53694Y666258D01*
X53962Y666413D01*
X54269Y666465D01*
X54652Y666362D01*
X54920Y666103D01*
X54997Y665793D01*
X54959Y665483D01*
X54805Y665225D01*
X54039Y664708D01*
X53694Y664347D01*
X53464Y663830D01*
X53387Y663365D01*
X54997D01*
G01X38792Y660551D02*
X44992D01*
G01X51673Y777567D02*
X51780Y777692D01*
X51860Y777901D01*
X51913Y778192D01*
X51860Y778442D01*
X51753Y778609D01*
X51567Y778734D01*
X50847D01*
Y776234D01*
X51727D01*
X51913Y776401D01*
X52020Y776651D01*
X52073Y776942D01*
X52020Y777234D01*
X51860Y777484D01*
X51673Y777567D01*
X50847D01*
G01X53660Y776234D02*
X53847Y776276D01*
X54060Y776401D01*
X54193Y776609D01*
X54247Y776901D01*
X54193Y777192D01*
X54033Y777442D01*
X53793Y777567D01*
X53527D01*
X53367Y777651D01*
X53233Y777859D01*
X53180Y778151D01*
X53260Y778442D01*
X53447Y778651D01*
X53660Y778734D01*
X53873Y778651D01*
X54060Y778442D01*
X54140Y778151D01*
X54087Y777859D01*
X53953Y777651D01*
X53793Y777567D01*
X53527D01*
X53287Y777442D01*
X53127Y777192D01*
X53073Y776901D01*
X53127Y776609D01*
X53260Y776401D01*
X53473Y776276D01*
X53660Y776234D01*
G01X55353Y778317D02*
X55513Y778567D01*
X55700Y778692D01*
X55913Y778734D01*
X56180Y778651D01*
X56367Y778442D01*
X56420Y778192D01*
X56393Y777942D01*
X56287Y777734D01*
X55753Y777317D01*
X55513Y777026D01*
X55353Y776609D01*
X55300Y776234D01*
X56420D01*
G01X380571Y782281D02*
X48681D01*
G01Y819152D02*
Y788581D01*
G01X51181Y821652D02*
X48681Y819152D01*
G01X326378Y821652D02*
X51181D01*
G01X68898Y236D02*
Y-9607D01*
G01D02*
G03X88582I9842J0D01*
G01X65189Y13443D02*
X62089D01*
Y14209D01*
X62244Y14516D01*
X62451Y14746D01*
X62761Y14938D01*
X63122Y15091D01*
X63639Y15129D01*
X64156Y15091D01*
X64517Y14938D01*
X64827Y14746D01*
X65034Y14516D01*
X65189Y14209D01*
Y13443D01*
G01Y17386D02*
X62089D01*
X62709Y16926D01*
G01X65189D02*
Y17846D01*
G01Y20486D02*
X65137Y20754D01*
X64982Y21061D01*
X64724Y21253D01*
X64362Y21329D01*
X64001Y21253D01*
X63691Y21023D01*
X63536Y20678D01*
Y20294D01*
X63432Y20064D01*
X63174Y19873D01*
X62812Y19796D01*
X62451Y19911D01*
X62192Y20179D01*
X62089Y20486D01*
X62192Y20793D01*
X62451Y21061D01*
X62812Y21176D01*
X63174Y21099D01*
X63432Y20908D01*
X63536Y20678D01*
Y20294D01*
X63691Y19949D01*
X64001Y19719D01*
X64362Y19643D01*
X64724Y19719D01*
X64982Y19911D01*
X65137Y20218D01*
X65189Y20486D01*
G01X66496Y236D02*
X68898D01*
G01X66496Y27508D02*
Y236D01*
G01X64998Y27828D02*
Y30928D01*
X64538Y30308D01*
G01Y27828D02*
X65458D01*
G01X66496Y36220D02*
Y26008D01*
G01X67618Y46013D02*
Y39330D01*
X67597D01*
X65404Y41523D01*
X65425Y41544D01*
X70253D01*
X68018Y39309D01*
X67681D01*
G01X90984Y36220D02*
X66496D01*
G01X68581Y67118D02*
Y60918D01*
G01D02*
X65381D01*
G01D02*
Y67118D01*
G01X61381Y60918D02*
Y67118D01*
G01X64581D02*
Y60918D01*
G01D02*
X61381D01*
G01X56581Y67118D02*
Y60918D01*
G01X65481Y64018D02*
X68481D01*
G01X65381Y67118D02*
X68581D01*
G01X64481Y64018D02*
X61481D01*
G01X61381Y67118D02*
X64581D01*
G01X67383Y93340D02*
X65083Y91040D01*
G01D02*
X67383Y88740D01*
G01D02*
Y83140D01*
G01X66083Y97040D02*
G02I-1000J0D01*
G01X67383Y98940D02*
Y93340D01*
G01X58273Y110829D02*
X58043Y110984D01*
X57775Y111087D01*
X57468D01*
X57123Y110932D01*
X56855Y110674D01*
X56663Y110364D01*
X56510Y109847D01*
X56472Y109382D01*
X56548Y108917D01*
X56663Y108607D01*
X56893Y108297D01*
X57162Y108090D01*
X57430Y107987D01*
X57698D01*
X57967Y108090D01*
X58197Y108245D01*
X58388Y108452D01*
G01X59687D02*
X59917Y108194D01*
X60185Y108039D01*
X60530Y107987D01*
X60875Y108090D01*
X61143Y108297D01*
X61335Y108659D01*
X61373Y109072D01*
X61297Y109485D01*
X61105Y109744D01*
X60837Y109950D01*
X60568Y110002D01*
X60300Y109950D01*
X59955Y109744D01*
X60070Y111087D01*
X61105D01*
G01X64090Y107987D02*
Y111087D01*
X62672Y108865D01*
X64588D01*
G01X66653Y107987D02*
X66730Y108659D01*
X66845Y109227D01*
X66998Y109744D01*
X67190Y110312D01*
X67497Y111087D01*
X65963D01*
G01X56303Y120621D02*
Y114421D01*
G01X60229Y113658D02*
Y116658D01*
G01X63329Y116758D02*
Y113558D01*
G01X57129Y116758D02*
X63329D01*
G01Y113558D02*
X57129D01*
G01D02*
Y116758D01*
G01X54430Y124790D02*
X71440D01*
Y136310D01*
G01X54560Y185780D02*
Y124790D01*
G01X55743Y137964D02*
X55588Y137734D01*
X55485Y137466D01*
Y137159D01*
X55640Y136814D01*
X55898Y136546D01*
X56208Y136354D01*
X56725Y136201D01*
X57190Y136163D01*
X57655Y136239D01*
X57965Y136354D01*
X58275Y136584D01*
X58482Y136853D01*
X58585Y137121D01*
Y137389D01*
X58482Y137658D01*
X58327Y137888D01*
X58120Y138079D01*
G01Y139378D02*
X58378Y139608D01*
X58533Y139876D01*
X58585Y140221D01*
X58482Y140566D01*
X58275Y140834D01*
X57913Y141026D01*
X57500Y141064D01*
X57087Y140988D01*
X56828Y140796D01*
X56622Y140528D01*
X56570Y140259D01*
X56622Y139991D01*
X56828Y139646D01*
X55485Y139761D01*
Y140796D01*
G01Y143321D02*
X55588Y143014D01*
X55847Y142784D01*
X56157Y142631D01*
X56570Y142516D01*
X57035Y142478D01*
X57500Y142516D01*
X57913Y142631D01*
X58223Y142784D01*
X58482Y143014D01*
X58585Y143321D01*
X58482Y143628D01*
X58223Y143858D01*
X57913Y144011D01*
X57500Y144126D01*
X57035Y144164D01*
X56570Y144126D01*
X56157Y144011D01*
X55847Y143858D01*
X55588Y143628D01*
X55485Y143321D01*
G01X56002Y145693D02*
X55692Y145923D01*
X55537Y146191D01*
X55485Y146498D01*
X55588Y146881D01*
X55847Y147149D01*
X56157Y147226D01*
X56467Y147188D01*
X56725Y147034D01*
X57242Y146268D01*
X57603Y145923D01*
X58120Y145693D01*
X58585Y145616D01*
Y147226D01*
G01X56879Y136030D02*
X56649Y136185D01*
X56381Y136288D01*
X56074D01*
X55729Y136133D01*
X55461Y135875D01*
X55269Y135565D01*
X55116Y135048D01*
X55078Y134583D01*
X55154Y134118D01*
X55269Y133808D01*
X55499Y133498D01*
X55768Y133291D01*
X56036Y133188D01*
X56304D01*
X56573Y133291D01*
X56803Y133446D01*
X56994Y133653D01*
G01X59596Y133188D02*
Y136288D01*
X58178Y134066D01*
X60094D01*
G01X61584Y133550D02*
X61853Y133291D01*
X62159Y133188D01*
X62466Y133291D01*
X62734Y133601D01*
X62926Y134066D01*
X63003Y134531D01*
Y135100D01*
X62926Y135565D01*
X62734Y135978D01*
X62504Y136185D01*
X62236Y136288D01*
X61929Y136185D01*
X61699Y135978D01*
X61546Y135668D01*
X61469Y135255D01*
X61546Y134893D01*
X61738Y134531D01*
X61968Y134325D01*
X62236Y134273D01*
X62543Y134376D01*
X62773Y134635D01*
X63003Y135100D01*
G01X64684Y133550D02*
X64953Y133291D01*
X65259Y133188D01*
X65566Y133291D01*
X65834Y133601D01*
X66026Y134066D01*
X66103Y134531D01*
Y135100D01*
X66026Y135565D01*
X65834Y135978D01*
X65604Y136185D01*
X65336Y136288D01*
X65029Y136185D01*
X64799Y135978D01*
X64646Y135668D01*
X64569Y135255D01*
X64646Y134893D01*
X64838Y134531D01*
X65068Y134325D01*
X65336Y134273D01*
X65643Y134376D01*
X65873Y134635D01*
X66103Y135100D01*
G01X58969Y137383D02*
X62069D01*
Y138917D01*
G01Y141710D02*
X58969D01*
X61191Y140292D01*
Y142208D01*
G01X62069Y144350D02*
X58969D01*
X59589Y143890D01*
G01X62069D02*
Y144810D01*
G01X65914Y137135D02*
X62814D01*
Y138094D01*
X62969Y138400D01*
X63176Y138592D01*
X63589Y138669D01*
X64002Y138592D01*
X64261Y138362D01*
X64416Y138094D01*
Y137135D01*
G01Y138094D02*
X65914Y138669D01*
G01Y140925D02*
X65242Y141002D01*
X64674Y141117D01*
X64157Y141270D01*
X63589Y141462D01*
X62814Y141769D01*
Y140235D01*
G01X65914Y144102D02*
X65862Y144370D01*
X65707Y144677D01*
X65449Y144869D01*
X65087Y144945D01*
X64726Y144869D01*
X64416Y144639D01*
X64261Y144294D01*
Y143910D01*
X64157Y143680D01*
X63899Y143489D01*
X63537Y143412D01*
X63176Y143527D01*
X62917Y143795D01*
X62814Y144102D01*
X62917Y144409D01*
X63176Y144677D01*
X63537Y144792D01*
X63899Y144715D01*
X64157Y144524D01*
X64261Y144294D01*
Y143910D01*
X64416Y143565D01*
X64726Y143335D01*
X65087Y143259D01*
X65449Y143335D01*
X65707Y143527D01*
X65862Y143834D01*
X65914Y144102D01*
G01X65552Y146550D02*
X65811Y146819D01*
X65914Y147125D01*
X65811Y147432D01*
X65501Y147700D01*
X65036Y147892D01*
X64571Y147969D01*
X64002D01*
X63537Y147892D01*
X63124Y147700D01*
X62917Y147470D01*
X62814Y147202D01*
X62917Y146895D01*
X63124Y146665D01*
X63434Y146512D01*
X63847Y146435D01*
X64209Y146512D01*
X64571Y146704D01*
X64777Y146934D01*
X64829Y147202D01*
X64726Y147509D01*
X64467Y147739D01*
X64002Y147969D01*
G01X69768Y127417D02*
X66668D01*
Y128376D01*
X66823Y128682D01*
X67030Y128874D01*
X67443Y128951D01*
X67856Y128874D01*
X68115Y128644D01*
X68270Y128376D01*
Y127417D01*
G01Y128376D02*
X69768Y128951D01*
G01Y131284D02*
X66668D01*
X67288Y130824D01*
G01X69768D02*
Y131744D01*
G01X69406Y133732D02*
X69665Y134001D01*
X69768Y134307D01*
X69665Y134614D01*
X69355Y134882D01*
X68890Y135074D01*
X68425Y135151D01*
X67856D01*
X67391Y135074D01*
X66978Y134882D01*
X66771Y134652D01*
X66668Y134384D01*
X66771Y134077D01*
X66978Y133847D01*
X67288Y133694D01*
X67701Y133617D01*
X68063Y133694D01*
X68425Y133886D01*
X68631Y134116D01*
X68683Y134384D01*
X68580Y134691D01*
X68321Y134921D01*
X67856Y135151D01*
G01X69303Y136641D02*
X69561Y136871D01*
X69716Y137139D01*
X69768Y137484D01*
X69665Y137829D01*
X69458Y138097D01*
X69096Y138289D01*
X68683Y138327D01*
X68270Y138251D01*
X68011Y138059D01*
X67805Y137791D01*
X67753Y137522D01*
X67805Y137254D01*
X68011Y136909D01*
X66668Y137024D01*
Y138059D01*
G01X68185Y147352D02*
Y148184D01*
G01X56293Y150564D02*
X56138Y150334D01*
X56035Y150066D01*
Y149759D01*
X56190Y149414D01*
X56448Y149146D01*
X56758Y148954D01*
X57275Y148801D01*
X57740Y148763D01*
X58205Y148839D01*
X58515Y148954D01*
X58825Y149184D01*
X59032Y149453D01*
X59135Y149721D01*
Y149989D01*
X59032Y150258D01*
X58877Y150488D01*
X58670Y150679D01*
G01Y151978D02*
X58928Y152208D01*
X59083Y152476D01*
X59135Y152821D01*
X59032Y153166D01*
X58825Y153434D01*
X58463Y153626D01*
X58050Y153664D01*
X57637Y153588D01*
X57378Y153396D01*
X57172Y153128D01*
X57120Y152859D01*
X57172Y152591D01*
X57378Y152246D01*
X56035Y152361D01*
Y153396D01*
G01Y155921D02*
X56138Y155614D01*
X56397Y155384D01*
X56707Y155231D01*
X57120Y155116D01*
X57585Y155078D01*
X58050Y155116D01*
X58463Y155231D01*
X58773Y155384D01*
X59032Y155614D01*
X59135Y155921D01*
X59032Y156228D01*
X58773Y156458D01*
X58463Y156611D01*
X58050Y156726D01*
X57585Y156764D01*
X57120Y156726D01*
X56707Y156611D01*
X56397Y156458D01*
X56138Y156228D01*
X56035Y155921D01*
G01X58670Y158178D02*
X58928Y158408D01*
X59083Y158676D01*
X59135Y159021D01*
X59032Y159366D01*
X58825Y159634D01*
X58463Y159826D01*
X58050Y159864D01*
X57637Y159788D01*
X57378Y159596D01*
X57172Y159328D01*
X57120Y159059D01*
X57172Y158791D01*
X57378Y158446D01*
X56035Y158561D01*
Y159596D01*
G01X62905Y148954D02*
X59805D01*
Y149913D01*
X59960Y150219D01*
X60167Y150411D01*
X60580Y150488D01*
X60993Y150411D01*
X61252Y150181D01*
X61407Y149913D01*
Y148954D01*
G01Y149913D02*
X62905Y150488D01*
G01X61613Y152093D02*
X61252Y152361D01*
X61045Y152591D01*
X60942Y152898D01*
X61045Y153166D01*
X61252Y153358D01*
X61562Y153511D01*
X61923Y153549D01*
X62233Y153511D01*
X62543Y153358D01*
X62802Y153128D01*
X62905Y152859D01*
X62802Y152553D01*
X62492Y152284D01*
X62027Y152131D01*
X61510Y152093D01*
X60838Y152169D01*
X60477Y152284D01*
X60115Y152476D01*
X59857Y152744D01*
X59805Y153013D01*
X59908Y153281D01*
X60167Y153473D01*
G01X62285Y155078D02*
X62647Y155308D01*
X62853Y155614D01*
X62905Y155959D01*
X62853Y156266D01*
X62595Y156573D01*
X62285Y156764D01*
X61975Y156803D01*
X61613Y156726D01*
X61355Y156458D01*
X61252Y156189D01*
Y155844D01*
G01Y156189D02*
X61097Y156419D01*
X60838Y156611D01*
X60528Y156688D01*
X60218Y156611D01*
X59960Y156419D01*
X59805Y156074D01*
X59857Y155729D01*
X60063Y155384D01*
G01X62543Y158369D02*
X62802Y158638D01*
X62905Y158944D01*
X62802Y159251D01*
X62492Y159519D01*
X62027Y159711D01*
X61562Y159788D01*
X60993D01*
X60528Y159711D01*
X60115Y159519D01*
X59908Y159289D01*
X59805Y159021D01*
X59908Y158714D01*
X60115Y158484D01*
X60425Y158331D01*
X60838Y158254D01*
X61200Y158331D01*
X61562Y158523D01*
X61768Y158753D01*
X61820Y159021D01*
X61717Y159328D01*
X61458Y159558D01*
X60993Y159788D01*
G01X69814Y148855D02*
X66714D01*
Y149814D01*
X66869Y150120D01*
X67076Y150312D01*
X67489Y150389D01*
X67902Y150312D01*
X68161Y150082D01*
X68316Y149814D01*
Y148855D01*
G01Y149814D02*
X69814Y150389D01*
G01X68522Y151994D02*
X68161Y152262D01*
X67954Y152492D01*
X67851Y152799D01*
X67954Y153067D01*
X68161Y153259D01*
X68471Y153412D01*
X68832Y153450D01*
X69142Y153412D01*
X69452Y153259D01*
X69711Y153029D01*
X69814Y152760D01*
X69711Y152454D01*
X69401Y152185D01*
X68936Y152032D01*
X68419Y151994D01*
X67747Y152070D01*
X67386Y152185D01*
X67024Y152377D01*
X66766Y152645D01*
X66714Y152914D01*
X66817Y153182D01*
X67076Y153374D01*
G01X69194Y154979D02*
X69556Y155209D01*
X69762Y155515D01*
X69814Y155860D01*
X69762Y156167D01*
X69504Y156474D01*
X69194Y156665D01*
X68884Y156704D01*
X68522Y156627D01*
X68264Y156359D01*
X68161Y156090D01*
Y155745D01*
G01Y156090D02*
X68006Y156320D01*
X67747Y156512D01*
X67437Y156589D01*
X67127Y156512D01*
X66869Y156320D01*
X66714Y155975D01*
X66766Y155630D01*
X66972Y155285D01*
G01X69814Y159382D02*
X66714D01*
X68936Y157964D01*
Y159880D01*
G01X69431Y146557D02*
Y140357D01*
X66231D01*
Y146557D01*
X69431D01*
G01X62220Y178026D02*
Y167826D01*
G01X57620D02*
Y178026D01*
G01X62220Y167826D02*
X57620D01*
G01X62540Y166848D02*
Y162248D01*
G01X67640Y166848D02*
Y162248D01*
G01X57440Y166848D02*
X67640D01*
G01Y162248D02*
X57440D01*
G01D02*
Y166848D01*
G01X68196Y178071D02*
Y167871D01*
G01X63196D02*
Y178071D01*
G01X68196Y167871D02*
X63196D01*
G01X69145Y168511D02*
Y174711D01*
G01X72345Y168511D02*
X69145D01*
G01X57570Y186110D02*
Y226620D01*
G01X57770Y186110D02*
X57570D01*
G01X54560Y185780D02*
X67766D01*
Y183872D01*
X73575D01*
G01X62522Y182287D02*
X59522D01*
G01X62622Y179187D02*
X59422D01*
G01X62622Y185387D02*
Y179187D01*
G01X59422Y185387D02*
X62622D01*
G01X59422Y179187D02*
Y185387D01*
G01X57620Y178026D02*
X62220D01*
G01X57620Y172926D02*
X62220D01*
G01X68196Y178071D02*
X63196D01*
G01X67996Y173471D02*
X63396D01*
G01X67996Y172471D02*
X63396D01*
G01X63569Y185446D02*
X66769D01*
G01X63569Y179246D02*
Y185446D01*
G01X66769Y179246D02*
X63569D01*
G01X66769Y185446D02*
Y179246D01*
G01X69145Y174711D02*
X72345D01*
G01X62329Y202801D02*
X59129D01*
G01X62329Y209001D02*
Y202801D01*
G01X59129D02*
Y209001D01*
G01X69580Y193109D02*
Y203309D01*
G01X74180Y193109D02*
X69580D01*
G01X74180Y198209D02*
X69580D01*
G01X57521Y201765D02*
X62121D01*
G01X57521Y191565D02*
Y201765D01*
G01X62121Y191565D02*
X57521D01*
G01X62121Y201765D02*
Y191565D01*
G01Y196665D02*
X57521D01*
G01X63521Y197165D02*
X68121D01*
G01X63321Y201765D02*
X68321D01*
G01X63321Y191565D02*
X68321D01*
G01Y201765D02*
Y191565D01*
G01X63521Y196165D02*
X68121D01*
G01X63321Y191565D02*
Y201765D01*
G01X63306Y202920D02*
Y209120D01*
G01X66506Y202920D02*
X63306D01*
G01X66506Y209120D02*
Y202920D01*
G01X67960Y190546D02*
X74160D01*
G01X67960Y187346D02*
Y190546D01*
G01X74160Y187346D02*
X67960D01*
G01X65338Y187582D02*
X59138D01*
G01X65338Y190782D02*
Y187582D01*
G01X59138Y190782D02*
X65338D01*
G01X59138Y187582D02*
Y190782D01*
G01X62229Y205901D02*
X59229D01*
G01X59129Y209001D02*
X62329D01*
G01X62542Y220743D02*
Y210543D01*
G01X57942D02*
Y220743D01*
G01X62542Y215643D02*
X57942D01*
G01X62542Y210543D02*
X57942D01*
G01X69580Y203309D02*
X74180D01*
G01X68742Y220743D02*
Y210543D01*
G01X63742D02*
Y220743D01*
G01X63942Y216143D02*
X68542D01*
G01X63942Y215143D02*
X68542D01*
G01X63742Y210543D02*
X68742D01*
G01X63306Y209120D02*
X66506D01*
G01X57570Y226620D02*
X78450D01*
G01X77584Y227420D02*
X62584D01*
G01D02*
Y240420D01*
G01X61532Y230258D02*
X58532D01*
G01X61632Y227158D02*
X58432D01*
G01Y233358D02*
X61632D01*
G01X58432Y227158D02*
Y233358D01*
G01X61632D02*
Y227158D01*
G01X57942Y220743D02*
X62542D01*
G01X58055Y221644D02*
Y226244D01*
G01X68255Y221644D02*
X58055D01*
G01Y226244D02*
X68255D01*
G01D02*
Y221644D01*
G01X63155Y226244D02*
Y221644D01*
G01X63742Y220743D02*
X68742D01*
G01X57544Y231198D02*
X54444D01*
Y232157D01*
X54599Y232463D01*
X54806Y232655D01*
X55219Y232732D01*
X55632Y232655D01*
X55891Y232425D01*
X56046Y232157D01*
Y231198D01*
G01Y232157D02*
X57544Y232732D01*
G01X56252Y234337D02*
X55891Y234605D01*
X55684Y234835D01*
X55581Y235142D01*
X55684Y235410D01*
X55891Y235602D01*
X56201Y235755D01*
X56562Y235793D01*
X56872Y235755D01*
X57182Y235602D01*
X57441Y235372D01*
X57544Y235103D01*
X57441Y234797D01*
X57131Y234528D01*
X56666Y234375D01*
X56149Y234337D01*
X55477Y234413D01*
X55116Y234528D01*
X54754Y234720D01*
X54496Y234988D01*
X54444Y235257D01*
X54547Y235525D01*
X54806Y235717D01*
G01X56924Y237322D02*
X57286Y237552D01*
X57492Y237858D01*
X57544Y238203D01*
X57492Y238510D01*
X57234Y238817D01*
X56924Y239008D01*
X56614Y239047D01*
X56252Y238970D01*
X55994Y238702D01*
X55891Y238433D01*
Y238088D01*
G01Y238433D02*
X55736Y238663D01*
X55477Y238855D01*
X55167Y238932D01*
X54857Y238855D01*
X54599Y238663D01*
X54444Y238318D01*
X54496Y237973D01*
X54702Y237628D01*
G01X57544Y241188D02*
X56872Y241265D01*
X56304Y241380D01*
X55787Y241533D01*
X55219Y241725D01*
X54444Y242032D01*
Y240498D01*
G01X61629Y234355D02*
X58429D01*
G01D02*
Y240555D01*
G01X61629D02*
Y234355D01*
G01X65027Y237780D02*
X65187Y237488D01*
X65401Y237322D01*
X65641Y237280D01*
X65854Y237322D01*
X66067Y237530D01*
X66201Y237780D01*
X66227Y238030D01*
X66174Y238322D01*
X65987Y238530D01*
X65801Y238613D01*
X65561D01*
G01X65801D02*
X65961Y238738D01*
X66094Y238947D01*
X66147Y239197D01*
X66094Y239447D01*
X65961Y239655D01*
X65721Y239780D01*
X65481Y239738D01*
X65241Y239572D01*
G01X62584Y240420D02*
X77584D01*
G01X58582Y248424D02*
Y254624D01*
G01X61782Y248424D02*
X58582D01*
G01X61782Y254624D02*
Y248424D01*
G01X57536Y243421D02*
X54436D01*
Y244380D01*
X54591Y244686D01*
X54798Y244878D01*
X55211Y244955D01*
X55624Y244878D01*
X55883Y244648D01*
X56038Y244380D01*
Y243421D01*
G01Y244380D02*
X57536Y244955D01*
G01X56244Y246560D02*
X55883Y246828D01*
X55676Y247058D01*
X55573Y247365D01*
X55676Y247633D01*
X55883Y247825D01*
X56193Y247978D01*
X56554Y248016D01*
X56864Y247978D01*
X57174Y247825D01*
X57433Y247595D01*
X57536Y247326D01*
X57433Y247020D01*
X57123Y246751D01*
X56658Y246598D01*
X56141Y246560D01*
X55469Y246636D01*
X55108Y246751D01*
X54746Y246943D01*
X54488Y247211D01*
X54436Y247480D01*
X54539Y247748D01*
X54798Y247940D01*
G01X56916Y249545D02*
X57278Y249775D01*
X57484Y250081D01*
X57536Y250426D01*
X57484Y250733D01*
X57226Y251040D01*
X56916Y251231D01*
X56606Y251270D01*
X56244Y251193D01*
X55986Y250925D01*
X55883Y250656D01*
Y250311D01*
G01Y250656D02*
X55728Y250886D01*
X55469Y251078D01*
X55159Y251155D01*
X54849Y251078D01*
X54591Y250886D01*
X54436Y250541D01*
X54488Y250196D01*
X54694Y249851D01*
G01X57071Y252645D02*
X57329Y252875D01*
X57484Y253143D01*
X57536Y253488D01*
X57433Y253833D01*
X57226Y254101D01*
X56864Y254293D01*
X56451Y254331D01*
X56038Y254255D01*
X55779Y254063D01*
X55573Y253795D01*
X55521Y253526D01*
X55573Y253258D01*
X55779Y252913D01*
X54436Y253028D01*
Y254063D01*
G01X58577Y247547D02*
X61777D01*
G01X58577Y241347D02*
Y247547D01*
G01X61777Y241347D02*
X58577D01*
G01X61777Y247547D02*
Y241347D01*
G01X58429Y240555D02*
X61629D01*
G01X63463Y242217D02*
Y244717D01*
X63997D01*
X64210Y244592D01*
X64370Y244425D01*
X64503Y244175D01*
X64610Y243884D01*
X64637Y243467D01*
X64610Y243050D01*
X64503Y242759D01*
X64370Y242509D01*
X64210Y242342D01*
X63997Y242217D01*
X63463D01*
G01X77874Y241444D02*
X62874D01*
G01D02*
Y254444D01*
G01X66083Y262087D02*
X66243Y261795D01*
X66457Y261629D01*
X66697Y261587D01*
X66910Y261629D01*
X67123Y261837D01*
X67257Y262087D01*
X67283Y262337D01*
X67230Y262629D01*
X67043Y262837D01*
X66857Y262920D01*
X66617D01*
G01X66857D02*
X67017Y263045D01*
X67150Y263254D01*
X67203Y263504D01*
X67150Y263754D01*
X67017Y263962D01*
X66777Y264087D01*
X66537Y264045D01*
X66297Y263879D01*
G01X64296Y255679D02*
Y270679D01*
G01X77296Y255679D02*
X64296D01*
G01X58604Y255549D02*
Y258549D01*
G01X55504Y255449D02*
Y258649D01*
G01X61704Y255449D02*
X55504D01*
G01Y258649D02*
X61704D01*
G01D02*
Y255449D01*
G01X63254Y259247D02*
X60754D01*
Y259913D01*
X60879Y260127D01*
X61046Y260260D01*
X61379Y260313D01*
X61712Y260260D01*
X61921Y260100D01*
X62046Y259913D01*
Y259247D01*
G01Y259913D02*
X63254Y260313D01*
G01X62212Y261473D02*
X61921Y261660D01*
X61754Y261820D01*
X61671Y262033D01*
X61754Y262220D01*
X61921Y262353D01*
X62171Y262460D01*
X62462Y262487D01*
X62712Y262460D01*
X62962Y262353D01*
X63171Y262193D01*
X63254Y262007D01*
X63171Y261793D01*
X62921Y261607D01*
X62546Y261500D01*
X62129Y261473D01*
X61587Y261527D01*
X61296Y261607D01*
X61004Y261740D01*
X60796Y261927D01*
X60754Y262113D01*
X60837Y262300D01*
X61046Y262433D01*
G01X62754Y263593D02*
X63046Y263753D01*
X63212Y263967D01*
X63254Y264207D01*
X63212Y264420D01*
X63004Y264633D01*
X62754Y264767D01*
X62504Y264793D01*
X62212Y264740D01*
X62004Y264553D01*
X61921Y264367D01*
Y264127D01*
G01Y264367D02*
X61796Y264527D01*
X61587Y264660D01*
X61337Y264713D01*
X61087Y264660D01*
X60879Y264527D01*
X60754Y264287D01*
X60796Y264047D01*
X60962Y263807D01*
G01X62212Y265873D02*
X61921Y266060D01*
X61754Y266220D01*
X61671Y266433D01*
X61754Y266620D01*
X61921Y266753D01*
X62171Y266860D01*
X62462Y266887D01*
X62712Y266860D01*
X62962Y266753D01*
X63171Y266593D01*
X63254Y266407D01*
X63171Y266193D01*
X62921Y266007D01*
X62546Y265900D01*
X62129Y265873D01*
X61587Y265927D01*
X61296Y266007D01*
X61004Y266140D01*
X60796Y266327D01*
X60754Y266513D01*
X60837Y266700D01*
X61046Y266833D01*
G01X58582Y254624D02*
X61782D01*
G01X62438Y255751D02*
X62651Y255543D01*
X62891Y255418D01*
X63105D01*
X63318Y255543D01*
X63478Y255751D01*
X63558Y256043D01*
X63505Y256335D01*
X63371Y256585D01*
X63131Y256751D01*
X62811Y256835D01*
X62625Y257001D01*
X62545Y257293D01*
X62598Y257585D01*
X62731Y257793D01*
X62918Y257918D01*
X63105D01*
X63291Y257835D01*
X63451Y257626D01*
G01X62874Y254444D02*
X77874D01*
G01X62233Y270480D02*
X62393Y270730D01*
X62580Y270855D01*
X62793Y270897D01*
X63060Y270814D01*
X63247Y270605D01*
X63300Y270355D01*
X63273Y270105D01*
X63167Y269897D01*
X62633Y269480D01*
X62393Y269189D01*
X62233Y268772D01*
X62180Y268397D01*
X63300D01*
G01X64296Y270679D02*
X77296D01*
G01X54968Y271557D02*
Y285757D01*
G01X76768Y271557D02*
X54968D01*
G01X57728Y300105D02*
X57498Y300260D01*
X57230Y300363D01*
X56923D01*
X56578Y300208D01*
X56310Y299950D01*
X56118Y299640D01*
X55965Y299123D01*
X55927Y298658D01*
X56003Y298193D01*
X56118Y297883D01*
X56348Y297573D01*
X56617Y297366D01*
X56885Y297263D01*
X57153D01*
X57422Y297366D01*
X57652Y297521D01*
X57843Y297728D01*
G01X59142Y297263D02*
Y300363D01*
X59908D01*
X60215Y300208D01*
X60445Y300001D01*
X60637Y299691D01*
X60790Y299330D01*
X60828Y298813D01*
X60790Y298296D01*
X60637Y297935D01*
X60445Y297625D01*
X60215Y297418D01*
X59908Y297263D01*
X59142D01*
G01X63085D02*
Y300363D01*
X62625Y299743D01*
G01Y297263D02*
X63545D01*
G01X66234Y301683D02*
X68114D01*
G01X67096Y303048D02*
Y300318D01*
G01X54005Y290514D02*
X69072D01*
G01Y295828D02*
X54005D01*
G01D02*
Y290514D01*
G01X69072D02*
Y295828D01*
G01X64644Y293171D02*
X63860D01*
G01X61498D02*
X63860Y294746D01*
G01Y291596D02*
X61498Y293171D01*
G01X63860Y294746D02*
Y291596D01*
G01X61498Y294746D02*
Y291596D01*
G01Y293171D02*
X60714D01*
G01X54968Y285757D02*
X76768D01*
G01X64257Y307708D02*
X59257D01*
Y308974D01*
X59507Y309481D01*
X59840Y309861D01*
X60340Y310178D01*
X60924Y310431D01*
X61757Y310494D01*
X62590Y310431D01*
X63174Y310178D01*
X63674Y309861D01*
X64007Y309481D01*
X64257Y308974D01*
Y307708D01*
G01Y315468D02*
Y312934D01*
X59257D01*
Y315468D01*
G01X61674Y314454D02*
Y312934D01*
G01X61590Y319808D02*
X61340Y320061D01*
X60924Y320251D01*
X60340Y320378D01*
X59840Y320251D01*
X59507Y319998D01*
X59257Y319554D01*
Y317844D01*
X64257D01*
Y319934D01*
X63924Y320378D01*
X63424Y320631D01*
X62840Y320758D01*
X62257Y320631D01*
X61757Y320251D01*
X61590Y319808D01*
Y317844D01*
G01X59257Y323008D02*
X62840D01*
X63590Y323261D01*
X64090Y323768D01*
X64257Y324401D01*
X64090Y325034D01*
X63590Y325541D01*
X62840Y325794D01*
X59257D01*
G01X61757Y329881D02*
Y331148D01*
X63257D01*
X63757Y330768D01*
X64090Y330324D01*
X64257Y329691D01*
X64090Y329058D01*
X63757Y328614D01*
X63257Y328234D01*
X62674Y327981D01*
X62007Y327854D01*
X61424D01*
X60924Y327981D01*
X60340Y328234D01*
X59840Y328614D01*
X59507Y328994D01*
X59257Y329501D01*
Y329944D01*
X59424Y330451D01*
X59757Y330831D01*
G01X64257Y338434D02*
X59257D01*
Y339954D01*
X59507Y340461D01*
X60090Y340841D01*
X60757Y340968D01*
X61424Y340841D01*
X61924Y340524D01*
X62174Y339954D01*
Y338434D01*
G01X59257Y342901D02*
X64257Y343788D01*
X59257Y344801D01*
X64257Y345814D01*
X59257Y346701D01*
G01X64257Y348634D02*
X59257D01*
Y350218D01*
X59507Y350724D01*
X59840Y351041D01*
X60507Y351168D01*
X61174Y351041D01*
X61590Y350661D01*
X61840Y350218D01*
Y348634D01*
G01Y350218D02*
X64257Y351168D01*
G01X59674Y361494D02*
X59424Y361114D01*
X59257Y360671D01*
Y360164D01*
X59507Y359594D01*
X59924Y359151D01*
X60424Y358834D01*
X61257Y358581D01*
X62007Y358518D01*
X62757Y358644D01*
X63257Y358834D01*
X63757Y359214D01*
X64090Y359658D01*
X64257Y360101D01*
Y360544D01*
X64090Y360988D01*
X63840Y361368D01*
X63507Y361684D01*
G01X64257Y365201D02*
X64174Y364694D01*
X63840Y364251D01*
X63340Y363871D01*
X62757Y363618D01*
X62090Y363491D01*
X61424D01*
X60757Y363618D01*
X60174Y363871D01*
X59674Y364251D01*
X59340Y364694D01*
X59257Y365201D01*
X59340Y365708D01*
X59674Y366151D01*
X60174Y366531D01*
X60757Y366784D01*
X61424Y366911D01*
X62090D01*
X62757Y366784D01*
X63340Y366531D01*
X63840Y366151D01*
X64174Y365708D01*
X64257Y365201D01*
G01Y368844D02*
X59257D01*
X64257Y371758D01*
X59257D01*
G01X64257Y373944D02*
X59257D01*
X64257Y376858D01*
X59257D01*
G01X58358Y378012D02*
Y305689D01*
X65558D01*
Y378955D01*
X58358D01*
Y378012D01*
G01X54140Y348930D02*
Y311134D01*
G01X56182Y318940D02*
X56412Y319250D01*
X56680Y319405D01*
X56987Y319457D01*
X57370Y319354D01*
X57638Y319095D01*
X57715Y318785D01*
X57677Y318475D01*
X57523Y318217D01*
X56757Y317700D01*
X56412Y317339D01*
X56182Y316822D01*
X56105Y316357D01*
X57715D01*
G01X56368Y340102D02*
Y343202D01*
X55908Y342582D01*
G01Y340102D02*
X56828D01*
G01X58438Y390065D02*
Y393165D01*
X59397D01*
X59703Y393010D01*
X59895Y392803D01*
X59972Y392390D01*
X59895Y391977D01*
X59665Y391718D01*
X59397Y391563D01*
X58438D01*
G01X59397D02*
X59972Y390065D01*
G01X62305D02*
Y393165D01*
X61845Y392545D01*
G01Y390065D02*
X62765D01*
G01X65405D02*
X65673Y390117D01*
X65980Y390272D01*
X66172Y390530D01*
X66248Y390892D01*
X66172Y391253D01*
X65942Y391563D01*
X65597Y391718D01*
X65213D01*
X64983Y391822D01*
X64792Y392080D01*
X64715Y392442D01*
X64830Y392803D01*
X65098Y393062D01*
X65405Y393165D01*
X65712Y393062D01*
X65980Y392803D01*
X66095Y392442D01*
X66018Y392080D01*
X65827Y391822D01*
X65597Y391718D01*
X65213D01*
X64868Y391563D01*
X64638Y391253D01*
X64562Y390892D01*
X64638Y390530D01*
X64830Y390272D01*
X65137Y390117D01*
X65405Y390065D01*
G01X67777Y391357D02*
X68045Y391718D01*
X68275Y391925D01*
X68582Y392028D01*
X68850Y391925D01*
X69042Y391718D01*
X69195Y391408D01*
X69233Y391047D01*
X69195Y390737D01*
X69042Y390427D01*
X68812Y390168D01*
X68543Y390065D01*
X68237Y390168D01*
X67968Y390478D01*
X67815Y390943D01*
X67777Y391460D01*
X67853Y392132D01*
X67968Y392493D01*
X68160Y392855D01*
X68428Y393113D01*
X68697Y393165D01*
X68965Y393062D01*
X69157Y392803D01*
G01X58438Y385536D02*
Y388636D01*
X59397D01*
X59703Y388481D01*
X59895Y388274D01*
X59972Y387861D01*
X59895Y387448D01*
X59665Y387189D01*
X59397Y387034D01*
X58438D01*
G01X59397D02*
X59972Y385536D01*
G01X62305D02*
Y388636D01*
X61845Y388016D01*
G01Y385536D02*
X62765D01*
G01X65405D02*
Y388636D01*
X64945Y388016D01*
G01Y385536D02*
X65865D01*
G01X67662Y386001D02*
X67892Y385743D01*
X68160Y385588D01*
X68505Y385536D01*
X68850Y385639D01*
X69118Y385846D01*
X69310Y386208D01*
X69348Y386621D01*
X69272Y387034D01*
X69080Y387293D01*
X68812Y387499D01*
X68543Y387551D01*
X68275Y387499D01*
X67930Y387293D01*
X68045Y388636D01*
X69080D01*
G01X70762Y386156D02*
X70992Y385794D01*
X71298Y385588D01*
X71643Y385536D01*
X71950Y385588D01*
X72257Y385846D01*
X72448Y386156D01*
X72487Y386466D01*
X72410Y386828D01*
X72142Y387086D01*
X71873Y387189D01*
X71528D01*
G01X71873D02*
X72103Y387344D01*
X72295Y387603D01*
X72372Y387913D01*
X72295Y388223D01*
X72103Y388481D01*
X71758Y388636D01*
X71413Y388584D01*
X71068Y388378D01*
G01X60793Y408637D02*
Y411737D01*
X61713D01*
X62020Y411582D01*
X62250Y411220D01*
X62327Y410807D01*
X62250Y410394D01*
X62058Y410084D01*
X61713Y409929D01*
X60793D01*
G01X65503Y411479D02*
X65273Y411634D01*
X65005Y411737D01*
X64698D01*
X64353Y411582D01*
X64085Y411324D01*
X63893Y411014D01*
X63740Y410497D01*
X63702Y410032D01*
X63778Y409567D01*
X63893Y409257D01*
X64123Y408947D01*
X64392Y408740D01*
X64660Y408637D01*
X64928D01*
X65197Y408740D01*
X65427Y408895D01*
X65618Y409102D01*
G01X67032Y409929D02*
X67300Y410290D01*
X67530Y410497D01*
X67837Y410600D01*
X68105Y410497D01*
X68297Y410290D01*
X68450Y409980D01*
X68488Y409619D01*
X68450Y409309D01*
X68297Y408999D01*
X68067Y408740D01*
X67798Y408637D01*
X67492Y408740D01*
X67223Y409050D01*
X67070Y409515D01*
X67032Y410032D01*
X67108Y410704D01*
X67223Y411065D01*
X67415Y411427D01*
X67683Y411685D01*
X67952Y411737D01*
X68220Y411634D01*
X68412Y411375D01*
G01X70017Y409257D02*
X70247Y408895D01*
X70553Y408689D01*
X70898Y408637D01*
X71205Y408689D01*
X71512Y408947D01*
X71703Y409257D01*
X71742Y409567D01*
X71665Y409929D01*
X71397Y410187D01*
X71128Y410290D01*
X70783D01*
G01X71128D02*
X71358Y410445D01*
X71550Y410704D01*
X71627Y411014D01*
X71550Y411324D01*
X71358Y411582D01*
X71013Y411737D01*
X70668Y411685D01*
X70323Y411479D01*
G01X58438Y394117D02*
Y397217D01*
X59397D01*
X59703Y397062D01*
X59895Y396855D01*
X59972Y396442D01*
X59895Y396029D01*
X59665Y395770D01*
X59397Y395615D01*
X58438D01*
G01X59397D02*
X59972Y394117D01*
G01X62305D02*
Y397217D01*
X61845Y396597D01*
G01Y394117D02*
X62765D01*
G01X65405D02*
Y397217D01*
X64945Y396597D01*
G01Y394117D02*
X65865D01*
G01X67662Y394582D02*
X67892Y394324D01*
X68160Y394169D01*
X68505Y394117D01*
X68850Y394220D01*
X69118Y394427D01*
X69310Y394789D01*
X69348Y395202D01*
X69272Y395615D01*
X69080Y395874D01*
X68812Y396080D01*
X68543Y396132D01*
X68275Y396080D01*
X67930Y395874D01*
X68045Y397217D01*
X69080D01*
G01X72065Y394117D02*
Y397217D01*
X70647Y394995D01*
X72563D01*
G01X58438Y398490D02*
Y401590D01*
X59397D01*
X59703Y401435D01*
X59895Y401228D01*
X59972Y400815D01*
X59895Y400402D01*
X59665Y400143D01*
X59397Y399988D01*
X58438D01*
G01X59397D02*
X59972Y398490D01*
G01X62305D02*
Y401590D01*
X61845Y400970D01*
G01Y398490D02*
X62765D01*
G01X65405D02*
X65673Y398542D01*
X65980Y398697D01*
X66172Y398955D01*
X66248Y399317D01*
X66172Y399678D01*
X65942Y399988D01*
X65597Y400143D01*
X65213D01*
X64983Y400247D01*
X64792Y400505D01*
X64715Y400867D01*
X64830Y401228D01*
X65098Y401487D01*
X65405Y401590D01*
X65712Y401487D01*
X65980Y401228D01*
X66095Y400867D01*
X66018Y400505D01*
X65827Y400247D01*
X65597Y400143D01*
X65213D01*
X64868Y399988D01*
X64638Y399678D01*
X64562Y399317D01*
X64638Y398955D01*
X64830Y398697D01*
X65137Y398542D01*
X65405Y398490D01*
G01X68428D02*
X68505Y399162D01*
X68620Y399730D01*
X68773Y400247D01*
X68965Y400815D01*
X69272Y401590D01*
X67738D01*
G01X62923Y454538D02*
X59823D01*
Y455458D01*
X59978Y455765D01*
X60340Y455995D01*
X60753Y456072D01*
X61166Y455995D01*
X61476Y455803D01*
X61631Y455458D01*
Y454538D01*
G01X59823Y457638D02*
X62923D01*
Y459172D01*
G01X61631Y460777D02*
X61270Y461045D01*
X61063Y461275D01*
X60960Y461582D01*
X61063Y461850D01*
X61270Y462042D01*
X61580Y462195D01*
X61941Y462233D01*
X62251Y462195D01*
X62561Y462042D01*
X62820Y461812D01*
X62923Y461543D01*
X62820Y461237D01*
X62510Y460968D01*
X62045Y460815D01*
X61528Y460777D01*
X60856Y460853D01*
X60495Y460968D01*
X60133Y461160D01*
X59875Y461428D01*
X59823Y461697D01*
X59926Y461965D01*
X60185Y462157D01*
G01X64310Y452606D02*
Y485406D01*
G01X90688Y452606D02*
X64310D01*
G01X59720Y475685D02*
Y468285D01*
G01X64310Y485406D02*
X90688D01*
G01X60046Y492256D02*
Y484856D01*
G01X59830Y483933D02*
Y476533D01*
G01X63467Y499524D02*
X81183D01*
G01X63467Y498618D02*
Y499524D01*
G01Y487712D02*
Y488618D01*
G01X81183Y487712D02*
X63467D01*
G01X54492Y496170D02*
Y492970D01*
G01X59395Y503140D02*
Y498540D01*
G01X54295D02*
Y503140D01*
G01X68156Y503358D02*
Y505858D01*
X67836Y505358D01*
G01Y503358D02*
X68476D01*
G01X69849Y505441D02*
X70009Y505691D01*
X70196Y505816D01*
X70409Y505858D01*
X70676Y505775D01*
X70863Y505566D01*
X70916Y505316D01*
X70889Y505066D01*
X70783Y504858D01*
X70249Y504441D01*
X70009Y504150D01*
X69849Y503733D01*
X69796Y503358D01*
X70916D01*
G01X55740Y504238D02*
X55926Y504029D01*
X56140Y503946D01*
X56353Y504029D01*
X56540Y504279D01*
X56673Y504654D01*
X56726Y505029D01*
Y505488D01*
X56673Y505863D01*
X56540Y506196D01*
X56380Y506363D01*
X56193Y506446D01*
X55980Y506363D01*
X55820Y506196D01*
X55713Y505946D01*
X55660Y505613D01*
X55713Y505321D01*
X55846Y505029D01*
X56006Y504863D01*
X56193Y504821D01*
X56406Y504904D01*
X56566Y505113D01*
X56726Y505488D01*
G01X57036Y519084D02*
Y517183D01*
G01X69438Y517083D02*
Y519084D01*
G01Y506682D02*
Y508783D01*
G01X67437Y506682D02*
X69438D01*
G01X57036D02*
X58737D01*
G01X57036Y508783D02*
Y506682D01*
G01X69438Y519084D02*
X67337D01*
G01X58937D02*
X57036D01*
G01X56951Y527582D02*
Y521382D01*
G01X62029Y533264D02*
Y536364D01*
X62949D01*
X63256Y536209D01*
X63486Y535847D01*
X63563Y535434D01*
X63486Y535021D01*
X63294Y534711D01*
X62949Y534556D01*
X62029D01*
G01X66739Y536106D02*
X66509Y536261D01*
X66241Y536364D01*
X65934D01*
X65589Y536209D01*
X65321Y535951D01*
X65129Y535641D01*
X64976Y535124D01*
X64938Y534659D01*
X65014Y534194D01*
X65129Y533884D01*
X65359Y533574D01*
X65628Y533367D01*
X65896Y533264D01*
X66164D01*
X66433Y533367D01*
X66663Y533522D01*
X66854Y533729D01*
G01X68268Y534556D02*
X68536Y534917D01*
X68766Y535124D01*
X69073Y535227D01*
X69341Y535124D01*
X69533Y534917D01*
X69686Y534607D01*
X69724Y534246D01*
X69686Y533936D01*
X69533Y533626D01*
X69303Y533367D01*
X69034Y533264D01*
X68728Y533367D01*
X68459Y533677D01*
X68306Y534142D01*
X68268Y534659D01*
X68344Y535331D01*
X68459Y535692D01*
X68651Y536054D01*
X68919Y536312D01*
X69188Y536364D01*
X69456Y536261D01*
X69648Y536002D01*
G01X71253Y533729D02*
X71483Y533471D01*
X71751Y533316D01*
X72096Y533264D01*
X72441Y533367D01*
X72709Y533574D01*
X72901Y533936D01*
X72939Y534349D01*
X72863Y534762D01*
X72671Y535021D01*
X72403Y535227D01*
X72134Y535279D01*
X71866Y535227D01*
X71521Y535021D01*
X71636Y536364D01*
X72671D01*
G01X61858Y528017D02*
X68058D01*
G01X61858Y524817D02*
Y528017D01*
G01X68058Y524817D02*
X61858D01*
G01X64958Y527917D02*
Y524917D01*
G01X68058Y528017D02*
Y524817D01*
G01X60509Y531923D02*
X57409D01*
Y532843D01*
X57564Y533150D01*
X57926Y533380D01*
X58339Y533457D01*
X58752Y533380D01*
X59062Y533188D01*
X59217Y532843D01*
Y531923D01*
G01X57667Y536633D02*
X57512Y536403D01*
X57409Y536135D01*
Y535828D01*
X57564Y535483D01*
X57822Y535215D01*
X58132Y535023D01*
X58649Y534870D01*
X59114Y534832D01*
X59579Y534908D01*
X59889Y535023D01*
X60199Y535253D01*
X60406Y535522D01*
X60509Y535790D01*
Y536058D01*
X60406Y536327D01*
X60251Y536557D01*
X60044Y536748D01*
G01X60509Y538813D02*
X59837Y538890D01*
X59269Y539005D01*
X58752Y539158D01*
X58184Y539350D01*
X57409Y539657D01*
Y538123D01*
G01Y541990D02*
X57512Y541683D01*
X57771Y541453D01*
X58081Y541300D01*
X58494Y541185D01*
X58959Y541147D01*
X59424Y541185D01*
X59837Y541300D01*
X60147Y541453D01*
X60406Y541683D01*
X60509Y541990D01*
X60406Y542297D01*
X60147Y542527D01*
X59837Y542680D01*
X59424Y542795D01*
X58959Y542833D01*
X58494Y542795D01*
X58081Y542680D01*
X57771Y542527D01*
X57512Y542297D01*
X57409Y541990D01*
G01X57699Y524528D02*
Y530728D01*
G01X60899Y524528D02*
X57699D01*
G01X60899Y530728D02*
Y524528D01*
G01X57799Y527628D02*
X60799D01*
G01X57699Y530728D02*
X60899D01*
G01X61858Y528817D02*
Y532017D01*
G01X68058Y528817D02*
X61858D01*
G01X68058Y532017D02*
Y528817D01*
G01X61858Y532017D02*
X68058D01*
G01X62180Y537653D02*
Y540753D01*
X63100D01*
X63407Y540598D01*
X63637Y540236D01*
X63714Y539823D01*
X63637Y539410D01*
X63445Y539100D01*
X63100Y538945D01*
X62180D01*
G01X65280Y537653D02*
Y540753D01*
X66239D01*
X66545Y540598D01*
X66737Y540391D01*
X66814Y539978D01*
X66737Y539565D01*
X66507Y539306D01*
X66239Y539151D01*
X65280D01*
G01X66239D02*
X66814Y537653D01*
G01X68419Y540236D02*
X68649Y540546D01*
X68917Y540701D01*
X69224Y540753D01*
X69607Y540650D01*
X69875Y540391D01*
X69952Y540081D01*
X69914Y539771D01*
X69760Y539513D01*
X68994Y538996D01*
X68649Y538635D01*
X68419Y538118D01*
X68342Y537653D01*
X69952D01*
G01X72170D02*
X72247Y538325D01*
X72362Y538893D01*
X72515Y539410D01*
X72707Y539978D01*
X73014Y540753D01*
X71480D01*
G01X81306Y557421D02*
X66306D01*
G01D02*
Y564221D01*
G01D02*
X81306D01*
G01X55853Y554089D02*
X55623Y554244D01*
X55355Y554347D01*
X55048D01*
X54703Y554192D01*
X54435Y553934D01*
X54243Y553624D01*
X54090Y553107D01*
X54052Y552642D01*
X54128Y552177D01*
X54243Y551867D01*
X54473Y551557D01*
X54742Y551350D01*
X55010Y551247D01*
X55278D01*
X55547Y551350D01*
X55777Y551505D01*
X55968Y551712D01*
G01X57267Y551867D02*
X57497Y551505D01*
X57803Y551299D01*
X58148Y551247D01*
X58455Y551299D01*
X58762Y551557D01*
X58953Y551867D01*
X58992Y552177D01*
X58915Y552539D01*
X58647Y552797D01*
X58378Y552900D01*
X58033D01*
G01X58378D02*
X58608Y553055D01*
X58800Y553314D01*
X58877Y553624D01*
X58800Y553934D01*
X58608Y554192D01*
X58263Y554347D01*
X57918Y554295D01*
X57573Y554089D01*
G01X60558Y551609D02*
X60827Y551350D01*
X61133Y551247D01*
X61440Y551350D01*
X61708Y551660D01*
X61900Y552125D01*
X61977Y552590D01*
Y553159D01*
X61900Y553624D01*
X61708Y554037D01*
X61478Y554244D01*
X61210Y554347D01*
X60903Y554244D01*
X60673Y554037D01*
X60520Y553727D01*
X60443Y553314D01*
X60520Y552952D01*
X60712Y552590D01*
X60942Y552384D01*
X61210Y552332D01*
X61517Y552435D01*
X61747Y552694D01*
X61977Y553159D01*
G01X63467Y551867D02*
X63697Y551505D01*
X64003Y551299D01*
X64348Y551247D01*
X64655Y551299D01*
X64962Y551557D01*
X65153Y551867D01*
X65192Y552177D01*
X65115Y552539D01*
X64847Y552797D01*
X64578Y552900D01*
X64233D01*
G01X64578D02*
X64808Y553055D01*
X65000Y553314D01*
X65077Y553624D01*
X65000Y553934D01*
X64808Y554192D01*
X64463Y554347D01*
X64118Y554295D01*
X63773Y554089D01*
G01X81460Y549572D02*
X66460D01*
G01D02*
Y556372D01*
G01D02*
X81460D01*
G01X58013Y584319D02*
X57783Y584474D01*
X57515Y584577D01*
X57208D01*
X56863Y584422D01*
X56595Y584164D01*
X56403Y583854D01*
X56250Y583337D01*
X56212Y582872D01*
X56288Y582407D01*
X56403Y582097D01*
X56633Y581787D01*
X56902Y581580D01*
X57170Y581477D01*
X57438D01*
X57707Y581580D01*
X57937Y581735D01*
X58128Y581942D01*
G01X60730Y581477D02*
Y584577D01*
X59312Y582355D01*
X61228D01*
G01X63370Y581477D02*
Y584577D01*
X62910Y583957D01*
G01Y581477D02*
X63830D01*
G01X65742Y582769D02*
X66010Y583130D01*
X66240Y583337D01*
X66547Y583440D01*
X66815Y583337D01*
X67007Y583130D01*
X67160Y582820D01*
X67198Y582459D01*
X67160Y582149D01*
X67007Y581839D01*
X66777Y581580D01*
X66508Y581477D01*
X66202Y581580D01*
X65933Y581890D01*
X65780Y582355D01*
X65742Y582872D01*
X65818Y583544D01*
X65933Y583905D01*
X66125Y584267D01*
X66393Y584525D01*
X66662Y584577D01*
X66930Y584474D01*
X67122Y584215D01*
G01X81306Y573421D02*
X66306D01*
G01D02*
Y580221D01*
G01D02*
X81306D01*
G01Y565421D02*
X66306D01*
G01D02*
Y572221D01*
G01D02*
X81306D01*
G01X59920Y585390D02*
X70330D01*
G01X59920Y600770D02*
Y585390D01*
G01X56020Y589419D02*
X55865Y589189D01*
X55762Y588921D01*
Y588614D01*
X55917Y588269D01*
X56175Y588001D01*
X56485Y587809D01*
X57002Y587656D01*
X57467Y587618D01*
X57932Y587694D01*
X58242Y587809D01*
X58552Y588039D01*
X58759Y588308D01*
X58862Y588576D01*
Y588844D01*
X58759Y589113D01*
X58604Y589343D01*
X58397Y589534D01*
G01Y590833D02*
X58655Y591063D01*
X58810Y591331D01*
X58862Y591676D01*
X58759Y592021D01*
X58552Y592289D01*
X58190Y592481D01*
X57777Y592519D01*
X57364Y592443D01*
X57105Y592251D01*
X56899Y591983D01*
X56847Y591714D01*
X56899Y591446D01*
X57105Y591101D01*
X55762Y591216D01*
Y592251D01*
G01X58397Y593933D02*
X58655Y594163D01*
X58810Y594431D01*
X58862Y594776D01*
X58759Y595121D01*
X58552Y595389D01*
X58190Y595581D01*
X57777Y595619D01*
X57364Y595543D01*
X57105Y595351D01*
X56899Y595083D01*
X56847Y594814D01*
X56899Y594546D01*
X57105Y594201D01*
X55762Y594316D01*
Y595351D01*
G01X56279Y597148D02*
X55969Y597378D01*
X55814Y597646D01*
X55762Y597953D01*
X55865Y598336D01*
X56124Y598604D01*
X56434Y598681D01*
X56744Y598643D01*
X57002Y598489D01*
X57519Y597723D01*
X57880Y597378D01*
X58397Y597148D01*
X58862Y597071D01*
Y598681D01*
G01X68613Y587107D02*
X65513D01*
Y588066D01*
X65668Y588372D01*
X65875Y588564D01*
X66288Y588641D01*
X66701Y588564D01*
X66960Y588334D01*
X67115Y588066D01*
Y587107D01*
G01Y588066D02*
X68613Y588641D01*
G01Y590974D02*
X65513D01*
X66133Y590514D01*
G01X68613D02*
Y591434D01*
G01X66030Y593346D02*
X65720Y593576D01*
X65565Y593844D01*
X65513Y594151D01*
X65616Y594534D01*
X65875Y594802D01*
X66185Y594879D01*
X66495Y594841D01*
X66753Y594687D01*
X67270Y593921D01*
X67631Y593576D01*
X68148Y593346D01*
X68613Y593269D01*
Y594879D01*
G01X68251Y596522D02*
X68510Y596791D01*
X68613Y597097D01*
X68510Y597404D01*
X68200Y597672D01*
X67735Y597864D01*
X67270Y597941D01*
X66701D01*
X66236Y597864D01*
X65823Y597672D01*
X65616Y597442D01*
X65513Y597174D01*
X65616Y596867D01*
X65823Y596637D01*
X66133Y596484D01*
X66546Y596407D01*
X66908Y596484D01*
X67270Y596676D01*
X67476Y596906D01*
X67528Y597174D01*
X67425Y597481D01*
X67166Y597711D01*
X66701Y597941D01*
G01X68251Y599622D02*
X68510Y599891D01*
X68613Y600197D01*
X68510Y600504D01*
X68200Y600772D01*
X67735Y600964D01*
X67270Y601041D01*
X66701D01*
X66236Y600964D01*
X65823Y600772D01*
X65616Y600542D01*
X65513Y600274D01*
X65616Y599967D01*
X65823Y599737D01*
X66133Y599584D01*
X66546Y599507D01*
X66908Y599584D01*
X67270Y599776D01*
X67476Y600006D01*
X67528Y600274D01*
X67425Y600581D01*
X67166Y600811D01*
X66701Y601041D01*
G01X64413Y587107D02*
X61313D01*
Y588066D01*
X61468Y588372D01*
X61675Y588564D01*
X62088Y588641D01*
X62501Y588564D01*
X62760Y588334D01*
X62915Y588066D01*
Y587107D01*
G01Y588066D02*
X64413Y588641D01*
G01Y590974D02*
X61313D01*
X61933Y590514D01*
G01X64413D02*
Y591434D01*
G01X61830Y593346D02*
X61520Y593576D01*
X61365Y593844D01*
X61313Y594151D01*
X61416Y594534D01*
X61675Y594802D01*
X61985Y594879D01*
X62295Y594841D01*
X62553Y594687D01*
X63070Y593921D01*
X63431Y593576D01*
X63948Y593346D01*
X64413Y593269D01*
Y594879D01*
G01X64051Y596522D02*
X64310Y596791D01*
X64413Y597097D01*
X64310Y597404D01*
X64000Y597672D01*
X63535Y597864D01*
X63070Y597941D01*
X62501D01*
X62036Y597864D01*
X61623Y597672D01*
X61416Y597442D01*
X61313Y597174D01*
X61416Y596867D01*
X61623Y596637D01*
X61933Y596484D01*
X62346Y596407D01*
X62708Y596484D01*
X63070Y596676D01*
X63276Y596906D01*
X63328Y597174D01*
X63225Y597481D01*
X62966Y597711D01*
X62501Y597941D01*
G01X64413Y600274D02*
X64361Y600542D01*
X64206Y600849D01*
X63948Y601041D01*
X63586Y601117D01*
X63225Y601041D01*
X62915Y600811D01*
X62760Y600466D01*
Y600082D01*
X62656Y599852D01*
X62398Y599661D01*
X62036Y599584D01*
X61675Y599699D01*
X61416Y599967D01*
X61313Y600274D01*
X61416Y600581D01*
X61675Y600849D01*
X62036Y600964D01*
X62398Y600887D01*
X62656Y600696D01*
X62760Y600466D01*
Y600082D01*
X62915Y599737D01*
X63225Y599507D01*
X63586Y599431D01*
X63948Y599507D01*
X64206Y599699D01*
X64361Y600006D01*
X64413Y600274D01*
G01X58956Y640232D02*
Y622832D01*
G01X59633Y621007D02*
Y617807D01*
G01Y616507D02*
Y613307D01*
G01X60672Y633223D02*
X60517Y632993D01*
X60414Y632725D01*
Y632418D01*
X60569Y632073D01*
X60827Y631805D01*
X61137Y631613D01*
X61654Y631460D01*
X62119Y631422D01*
X62584Y631498D01*
X62894Y631613D01*
X63204Y631843D01*
X63411Y632112D01*
X63514Y632380D01*
Y632648D01*
X63411Y632917D01*
X63256Y633147D01*
X63049Y633338D01*
G01Y634637D02*
X63307Y634867D01*
X63462Y635135D01*
X63514Y635480D01*
X63411Y635825D01*
X63204Y636093D01*
X62842Y636285D01*
X62429Y636323D01*
X62016Y636247D01*
X61757Y636055D01*
X61551Y635787D01*
X61499Y635518D01*
X61551Y635250D01*
X61757Y634905D01*
X60414Y635020D01*
Y636055D01*
G01X63514Y639040D02*
X60414D01*
X62636Y637622D01*
Y639538D01*
G01X60414Y641680D02*
X60517Y641373D01*
X60776Y641143D01*
X61086Y640990D01*
X61499Y640875D01*
X61964Y640837D01*
X62429Y640875D01*
X62842Y640990D01*
X63152Y641143D01*
X63411Y641373D01*
X63514Y641680D01*
X63411Y641987D01*
X63152Y642217D01*
X62842Y642370D01*
X62429Y642485D01*
X61964Y642523D01*
X61499Y642485D01*
X61086Y642370D01*
X60776Y642217D01*
X60517Y641987D01*
X60414Y641680D01*
G01X58426Y645528D02*
Y642328D01*
G01Y650028D02*
Y646828D01*
G01X66087Y668017D02*
Y665795D01*
X66240Y665330D01*
X66547Y665020D01*
X66930Y664917D01*
X67313Y665020D01*
X67620Y665330D01*
X67773Y665795D01*
Y668017D01*
G01X70030Y664917D02*
Y668017D01*
X69570Y667397D01*
G01Y664917D02*
X70490D01*
G01X72287Y665537D02*
X72517Y665175D01*
X72823Y664969D01*
X73168Y664917D01*
X73475Y664969D01*
X73782Y665227D01*
X73973Y665537D01*
X74012Y665847D01*
X73935Y666209D01*
X73667Y666467D01*
X73398Y666570D01*
X73053D01*
G01X73398D02*
X73628Y666725D01*
X73820Y666984D01*
X73897Y667294D01*
X73820Y667604D01*
X73628Y667862D01*
X73283Y668017D01*
X72938Y667965D01*
X72593Y667759D01*
G01X76153Y664917D02*
X76230Y665589D01*
X76345Y666157D01*
X76498Y666674D01*
X76690Y667242D01*
X76997Y668017D01*
X75463D01*
G01X86920Y37274D02*
X83820D01*
Y38233D01*
X83975Y38539D01*
X84182Y38731D01*
X84595Y38808D01*
X85008Y38731D01*
X85267Y38501D01*
X85422Y38233D01*
Y37274D01*
G01Y38233D02*
X86920Y38808D01*
G01Y41141D02*
X86868Y41409D01*
X86713Y41716D01*
X86455Y41908D01*
X86093Y41984D01*
X85732Y41908D01*
X85422Y41678D01*
X85267Y41333D01*
Y40949D01*
X85163Y40719D01*
X84905Y40528D01*
X84543Y40451D01*
X84182Y40566D01*
X83923Y40834D01*
X83820Y41141D01*
X83923Y41448D01*
X84182Y41716D01*
X84543Y41831D01*
X84905Y41754D01*
X85163Y41563D01*
X85267Y41333D01*
Y40949D01*
X85422Y40604D01*
X85732Y40374D01*
X86093Y40298D01*
X86455Y40374D01*
X86713Y40566D01*
X86868Y40873D01*
X86920Y41141D01*
G01X83820Y44241D02*
X83923Y43934D01*
X84182Y43704D01*
X84492Y43551D01*
X84905Y43436D01*
X85370Y43398D01*
X85835Y43436D01*
X86248Y43551D01*
X86558Y43704D01*
X86817Y43934D01*
X86920Y44241D01*
X86817Y44548D01*
X86558Y44778D01*
X86248Y44931D01*
X85835Y45046D01*
X85370Y45084D01*
X84905Y45046D01*
X84492Y44931D01*
X84182Y44778D01*
X83923Y44548D01*
X83820Y44241D01*
G01X86920Y47341D02*
X86868Y47609D01*
X86713Y47916D01*
X86455Y48108D01*
X86093Y48184D01*
X85732Y48108D01*
X85422Y47878D01*
X85267Y47533D01*
Y47149D01*
X85163Y46919D01*
X84905Y46728D01*
X84543Y46651D01*
X84182Y46766D01*
X83923Y47034D01*
X83820Y47341D01*
X83923Y47648D01*
X84182Y47916D01*
X84543Y48031D01*
X84905Y47954D01*
X85163Y47763D01*
X85267Y47533D01*
Y47149D01*
X85422Y46804D01*
X85732Y46574D01*
X86093Y46498D01*
X86455Y46574D01*
X86713Y46766D01*
X86868Y47073D01*
X86920Y47341D01*
G01X80960Y44601D02*
Y38401D01*
G01D02*
X77760D01*
G01D02*
Y44601D01*
G01D02*
X80960D01*
G01X73220Y133425D02*
Y136525D01*
X72760Y135905D01*
G01Y133425D02*
X73680D01*
G01X82033Y132131D02*
X82225Y131821D01*
X82455Y131614D01*
X82723Y131511D01*
X83030Y131614D01*
X83260Y131821D01*
X83490Y132131D01*
X83567Y132544D01*
Y134611D01*
G01X85057Y132131D02*
X85287Y131769D01*
X85593Y131563D01*
X85938Y131511D01*
X86245Y131563D01*
X86552Y131821D01*
X86743Y132131D01*
X86782Y132441D01*
X86705Y132803D01*
X86437Y133061D01*
X86168Y133164D01*
X85823D01*
G01X86168D02*
X86398Y133319D01*
X86590Y133578D01*
X86667Y133888D01*
X86590Y134198D01*
X86398Y134456D01*
X86053Y134611D01*
X85708Y134559D01*
X85363Y134353D01*
G01X89460Y131511D02*
Y134611D01*
X88042Y132389D01*
X89958D01*
G01X71093Y138269D02*
X92667D01*
G01X71093D02*
X71289D01*
G01X71093Y148269D02*
Y138269D01*
G01X92667Y148269D02*
X71093D01*
G01X78826Y156101D02*
Y153879D01*
X78979Y153414D01*
X79286Y153104D01*
X79669Y153001D01*
X80052Y153104D01*
X80359Y153414D01*
X80512Y153879D01*
Y156101D01*
G01X83229Y153001D02*
Y156101D01*
X81811Y153879D01*
X83727D01*
G01X85141Y154293D02*
X85409Y154654D01*
X85639Y154861D01*
X85946Y154964D01*
X86214Y154861D01*
X86406Y154654D01*
X86559Y154344D01*
X86597Y153983D01*
X86559Y153673D01*
X86406Y153363D01*
X86176Y153104D01*
X85907Y153001D01*
X85601Y153104D01*
X85332Y153414D01*
X85179Y153879D01*
X85141Y154396D01*
X85217Y155068D01*
X85332Y155429D01*
X85524Y155791D01*
X85792Y156049D01*
X86061Y156101D01*
X86329Y155998D01*
X86521Y155739D01*
G01X73173Y151566D02*
X73333Y151274D01*
X73547Y151108D01*
X73787Y151066D01*
X74000Y151108D01*
X74213Y151316D01*
X74347Y151566D01*
X74373Y151816D01*
X74320Y152108D01*
X74133Y152316D01*
X73947Y152399D01*
X73707D01*
G01X73947D02*
X74107Y152524D01*
X74240Y152733D01*
X74293Y152983D01*
X74240Y153233D01*
X74107Y153441D01*
X73867Y153566D01*
X73627Y153524D01*
X73387Y153358D01*
G01X72750Y156270D02*
Y174130D01*
G01X71640Y156270D02*
X72750D01*
G01X83463Y173316D02*
X83623Y173566D01*
X83810Y173691D01*
X84023Y173733D01*
X84290Y173650D01*
X84477Y173441D01*
X84530Y173191D01*
X84503Y172941D01*
X84397Y172733D01*
X83863Y172316D01*
X83623Y172025D01*
X83463Y171608D01*
X83410Y171233D01*
X84530D01*
G01X73110Y157077D02*
Y170077D01*
G01D02*
X88110D01*
G01Y157077D02*
X73110D01*
G01X73220Y171005D02*
Y174205D01*
G01X79420Y171005D02*
X73220D01*
G01X79420Y174205D02*
Y171005D01*
G01X72345Y174711D02*
Y168511D01*
G01X74260Y185780D02*
X73800D01*
G01X74260Y202600D02*
Y185780D01*
G01X73800Y174130D02*
Y185780D01*
G01X72750Y174130D02*
X73800D01*
G01X75594Y177344D02*
X75754Y177052D01*
X75968Y176886D01*
X76208Y176844D01*
X76421Y176886D01*
X76634Y177094D01*
X76768Y177344D01*
X76794Y177594D01*
X76741Y177886D01*
X76554Y178094D01*
X76368Y178177D01*
X76128D01*
G01X76368D02*
X76528Y178302D01*
X76661Y178511D01*
X76714Y178761D01*
X76661Y179011D01*
X76528Y179219D01*
X76288Y179344D01*
X76048Y179302D01*
X75808Y179136D01*
G01X89844Y175467D02*
X74844D01*
G01D02*
Y188467D01*
G01X73220Y174205D02*
X79420D01*
G01X70130Y182269D02*
X73330D01*
G01X70130Y176069D02*
Y182269D01*
G01X73330Y176069D02*
X70130D01*
G01X73330Y182269D02*
Y176069D01*
G01X96700Y202600D02*
X74260D01*
G01X76697Y203024D02*
X76989Y203184D01*
X77155Y203398D01*
X77197Y203638D01*
X77155Y203851D01*
X76947Y204064D01*
X76697Y204198D01*
X76447Y204224D01*
X76155Y204171D01*
X75947Y203984D01*
X75864Y203798D01*
Y203558D01*
G01Y203798D02*
X75739Y203958D01*
X75530Y204091D01*
X75280Y204144D01*
X75030Y204091D01*
X74822Y203958D01*
X74697Y203718D01*
X74739Y203478D01*
X74905Y203238D01*
G01X89844Y189233D02*
X74844D01*
G01D02*
Y202233D01*
G01D02*
X89844D01*
G01X74844Y188467D02*
X89844D01*
G01X74180Y203309D02*
Y193109D01*
G01X74160Y190546D02*
Y187346D01*
G01X93833Y217234D02*
X78833D01*
G01D02*
Y230234D01*
G01X76711Y209640D02*
X76871Y209348D01*
X77085Y209182D01*
X77325Y209140D01*
X77538Y209182D01*
X77751Y209390D01*
X77885Y209640D01*
X77911Y209890D01*
X77858Y210182D01*
X77671Y210390D01*
X77485Y210473D01*
X77245D01*
G01X77485D02*
X77645Y210598D01*
X77778Y210807D01*
X77831Y211057D01*
X77778Y211307D01*
X77645Y211515D01*
X77405Y211640D01*
X77165Y211598D01*
X76925Y211432D01*
G01X93773Y203352D02*
X78773D01*
G01D02*
Y216352D01*
G01D02*
X93773D01*
G01X70178Y210501D02*
Y216701D01*
G01D02*
X73378D01*
G01D02*
Y210501D01*
G01D02*
X70178D01*
G01X70158Y217389D02*
Y223589D01*
G01X73358D02*
Y217389D01*
G01D02*
X70158D01*
G01X78450Y226620D02*
Y235720D01*
G01X80150Y231607D02*
Y234107D01*
X79830Y233607D01*
G01Y231607D02*
X80470D01*
G01X77584Y240420D02*
Y227420D01*
G01X75411Y221418D02*
X75571Y221126D01*
X75785Y220960D01*
X76025Y220918D01*
X76238Y220960D01*
X76451Y221168D01*
X76585Y221418D01*
X76611Y221668D01*
X76558Y221960D01*
X76371Y222168D01*
X76185Y222251D01*
X75945D01*
G01X76185D02*
X76345Y222376D01*
X76478Y222585D01*
X76531Y222835D01*
X76478Y223085D01*
X76345Y223293D01*
X76105Y223418D01*
X75865Y223376D01*
X75625Y223210D01*
G01X78833Y230234D02*
X93833D01*
G01X83885Y234361D02*
Y231361D01*
G01X80785Y234461D02*
X86985D01*
G01X80785Y231261D02*
Y234461D01*
G01X86985Y231261D02*
X80785D01*
G01X70158Y223589D02*
X73358D01*
G01X78450Y235720D02*
X103640D01*
G01X78051Y239044D02*
X78211Y239294D01*
X78398Y239419D01*
X78611Y239461D01*
X78878Y239378D01*
X79065Y239169D01*
X79118Y238919D01*
X79091Y238669D01*
X78985Y238461D01*
X78451Y238044D01*
X78211Y237753D01*
X78051Y237336D01*
X77998Y236961D01*
X79118D01*
G01X81109Y240206D02*
Y237984D01*
X81262Y237519D01*
X81569Y237209D01*
X81952Y237106D01*
X82335Y237209D01*
X82642Y237519D01*
X82795Y237984D01*
Y240206D01*
G01X84209Y237571D02*
X84439Y237313D01*
X84707Y237158D01*
X85052Y237106D01*
X85397Y237209D01*
X85665Y237416D01*
X85857Y237778D01*
X85895Y238191D01*
X85819Y238604D01*
X85627Y238863D01*
X85359Y239069D01*
X85090Y239121D01*
X84822Y239069D01*
X84477Y238863D01*
X84592Y240206D01*
X85627D01*
G01X88152D02*
X87845Y240103D01*
X87615Y239844D01*
X87462Y239534D01*
X87347Y239121D01*
X87309Y238656D01*
X87347Y238191D01*
X87462Y237778D01*
X87615Y237468D01*
X87845Y237209D01*
X88152Y237106D01*
X88459Y237209D01*
X88689Y237468D01*
X88842Y237778D01*
X88957Y238191D01*
X88995Y238656D01*
X88957Y239121D01*
X88842Y239534D01*
X88689Y239844D01*
X88459Y240103D01*
X88152Y240206D01*
G01X78769Y249154D02*
Y255354D01*
G01X81969Y249154D02*
X78769D01*
G01X81969Y255354D02*
Y249154D01*
G01X81991Y241784D02*
X78791D01*
G01X81991Y247984D02*
Y241784D01*
G01X78791Y247984D02*
X81991D01*
G01X78791Y241784D02*
Y247984D01*
G01X79941Y240583D02*
X80474D01*
Y239833D01*
X80314Y239583D01*
X80128Y239416D01*
X79861Y239333D01*
X79594Y239416D01*
X79408Y239583D01*
X79248Y239833D01*
X79141Y240125D01*
X79088Y240458D01*
Y240750D01*
X79141Y241000D01*
X79248Y241291D01*
X79408Y241541D01*
X79568Y241708D01*
X79781Y241833D01*
X79968D01*
X80181Y241750D01*
X80341Y241583D01*
G01X86568Y246497D02*
X86516Y246190D01*
X86310Y245922D01*
X86000Y245692D01*
X85638Y245539D01*
X85225Y245462D01*
X84811D01*
X84398Y245539D01*
X84036Y245692D01*
X83726Y245922D01*
X83520Y246190D01*
X83468Y246497D01*
X83520Y246804D01*
X83726Y247072D01*
X84036Y247302D01*
X84398Y247455D01*
X84811Y247532D01*
X85225D01*
X85638Y247455D01*
X86000Y247302D01*
X86310Y247072D01*
X86516Y246804D01*
X86568Y246497D01*
G01X85741Y246804D02*
X86568Y247264D01*
G01Y249597D02*
X83468D01*
X84088Y249137D01*
G01X86568D02*
Y250057D01*
G01Y252620D02*
X85896Y252697D01*
X85328Y252812D01*
X84811Y252965D01*
X84243Y253157D01*
X83468Y253464D01*
Y251930D01*
G01X77874Y254444D02*
Y241444D01*
G01X78437Y264405D02*
Y262183D01*
X78590Y261718D01*
X78897Y261408D01*
X79280Y261305D01*
X79663Y261408D01*
X79970Y261718D01*
X80123Y262183D01*
Y264405D01*
G01X82840Y261305D02*
Y264405D01*
X81422Y262183D01*
X83338D01*
G01X84828Y261667D02*
X85097Y261408D01*
X85403Y261305D01*
X85710Y261408D01*
X85978Y261718D01*
X86170Y262183D01*
X86247Y262648D01*
Y263217D01*
X86170Y263682D01*
X85978Y264095D01*
X85748Y264302D01*
X85480Y264405D01*
X85173Y264302D01*
X84943Y264095D01*
X84790Y263785D01*
X84713Y263372D01*
X84790Y263010D01*
X84982Y262648D01*
X85212Y262442D01*
X85480Y262390D01*
X85787Y262493D01*
X86017Y262752D01*
X86247Y263217D01*
G01X77296Y270679D02*
Y255679D01*
G01X83751Y266383D02*
X83911Y266091D01*
X84125Y265925D01*
X84365Y265883D01*
X84578Y265925D01*
X84791Y266133D01*
X84925Y266383D01*
X84951Y266633D01*
X84898Y266925D01*
X84711Y267133D01*
X84525Y267216D01*
X84285D01*
G01X84525D02*
X84685Y267341D01*
X84818Y267550D01*
X84871Y267800D01*
X84818Y268050D01*
X84685Y268258D01*
X84445Y268383D01*
X84205Y268341D01*
X83965Y268175D01*
G01X78769Y255354D02*
X81969D01*
G01X80020Y272847D02*
Y275347D01*
X79700Y274847D01*
G01Y272847D02*
X80340D01*
G01X79668Y281110D02*
X79828Y281360D01*
X80015Y281485D01*
X80228Y281527D01*
X80495Y281444D01*
X80682Y281235D01*
X80735Y280985D01*
X80708Y280735D01*
X80602Y280527D01*
X80068Y280110D01*
X79828Y279819D01*
X79668Y279402D01*
X79615Y279027D01*
X80735D01*
G01X93199Y269238D02*
X81231D01*
G01D02*
Y281838D01*
G01X76768Y285757D02*
Y271557D01*
G01X81231Y281838D02*
X93199D01*
G01X73868Y292157D02*
X70868D01*
G01X73968Y289057D02*
X70768D01*
G01X73968Y295257D02*
Y289057D01*
G01X70768Y295257D02*
X73968D01*
G01X70768Y289057D02*
Y295257D01*
G01X80868Y292157D02*
X83868D01*
G01X80768Y295257D02*
X83968D01*
G01X80768Y289057D02*
Y295257D01*
G01X83968Y289057D02*
X80768D01*
G01X83968Y295257D02*
Y289057D01*
G01X74868Y287057D02*
X79868D01*
G01Y297257D02*
Y287057D01*
G01X74868D02*
Y297257D01*
G01X75068Y292657D02*
X79668D01*
G01X74868Y297257D02*
X79868D01*
G01X75068Y291657D02*
X79668D01*
G01X80078Y282926D02*
Y286026D01*
X81534D01*
G01X80998Y284528D02*
X80078D01*
G01X83101Y283339D02*
X83408Y283081D01*
X83753Y282926D01*
X84059D01*
X84366Y283081D01*
X84596Y283339D01*
X84711Y283701D01*
X84634Y284063D01*
X84443Y284373D01*
X84098Y284579D01*
X83638Y284683D01*
X83369Y284889D01*
X83254Y285251D01*
X83331Y285613D01*
X83523Y285871D01*
X83791Y286026D01*
X84059D01*
X84328Y285923D01*
X84558Y285664D01*
G01X86278Y285509D02*
X86508Y285819D01*
X86776Y285974D01*
X87083Y286026D01*
X87466Y285923D01*
X87734Y285664D01*
X87811Y285354D01*
X87773Y285044D01*
X87619Y284786D01*
X86853Y284269D01*
X86508Y283908D01*
X86278Y283391D01*
X86201Y282926D01*
X87811D01*
G01X70634Y300830D02*
X70479Y300600D01*
X70376Y300332D01*
Y300025D01*
X70531Y299680D01*
X70789Y299412D01*
X71099Y299220D01*
X71616Y299067D01*
X72081Y299029D01*
X72546Y299105D01*
X72856Y299220D01*
X73166Y299450D01*
X73373Y299719D01*
X73476Y299987D01*
Y300255D01*
X73373Y300524D01*
X73218Y300754D01*
X73011Y300945D01*
G01X73476Y303547D02*
X70376D01*
X72598Y302129D01*
Y304045D01*
G01X73114Y305535D02*
X73373Y305804D01*
X73476Y306110D01*
X73373Y306417D01*
X73063Y306685D01*
X72598Y306877D01*
X72133Y306954D01*
X71564D01*
X71099Y306877D01*
X70686Y306685D01*
X70479Y306455D01*
X70376Y306187D01*
X70479Y305880D01*
X70686Y305650D01*
X70996Y305497D01*
X71409Y305420D01*
X71771Y305497D01*
X72133Y305689D01*
X72339Y305919D01*
X72391Y306187D01*
X72288Y306494D01*
X72029Y306724D01*
X71564Y306954D01*
G01X73476Y309287D02*
X73424Y309555D01*
X73269Y309862D01*
X73011Y310054D01*
X72649Y310130D01*
X72288Y310054D01*
X71978Y309824D01*
X71823Y309479D01*
Y309095D01*
X71719Y308865D01*
X71461Y308674D01*
X71099Y308597D01*
X70738Y308712D01*
X70479Y308980D01*
X70376Y309287D01*
X70479Y309594D01*
X70738Y309862D01*
X71099Y309977D01*
X71461Y309900D01*
X71719Y309709D01*
X71823Y309479D01*
Y309095D01*
X71978Y308750D01*
X72288Y308520D01*
X72649Y308444D01*
X73011Y308520D01*
X73269Y308712D01*
X73424Y309019D01*
X73476Y309287D01*
G01X80932Y300841D02*
X80777Y300611D01*
X80674Y300343D01*
Y300036D01*
X80829Y299691D01*
X81087Y299423D01*
X81397Y299231D01*
X81914Y299078D01*
X82379Y299040D01*
X82844Y299116D01*
X83154Y299231D01*
X83464Y299461D01*
X83671Y299730D01*
X83774Y299998D01*
Y300266D01*
X83671Y300535D01*
X83516Y300765D01*
X83309Y300956D01*
G01X83774Y303558D02*
X80674D01*
X82896Y302140D01*
Y304056D01*
G01X83412Y305546D02*
X83671Y305815D01*
X83774Y306121D01*
X83671Y306428D01*
X83361Y306696D01*
X82896Y306888D01*
X82431Y306965D01*
X81862D01*
X81397Y306888D01*
X80984Y306696D01*
X80777Y306466D01*
X80674Y306198D01*
X80777Y305891D01*
X80984Y305661D01*
X81294Y305508D01*
X81707Y305431D01*
X82069Y305508D01*
X82431Y305700D01*
X82637Y305930D01*
X82689Y306198D01*
X82586Y306505D01*
X82327Y306735D01*
X81862Y306965D01*
G01X83774Y309221D02*
X83102Y309298D01*
X82534Y309413D01*
X82017Y309566D01*
X81449Y309758D01*
X80674Y310065D01*
Y308531D01*
G01X75493Y301037D02*
X78593D01*
Y302571D01*
G01X77973Y304061D02*
X78335Y304291D01*
X78541Y304597D01*
X78593Y304942D01*
X78541Y305249D01*
X78283Y305556D01*
X77973Y305747D01*
X77663Y305786D01*
X77301Y305709D01*
X77043Y305441D01*
X76940Y305172D01*
Y304827D01*
G01Y305172D02*
X76785Y305402D01*
X76526Y305594D01*
X76216Y305671D01*
X75906Y305594D01*
X75648Y305402D01*
X75493Y305057D01*
X75545Y304712D01*
X75751Y304367D01*
G01X78593Y308004D02*
X78541Y308272D01*
X78386Y308579D01*
X78128Y308771D01*
X77766Y308847D01*
X77405Y308771D01*
X77095Y308541D01*
X76940Y308196D01*
Y307812D01*
X76836Y307582D01*
X76578Y307391D01*
X76216Y307314D01*
X75855Y307429D01*
X75596Y307697D01*
X75493Y308004D01*
X75596Y308311D01*
X75855Y308579D01*
X76216Y308694D01*
X76578Y308617D01*
X76836Y308426D01*
X76940Y308196D01*
Y307812D01*
X77095Y307467D01*
X77405Y307237D01*
X77766Y307161D01*
X78128Y307237D01*
X78386Y307429D01*
X78541Y307736D01*
X78593Y308004D01*
G01X103351Y388368D02*
X83551D01*
G01D02*
Y399568D01*
G01X81599Y391221D02*
Y388021D01*
G01X75399Y391221D02*
X81599D01*
G01X75399Y388021D02*
Y391221D01*
G01X81599Y388021D02*
X75399D01*
G01X81599Y387322D02*
Y384122D01*
G01X75399Y387322D02*
X81599D01*
G01X75399Y384122D02*
Y387322D01*
G01X81599Y384122D02*
X75399D01*
G01X83551Y399568D02*
X103351D01*
G01X81619Y395457D02*
Y392257D01*
G01X75419Y395457D02*
X81619D01*
G01X75419Y392257D02*
Y395457D01*
G01X81619Y392257D02*
X75419D01*
G01X81619Y399513D02*
Y396313D01*
G01X75419Y399513D02*
X81619D01*
G01X75419Y396313D02*
Y399513D01*
G01X81619Y396313D02*
X75419D01*
G01X77738Y431488D02*
Y413772D01*
G01X83260Y430713D02*
Y429193D01*
G01X84343Y430016D02*
X82176D01*
G01X77738Y450304D02*
Y432588D01*
G01X83230Y448337D02*
Y446817D01*
G01X84313Y447640D02*
X82146D01*
G01X81183Y499524D02*
Y498618D01*
G01Y488618D02*
Y487712D01*
G01X70678Y517284D02*
Y519784D01*
X70358Y519284D01*
G01Y517284D02*
X70998D01*
G01X72371Y518326D02*
X72558Y518617D01*
X72718Y518784D01*
X72931Y518867D01*
X73118Y518784D01*
X73251Y518617D01*
X73358Y518367D01*
X73385Y518076D01*
X73358Y517826D01*
X73251Y517576D01*
X73091Y517367D01*
X72905Y517284D01*
X72691Y517367D01*
X72505Y517617D01*
X72398Y517992D01*
X72371Y518409D01*
X72425Y518951D01*
X72505Y519242D01*
X72638Y519534D01*
X72825Y519742D01*
X73011Y519784D01*
X73198Y519701D01*
X73331Y519492D01*
G01X83923Y512623D02*
Y515723D01*
X84843D01*
X85150Y515568D01*
X85380Y515206D01*
X85457Y514793D01*
X85380Y514380D01*
X85188Y514070D01*
X84843Y513915D01*
X83923D01*
G01X88633Y515465D02*
X88403Y515620D01*
X88135Y515723D01*
X87828D01*
X87483Y515568D01*
X87215Y515310D01*
X87023Y515000D01*
X86870Y514483D01*
X86832Y514018D01*
X86908Y513553D01*
X87023Y513243D01*
X87253Y512933D01*
X87522Y512726D01*
X87790Y512623D01*
X88058D01*
X88327Y512726D01*
X88557Y512881D01*
X88748Y513088D01*
G01X90162Y513915D02*
X90430Y514276D01*
X90660Y514483D01*
X90967Y514586D01*
X91235Y514483D01*
X91427Y514276D01*
X91580Y513966D01*
X91618Y513605D01*
X91580Y513295D01*
X91427Y512985D01*
X91197Y512726D01*
X90928Y512623D01*
X90622Y512726D01*
X90353Y513036D01*
X90200Y513501D01*
X90162Y514018D01*
X90238Y514690D01*
X90353Y515051D01*
X90545Y515413D01*
X90813Y515671D01*
X91082Y515723D01*
X91350Y515620D01*
X91542Y515361D01*
G01X93262Y515206D02*
X93492Y515516D01*
X93760Y515671D01*
X94067Y515723D01*
X94450Y515620D01*
X94718Y515361D01*
X94795Y515051D01*
X94757Y514741D01*
X94603Y514483D01*
X93837Y513966D01*
X93492Y513605D01*
X93262Y513088D01*
X93185Y512623D01*
X94795D01*
G01X80760Y514704D02*
Y511504D01*
G01X74560D02*
Y514704D01*
G01X80760Y511504D02*
X74560D01*
G01X77660Y514604D02*
Y511604D01*
G01X74560Y514704D02*
X80760D01*
G01X77173Y502469D02*
X73973D01*
G01X77173Y508669D02*
Y502469D01*
G01X73973Y508669D02*
X77173D01*
G01X73973Y502469D02*
Y508669D01*
G01X77073Y505569D02*
X74073D01*
G01X83923Y516623D02*
Y519723D01*
X84843D01*
X85150Y519568D01*
X85380Y519206D01*
X85457Y518793D01*
X85380Y518380D01*
X85188Y518070D01*
X84843Y517915D01*
X83923D01*
G01X87023Y516623D02*
Y519723D01*
X87982D01*
X88288Y519568D01*
X88480Y519361D01*
X88557Y518948D01*
X88480Y518535D01*
X88250Y518276D01*
X87982Y518121D01*
X87023D01*
G01X87982D02*
X88557Y516623D01*
G01X90162Y519206D02*
X90392Y519516D01*
X90660Y519671D01*
X90967Y519723D01*
X91350Y519620D01*
X91618Y519361D01*
X91695Y519051D01*
X91657Y518741D01*
X91503Y518483D01*
X90737Y517966D01*
X90392Y517605D01*
X90162Y517088D01*
X90085Y516623D01*
X91695D01*
G01X93262Y517915D02*
X93530Y518276D01*
X93760Y518483D01*
X94067Y518586D01*
X94335Y518483D01*
X94527Y518276D01*
X94680Y517966D01*
X94718Y517605D01*
X94680Y517295D01*
X94527Y516985D01*
X94297Y516726D01*
X94028Y516623D01*
X93722Y516726D01*
X93453Y517036D01*
X93300Y517501D01*
X93262Y518018D01*
X93338Y518690D01*
X93453Y519051D01*
X93645Y519413D01*
X93913Y519671D01*
X94182Y519723D01*
X94450Y519620D01*
X94642Y519361D01*
G01X80760Y518704D02*
Y515504D01*
G01X74560D02*
Y518704D01*
G01X80760Y515504D02*
X74560D01*
G01X78768Y510695D02*
X81968D01*
G01X78768Y504495D02*
Y510695D01*
G01X81968Y504495D02*
X78768D01*
G01X81968Y510695D02*
Y504495D01*
G01X74764Y523803D02*
X71664D01*
Y524723D01*
X71819Y525030D01*
X72181Y525260D01*
X72594Y525337D01*
X73007Y525260D01*
X73317Y525068D01*
X73472Y524723D01*
Y523803D01*
G01X71664Y526827D02*
X73886D01*
X74351Y526980D01*
X74661Y527287D01*
X74764Y527670D01*
X74661Y528053D01*
X74351Y528360D01*
X73886Y528513D01*
X71664D01*
G01X73472Y530042D02*
X73111Y530310D01*
X72904Y530540D01*
X72801Y530847D01*
X72904Y531115D01*
X73111Y531307D01*
X73421Y531460D01*
X73782Y531498D01*
X74092Y531460D01*
X74402Y531307D01*
X74661Y531077D01*
X74764Y530808D01*
X74661Y530502D01*
X74351Y530233D01*
X73886Y530080D01*
X73369Y530042D01*
X72697Y530118D01*
X72336Y530233D01*
X71974Y530425D01*
X71716Y530693D01*
X71664Y530962D01*
X71767Y531230D01*
X72026Y531422D01*
G01X82263Y527709D02*
X82033Y527864D01*
X81765Y527967D01*
X81458D01*
X81113Y527812D01*
X80845Y527554D01*
X80653Y527244D01*
X80500Y526727D01*
X80462Y526262D01*
X80538Y525797D01*
X80653Y525487D01*
X80883Y525177D01*
X81152Y524970D01*
X81420Y524867D01*
X81688D01*
X81957Y524970D01*
X82187Y525125D01*
X82378Y525332D01*
G01X84980Y524867D02*
Y527967D01*
X83562Y525745D01*
X85478D01*
G01X86777Y525487D02*
X87007Y525125D01*
X87313Y524919D01*
X87658Y524867D01*
X87965Y524919D01*
X88272Y525177D01*
X88463Y525487D01*
X88502Y525797D01*
X88425Y526159D01*
X88157Y526417D01*
X87888Y526520D01*
X87543D01*
G01X87888D02*
X88118Y526675D01*
X88310Y526934D01*
X88387Y527244D01*
X88310Y527554D01*
X88118Y527812D01*
X87773Y527967D01*
X87428Y527915D01*
X87083Y527709D01*
G01X89877Y525487D02*
X90107Y525125D01*
X90413Y524919D01*
X90758Y524867D01*
X91065Y524919D01*
X91372Y525177D01*
X91563Y525487D01*
X91602Y525797D01*
X91525Y526159D01*
X91257Y526417D01*
X90988Y526520D01*
X90643D01*
G01X90988D02*
X91218Y526675D01*
X91410Y526934D01*
X91487Y527244D01*
X91410Y527554D01*
X91218Y527812D01*
X90873Y527967D01*
X90528Y527915D01*
X90183Y527709D01*
G01X93829Y532902D02*
X83629D01*
G01D02*
Y537502D01*
G01X82366Y531637D02*
X82136Y531792D01*
X81868Y531895D01*
X81561D01*
X81216Y531740D01*
X80948Y531482D01*
X80756Y531172D01*
X80603Y530655D01*
X80565Y530190D01*
X80641Y529725D01*
X80756Y529415D01*
X80986Y529105D01*
X81255Y528898D01*
X81523Y528795D01*
X81791D01*
X82060Y528898D01*
X82290Y529053D01*
X82481Y529260D01*
G01X85083Y528795D02*
Y531895D01*
X83665Y529673D01*
X85581D01*
G01X86880Y529415D02*
X87110Y529053D01*
X87416Y528847D01*
X87761Y528795D01*
X88068Y528847D01*
X88375Y529105D01*
X88566Y529415D01*
X88605Y529725D01*
X88528Y530087D01*
X88260Y530345D01*
X87991Y530448D01*
X87646D01*
G01X87991D02*
X88221Y530603D01*
X88413Y530862D01*
X88490Y531172D01*
X88413Y531482D01*
X88221Y531740D01*
X87876Y531895D01*
X87531Y531843D01*
X87186Y531637D01*
G01X90823Y531895D02*
X90516Y531792D01*
X90286Y531533D01*
X90133Y531223D01*
X90018Y530810D01*
X89980Y530345D01*
X90018Y529880D01*
X90133Y529467D01*
X90286Y529157D01*
X90516Y528898D01*
X90823Y528795D01*
X91130Y528898D01*
X91360Y529157D01*
X91513Y529467D01*
X91628Y529880D01*
X91666Y530345D01*
X91628Y530810D01*
X91513Y531223D01*
X91360Y531533D01*
X91130Y531792D01*
X90823Y531895D01*
G01X84046Y520634D02*
Y523734D01*
X84966D01*
X85273Y523579D01*
X85503Y523217D01*
X85580Y522804D01*
X85503Y522391D01*
X85311Y522081D01*
X84966Y521926D01*
X84046D01*
G01X87146Y520634D02*
Y523734D01*
X88105D01*
X88411Y523579D01*
X88603Y523372D01*
X88680Y522959D01*
X88603Y522546D01*
X88373Y522287D01*
X88105Y522132D01*
X87146D01*
G01X88105D02*
X88680Y520634D01*
G01X90285Y523217D02*
X90515Y523527D01*
X90783Y523682D01*
X91090Y523734D01*
X91473Y523631D01*
X91741Y523372D01*
X91818Y523062D01*
X91780Y522752D01*
X91626Y522494D01*
X90860Y521977D01*
X90515Y521616D01*
X90285Y521099D01*
X90208Y520634D01*
X91818D01*
G01X94573D02*
Y523734D01*
X93155Y521512D01*
X95071D01*
G01X74560Y519504D02*
Y522704D01*
G01X80760Y519504D02*
X74560D01*
G01X80760Y522704D02*
Y519504D01*
G01X74560Y522704D02*
X80760D01*
G01X74560Y518704D02*
X80760D01*
G01X83629Y537502D02*
X93829D01*
G01X96229Y539302D02*
X81229D01*
G01D02*
Y546102D01*
G01D02*
X96229D01*
G01X81306Y564221D02*
Y557421D01*
G01X73806Y557521D02*
Y564121D01*
G01X81460Y556372D02*
Y549572D01*
G01X73960Y549672D02*
Y556272D01*
G01X83950Y557702D02*
X110350D01*
G01X83950Y570702D02*
Y557702D01*
G01X81306Y580221D02*
Y573421D01*
G01X73806Y573521D02*
Y580121D01*
G01X81306Y572221D02*
Y565421D01*
G01X73806Y565521D02*
Y572121D01*
G01X110350Y570702D02*
X83950D01*
G01X84200Y587160D02*
Y599000D01*
G01X82240Y587160D02*
X84200D01*
G01X70173Y588717D02*
X70018Y588487D01*
X69915Y588219D01*
Y587912D01*
X70070Y587567D01*
X70328Y587299D01*
X70638Y587107D01*
X71155Y586954D01*
X71620Y586916D01*
X72085Y586992D01*
X72395Y587107D01*
X72705Y587337D01*
X72912Y587606D01*
X73015Y587874D01*
Y588142D01*
X72912Y588411D01*
X72757Y588641D01*
X72550Y588832D01*
G01Y590131D02*
X72808Y590361D01*
X72963Y590629D01*
X73015Y590974D01*
X72912Y591319D01*
X72705Y591587D01*
X72343Y591779D01*
X71930Y591817D01*
X71517Y591741D01*
X71258Y591549D01*
X71052Y591281D01*
X71000Y591012D01*
X71052Y590744D01*
X71258Y590399D01*
X69915Y590514D01*
Y591549D01*
G01X72550Y593231D02*
X72808Y593461D01*
X72963Y593729D01*
X73015Y594074D01*
X72912Y594419D01*
X72705Y594687D01*
X72343Y594879D01*
X71930Y594917D01*
X71517Y594841D01*
X71258Y594649D01*
X71052Y594381D01*
X71000Y594112D01*
X71052Y593844D01*
X71258Y593499D01*
X69915Y593614D01*
Y594649D01*
G01Y597174D02*
X70018Y596867D01*
X70277Y596637D01*
X70587Y596484D01*
X71000Y596369D01*
X71465Y596331D01*
X71930Y596369D01*
X72343Y596484D01*
X72653Y596637D01*
X72912Y596867D01*
X73015Y597174D01*
X72912Y597481D01*
X72653Y597711D01*
X72343Y597864D01*
X71930Y597979D01*
X71465Y598017D01*
X71000Y597979D01*
X70587Y597864D01*
X70277Y597711D01*
X70018Y597481D01*
X69915Y597174D01*
G01X74381Y588717D02*
X74226Y588487D01*
X74123Y588219D01*
Y587912D01*
X74278Y587567D01*
X74536Y587299D01*
X74846Y587107D01*
X75363Y586954D01*
X75828Y586916D01*
X76293Y586992D01*
X76603Y587107D01*
X76913Y587337D01*
X77120Y587606D01*
X77223Y587874D01*
Y588142D01*
X77120Y588411D01*
X76965Y588641D01*
X76758Y588832D01*
G01Y590131D02*
X77016Y590361D01*
X77171Y590629D01*
X77223Y590974D01*
X77120Y591319D01*
X76913Y591587D01*
X76551Y591779D01*
X76138Y591817D01*
X75725Y591741D01*
X75466Y591549D01*
X75260Y591281D01*
X75208Y591012D01*
X75260Y590744D01*
X75466Y590399D01*
X74123Y590514D01*
Y591549D01*
G01X76758Y593231D02*
X77016Y593461D01*
X77171Y593729D01*
X77223Y594074D01*
X77120Y594419D01*
X76913Y594687D01*
X76551Y594879D01*
X76138Y594917D01*
X75725Y594841D01*
X75466Y594649D01*
X75260Y594381D01*
X75208Y594112D01*
X75260Y593844D01*
X75466Y593499D01*
X74123Y593614D01*
Y594649D01*
G01X77223Y597174D02*
X74123D01*
X74743Y596714D01*
G01X77223D02*
Y597634D01*
G01X78421Y588717D02*
X78266Y588487D01*
X78163Y588219D01*
Y587912D01*
X78318Y587567D01*
X78576Y587299D01*
X78886Y587107D01*
X79403Y586954D01*
X79868Y586916D01*
X80333Y586992D01*
X80643Y587107D01*
X80953Y587337D01*
X81160Y587606D01*
X81263Y587874D01*
Y588142D01*
X81160Y588411D01*
X81005Y588641D01*
X80798Y588832D01*
G01Y590131D02*
X81056Y590361D01*
X81211Y590629D01*
X81263Y590974D01*
X81160Y591319D01*
X80953Y591587D01*
X80591Y591779D01*
X80178Y591817D01*
X79765Y591741D01*
X79506Y591549D01*
X79300Y591281D01*
X79248Y591012D01*
X79300Y590744D01*
X79506Y590399D01*
X78163Y590514D01*
Y591549D01*
G01X81263Y594534D02*
X78163D01*
X80385Y593116D01*
Y595032D01*
G01X80901Y596522D02*
X81160Y596791D01*
X81263Y597097D01*
X81160Y597404D01*
X80850Y597672D01*
X80385Y597864D01*
X79920Y597941D01*
X79351D01*
X78886Y597864D01*
X78473Y597672D01*
X78266Y597442D01*
X78163Y597174D01*
X78266Y596867D01*
X78473Y596637D01*
X78783Y596484D01*
X79196Y596407D01*
X79558Y596484D01*
X79920Y596676D01*
X80126Y596906D01*
X80178Y597174D01*
X80075Y597481D01*
X79816Y597711D01*
X79351Y597941D01*
G01X81382Y581413D02*
X71182D01*
G01X76282Y586013D02*
Y581413D01*
G01X71182Y586013D02*
X81382D01*
G01D02*
Y581413D01*
G01X71182D02*
Y586013D01*
G01X70790Y601290D02*
X69740D01*
G01X70790Y599000D02*
Y601290D01*
G01X84200Y599000D02*
X70790D01*
G01X72075Y600705D02*
Y662123D01*
G01X79020Y600705D02*
X72075D01*
G01X86107Y607792D02*
X79020Y600705D01*
G01X72075Y662123D02*
X100139D01*
G01X88582Y-9607D02*
Y236D01*
G01X92420Y1570D02*
X195150D01*
G01X92420Y14990D02*
Y1570D01*
G01X96363Y11699D02*
X96133Y11854D01*
X95865Y11957D01*
X95558D01*
X95213Y11802D01*
X94945Y11544D01*
X94753Y11234D01*
X94600Y10717D01*
X94562Y10252D01*
X94638Y9787D01*
X94753Y9477D01*
X94983Y9167D01*
X95252Y8960D01*
X95520Y8857D01*
X95788D01*
X96057Y8960D01*
X96287Y9115D01*
X96478Y9322D01*
G01X98620Y8857D02*
X98888Y8909D01*
X99195Y9064D01*
X99387Y9322D01*
X99463Y9684D01*
X99387Y10045D01*
X99157Y10355D01*
X98812Y10510D01*
X98428D01*
X98198Y10614D01*
X98007Y10872D01*
X97930Y11234D01*
X98045Y11595D01*
X98313Y11854D01*
X98620Y11957D01*
X98927Y11854D01*
X99195Y11595D01*
X99310Y11234D01*
X99233Y10872D01*
X99042Y10614D01*
X98812Y10510D01*
X98428D01*
X98083Y10355D01*
X97853Y10045D01*
X97777Y9684D01*
X97853Y9322D01*
X98045Y9064D01*
X98352Y8909D01*
X98620Y8857D01*
G01X100877Y9322D02*
X101107Y9064D01*
X101375Y8909D01*
X101720Y8857D01*
X102065Y8960D01*
X102333Y9167D01*
X102525Y9529D01*
X102563Y9942D01*
X102487Y10355D01*
X102295Y10614D01*
X102027Y10820D01*
X101758Y10872D01*
X101490Y10820D01*
X101145Y10614D01*
X101260Y11957D01*
X102295D01*
G01X103977Y9477D02*
X104207Y9115D01*
X104513Y8909D01*
X104858Y8857D01*
X105165Y8909D01*
X105472Y9167D01*
X105663Y9477D01*
X105702Y9787D01*
X105625Y10149D01*
X105357Y10407D01*
X105088Y10510D01*
X104743D01*
G01X105088D02*
X105318Y10665D01*
X105510Y10924D01*
X105587Y11234D01*
X105510Y11544D01*
X105318Y11802D01*
X104973Y11957D01*
X104628Y11905D01*
X104283Y11699D01*
G01X93075Y4049D02*
Y7149D01*
X94034D01*
X94340Y6994D01*
X94532Y6787D01*
X94609Y6374D01*
X94532Y5961D01*
X94302Y5702D01*
X94034Y5547D01*
X93075D01*
G01X94034D02*
X94609Y4049D01*
G01X96942D02*
Y7149D01*
X96482Y6529D01*
G01Y4049D02*
X97402D01*
G01X99314Y6632D02*
X99544Y6942D01*
X99812Y7097D01*
X100119Y7149D01*
X100502Y7046D01*
X100770Y6787D01*
X100847Y6477D01*
X100809Y6167D01*
X100655Y5909D01*
X99889Y5392D01*
X99544Y5031D01*
X99314Y4514D01*
X99237Y4049D01*
X100847D01*
G01X103602D02*
Y7149D01*
X102184Y4927D01*
X104100D01*
G01X106242Y4049D02*
Y7149D01*
X105782Y6529D01*
G01Y4049D02*
X106702D01*
G01X90984Y236D02*
Y28308D01*
G01X88582Y236D02*
X90984D01*
G01X127970Y14990D02*
X92420D01*
G01X102213Y26533D02*
X99113D01*
Y27453D01*
X99268Y27760D01*
X99630Y27990D01*
X100043Y28067D01*
X100456Y27990D01*
X100766Y27798D01*
X100921Y27453D01*
Y26533D01*
G01X102213Y29633D02*
X99113D01*
Y30592D01*
X99268Y30898D01*
X99475Y31090D01*
X99888Y31167D01*
X100301Y31090D01*
X100560Y30860D01*
X100715Y30592D01*
Y29633D01*
G01Y30592D02*
X102213Y31167D01*
G01Y33960D02*
X99113D01*
X101335Y32542D01*
Y34458D01*
G01X99113Y36600D02*
X99216Y36293D01*
X99475Y36063D01*
X99785Y35910D01*
X100198Y35795D01*
X100663Y35757D01*
X101128Y35795D01*
X101541Y35910D01*
X101851Y36063D01*
X102110Y36293D01*
X102213Y36600D01*
X102110Y36907D01*
X101851Y37137D01*
X101541Y37290D01*
X101128Y37405D01*
X100663Y37443D01*
X100198Y37405D01*
X99785Y37290D01*
X99475Y37137D01*
X99216Y36907D01*
X99113Y36600D01*
G01X91720Y16656D02*
X91950Y16294D01*
X92256Y16088D01*
X92601Y16036D01*
X92908Y16088D01*
X93215Y16346D01*
X93406Y16656D01*
X93445Y16966D01*
X93368Y17328D01*
X93100Y17586D01*
X92831Y17689D01*
X92486D01*
G01X92831D02*
X93061Y17844D01*
X93253Y18103D01*
X93330Y18413D01*
X93253Y18723D01*
X93061Y18981D01*
X92716Y19136D01*
X92371Y19084D01*
X92026Y18878D01*
G01X90984Y25008D02*
Y36220D01*
G01X93722Y42101D02*
Y45201D01*
X94642D01*
X94949Y45046D01*
X95179Y44684D01*
X95256Y44271D01*
X95179Y43858D01*
X94987Y43548D01*
X94642Y43393D01*
X93722D01*
G01X96822Y42101D02*
Y45201D01*
X97781D01*
X98087Y45046D01*
X98279Y44839D01*
X98356Y44426D01*
X98279Y44013D01*
X98049Y43754D01*
X97781Y43599D01*
X96822D01*
G01X97781D02*
X98356Y42101D01*
G01X99846Y42721D02*
X100076Y42359D01*
X100382Y42153D01*
X100727Y42101D01*
X101034Y42153D01*
X101341Y42411D01*
X101532Y42721D01*
X101571Y43031D01*
X101494Y43393D01*
X101226Y43651D01*
X100957Y43754D01*
X100612D01*
G01X100957D02*
X101187Y43909D01*
X101379Y44168D01*
X101456Y44478D01*
X101379Y44788D01*
X101187Y45046D01*
X100842Y45201D01*
X100497Y45149D01*
X100152Y44943D01*
G01X103061Y43393D02*
X103329Y43754D01*
X103559Y43961D01*
X103866Y44064D01*
X104134Y43961D01*
X104326Y43754D01*
X104479Y43444D01*
X104517Y43083D01*
X104479Y42773D01*
X104326Y42463D01*
X104096Y42204D01*
X103827Y42101D01*
X103521Y42204D01*
X103252Y42514D01*
X103099Y42979D01*
X103061Y43496D01*
X103137Y44168D01*
X103252Y44529D01*
X103444Y44891D01*
X103712Y45149D01*
X103981Y45201D01*
X104249Y45098D01*
X104441Y44839D01*
G01X93722Y38182D02*
Y41282D01*
X94642D01*
X94949Y41127D01*
X95179Y40765D01*
X95256Y40352D01*
X95179Y39939D01*
X94987Y39629D01*
X94642Y39474D01*
X93722D01*
G01X96822Y38182D02*
Y41282D01*
X97781D01*
X98087Y41127D01*
X98279Y40920D01*
X98356Y40507D01*
X98279Y40094D01*
X98049Y39835D01*
X97781Y39680D01*
X96822D01*
G01X97781D02*
X98356Y38182D01*
G01X99846Y38802D02*
X100076Y38440D01*
X100382Y38234D01*
X100727Y38182D01*
X101034Y38234D01*
X101341Y38492D01*
X101532Y38802D01*
X101571Y39112D01*
X101494Y39474D01*
X101226Y39732D01*
X100957Y39835D01*
X100612D01*
G01X100957D02*
X101187Y39990D01*
X101379Y40249D01*
X101456Y40559D01*
X101379Y40869D01*
X101187Y41127D01*
X100842Y41282D01*
X100497Y41230D01*
X100152Y41024D01*
G01X103789Y38182D02*
X104057Y38234D01*
X104364Y38389D01*
X104556Y38647D01*
X104632Y39009D01*
X104556Y39370D01*
X104326Y39680D01*
X103981Y39835D01*
X103597D01*
X103367Y39939D01*
X103176Y40197D01*
X103099Y40559D01*
X103214Y40920D01*
X103482Y41179D01*
X103789Y41282D01*
X104096Y41179D01*
X104364Y40920D01*
X104479Y40559D01*
X104402Y40197D01*
X104211Y39939D01*
X103981Y39835D01*
X103597D01*
X103252Y39680D01*
X103022Y39370D01*
X102946Y39009D01*
X103022Y38647D01*
X103214Y38389D01*
X103521Y38234D01*
X103789Y38182D01*
G01X93652Y46165D02*
Y49265D01*
X94572D01*
X94879Y49110D01*
X95109Y48748D01*
X95186Y48335D01*
X95109Y47922D01*
X94917Y47612D01*
X94572Y47457D01*
X93652D01*
G01X96752Y46165D02*
Y49265D01*
X97711D01*
X98017Y49110D01*
X98209Y48903D01*
X98286Y48490D01*
X98209Y48077D01*
X97979Y47818D01*
X97711Y47663D01*
X96752D01*
G01X97711D02*
X98286Y46165D01*
G01X99776Y46785D02*
X100006Y46423D01*
X100312Y46217D01*
X100657Y46165D01*
X100964Y46217D01*
X101271Y46475D01*
X101462Y46785D01*
X101501Y47095D01*
X101424Y47457D01*
X101156Y47715D01*
X100887Y47818D01*
X100542D01*
G01X100887D02*
X101117Y47973D01*
X101309Y48232D01*
X101386Y48542D01*
X101309Y48852D01*
X101117Y49110D01*
X100772Y49265D01*
X100427Y49213D01*
X100082Y49007D01*
G01X104179Y46165D02*
Y49265D01*
X102761Y47043D01*
X104677D01*
G01X91924Y34990D02*
X92154Y35300D01*
X92422Y35455D01*
X92729Y35507D01*
X93112Y35404D01*
X93380Y35145D01*
X93457Y34835D01*
X93419Y34525D01*
X93265Y34267D01*
X92499Y33750D01*
X92154Y33389D01*
X91924Y32872D01*
X91847Y32407D01*
X93457D01*
G01X95813Y137934D02*
X95583Y138089D01*
X95315Y138192D01*
X95008D01*
X94663Y138037D01*
X94395Y137779D01*
X94203Y137469D01*
X94050Y136952D01*
X94012Y136487D01*
X94088Y136022D01*
X94203Y135712D01*
X94433Y135402D01*
X94702Y135195D01*
X94970Y135092D01*
X95238D01*
X95507Y135195D01*
X95737Y135350D01*
X95928Y135557D01*
G01X98070Y135092D02*
X97763Y135144D01*
X97495Y135350D01*
X97265Y135660D01*
X97112Y136022D01*
X97035Y136435D01*
Y136849D01*
X97112Y137262D01*
X97265Y137624D01*
X97495Y137934D01*
X97763Y138140D01*
X98070Y138192D01*
X98377Y138140D01*
X98645Y137934D01*
X98875Y137624D01*
X99028Y137262D01*
X99105Y136849D01*
Y136435D01*
X99028Y136022D01*
X98875Y135660D01*
X98645Y135350D01*
X98377Y135144D01*
X98070Y135092D01*
G01X100288D02*
Y138192D01*
X102052Y135092D01*
Y138192D01*
G01X103465Y135505D02*
X103772Y135247D01*
X104117Y135092D01*
X104423D01*
X104730Y135247D01*
X104960Y135505D01*
X105075Y135867D01*
X104998Y136229D01*
X104807Y136539D01*
X104462Y136745D01*
X104002Y136849D01*
X103733Y137055D01*
X103618Y137417D01*
X103695Y137779D01*
X103887Y138037D01*
X104155Y138192D01*
X104423D01*
X104692Y138089D01*
X104922Y137830D01*
G01X107370Y135092D02*
X107063Y135144D01*
X106795Y135350D01*
X106565Y135660D01*
X106412Y136022D01*
X106335Y136435D01*
Y136849D01*
X106412Y137262D01*
X106565Y137624D01*
X106795Y137934D01*
X107063Y138140D01*
X107370Y138192D01*
X107677Y138140D01*
X107945Y137934D01*
X108175Y137624D01*
X108328Y137262D01*
X108405Y136849D01*
Y136435D01*
X108328Y136022D01*
X108175Y135660D01*
X107945Y135350D01*
X107677Y135144D01*
X107370Y135092D01*
G01X109703Y138192D02*
Y135092D01*
X111237D01*
G01X114337D02*
X112803D01*
Y138192D01*
X114337D01*
G01X113723Y136694D02*
X112803D01*
G01X94373Y130770D02*
Y133870D01*
X95332D01*
X95638Y133715D01*
X95830Y133508D01*
X95907Y133095D01*
X95830Y132682D01*
X95600Y132423D01*
X95332Y132268D01*
X94373D01*
G01X95332D02*
X95907Y130770D01*
G01X99007D02*
X97473D01*
Y133870D01*
X99007D01*
G01X98393Y132372D02*
X97473D01*
G01X100497Y130770D02*
Y133870D01*
X101263D01*
X101570Y133715D01*
X101800Y133508D01*
X101992Y133198D01*
X102145Y132837D01*
X102183Y132320D01*
X102145Y131803D01*
X101992Y131442D01*
X101800Y131132D01*
X101570Y130925D01*
X101263Y130770D01*
X100497D01*
G01X103980Y133870D02*
X104900D01*
G01X104440D02*
Y130770D01*
G01X103980D02*
X104900D01*
G01X106773D02*
Y133870D01*
X107732D01*
X108038Y133715D01*
X108230Y133508D01*
X108307Y133095D01*
X108230Y132682D01*
X108000Y132423D01*
X107732Y132268D01*
X106773D01*
G01X107732D02*
X108307Y130770D01*
G01X111407D02*
X109873D01*
Y133870D01*
X111407D01*
G01X110793Y132372D02*
X109873D01*
G01X114583Y133612D02*
X114353Y133767D01*
X114085Y133870D01*
X113778D01*
X113433Y133715D01*
X113165Y133457D01*
X112973Y133147D01*
X112820Y132630D01*
X112782Y132165D01*
X112858Y131700D01*
X112973Y131390D01*
X113203Y131080D01*
X113472Y130873D01*
X113740Y130770D01*
X114008D01*
X114277Y130873D01*
X114507Y131028D01*
X114698Y131235D01*
G01X116840Y133870D02*
Y130770D01*
G01X115958Y133870D02*
X117722D01*
G01X119480D02*
X120400D01*
G01X119940D02*
Y130770D01*
G01X119480D02*
X120400D01*
G01X123040D02*
X122733Y130822D01*
X122465Y131028D01*
X122235Y131338D01*
X122082Y131700D01*
X122005Y132113D01*
Y132527D01*
X122082Y132940D01*
X122235Y133302D01*
X122465Y133612D01*
X122733Y133818D01*
X123040Y133870D01*
X123347Y133818D01*
X123615Y133612D01*
X123845Y133302D01*
X123998Y132940D01*
X124075Y132527D01*
Y132113D01*
X123998Y131700D01*
X123845Y131338D01*
X123615Y131028D01*
X123347Y130822D01*
X123040Y130770D01*
G01X125258D02*
Y133870D01*
X127022Y130770D01*
Y133870D01*
G01X92667Y138269D02*
Y148269D01*
G01X94472Y147342D02*
X94702Y147652D01*
X94970Y147807D01*
X95277Y147859D01*
X95660Y147756D01*
X95928Y147497D01*
X96005Y147187D01*
X95967Y146877D01*
X95813Y146619D01*
X95047Y146102D01*
X94702Y145741D01*
X94472Y145224D01*
X94395Y144759D01*
X96005D01*
G01X89650Y154062D02*
Y156562D01*
X89330Y156062D01*
G01Y154062D02*
X89970D01*
G01X92312Y153308D02*
Y156408D01*
X93078D01*
X93385Y156253D01*
X93615Y156046D01*
X93807Y155736D01*
X93960Y155375D01*
X93998Y154858D01*
X93960Y154341D01*
X93807Y153980D01*
X93615Y153670D01*
X93385Y153463D01*
X93078Y153308D01*
X92312D01*
G01X96255D02*
X96523Y153360D01*
X96830Y153515D01*
X97022Y153773D01*
X97098Y154135D01*
X97022Y154496D01*
X96792Y154806D01*
X96447Y154961D01*
X96063D01*
X95833Y155065D01*
X95642Y155323D01*
X95565Y155685D01*
X95680Y156046D01*
X95948Y156305D01*
X96255Y156408D01*
X96562Y156305D01*
X96830Y156046D01*
X96945Y155685D01*
X96868Y155323D01*
X96677Y155065D01*
X96447Y154961D01*
X96063D01*
X95718Y154806D01*
X95488Y154496D01*
X95412Y154135D01*
X95488Y153773D01*
X95680Y153515D01*
X95987Y153360D01*
X96255Y153308D01*
G01X98077Y154243D02*
X98237Y153951D01*
X98451Y153785D01*
X98691Y153743D01*
X98904Y153785D01*
X99117Y153993D01*
X99251Y154243D01*
X99277Y154493D01*
X99224Y154785D01*
X99037Y154993D01*
X98851Y155076D01*
X98611D01*
G01X98851D02*
X99011Y155201D01*
X99144Y155410D01*
X99197Y155660D01*
X99144Y155910D01*
X99011Y156118D01*
X98771Y156243D01*
X98531Y156201D01*
X98291Y156035D01*
G01X88110Y170077D02*
Y157077D01*
G01X101835Y166764D02*
Y169264D01*
X101515Y168764D01*
G01Y166764D02*
X102155D01*
G01X101044Y170048D02*
Y157548D01*
G01Y157448D02*
X89076D01*
G01D02*
Y170048D01*
G01D02*
X101044D01*
G01X86763Y170468D02*
Y173568D01*
X87722D01*
X88028Y173413D01*
X88220Y173206D01*
X88297Y172793D01*
X88220Y172380D01*
X87990Y172121D01*
X87722Y171966D01*
X86763D01*
G01X87722D02*
X88297Y170468D01*
G01X89902Y171760D02*
X90170Y172121D01*
X90400Y172328D01*
X90707Y172431D01*
X90975Y172328D01*
X91167Y172121D01*
X91320Y171811D01*
X91358Y171450D01*
X91320Y171140D01*
X91167Y170830D01*
X90937Y170571D01*
X90668Y170468D01*
X90362Y170571D01*
X90093Y170881D01*
X89940Y171346D01*
X89902Y171863D01*
X89978Y172535D01*
X90093Y172896D01*
X90285Y173258D01*
X90553Y173516D01*
X90822Y173568D01*
X91090Y173465D01*
X91282Y173206D01*
G01X94190Y170468D02*
Y173568D01*
X92772Y171346D01*
X94688D01*
G01X96830Y173568D02*
X96523Y173465D01*
X96293Y173206D01*
X96140Y172896D01*
X96025Y172483D01*
X95987Y172018D01*
X96025Y171553D01*
X96140Y171140D01*
X96293Y170830D01*
X96523Y170571D01*
X96830Y170468D01*
X97137Y170571D01*
X97367Y170830D01*
X97520Y171140D01*
X97635Y171553D01*
X97673Y172018D01*
X97635Y172483D01*
X97520Y172896D01*
X97367Y173206D01*
X97137Y173465D01*
X96830Y173568D01*
G01X100657Y170524D02*
Y176724D01*
G01X103857Y170524D02*
X100657D01*
G01X90927Y176888D02*
Y174666D01*
X91080Y174201D01*
X91387Y173891D01*
X91770Y173788D01*
X92153Y173891D01*
X92460Y174201D01*
X92613Y174666D01*
Y176888D01*
G01X95330Y173788D02*
Y176888D01*
X93912Y174666D01*
X95828D01*
G01X97893Y173788D02*
X97970Y174460D01*
X98085Y175028D01*
X98238Y175545D01*
X98430Y176113D01*
X98737Y176888D01*
X97203D01*
G01X88983Y174428D02*
X86483D01*
X86983Y174108D01*
G01X88983D02*
Y174748D01*
G01X89844Y188467D02*
Y175467D01*
G01X100657Y176724D02*
X103857D01*
G01X90949Y177916D02*
Y192916D01*
G01X103949Y177916D02*
X90949D01*
G01X91800Y198150D02*
X96900D01*
G01X100330Y198449D02*
Y200949D01*
X100010Y200449D01*
G01Y198449D02*
X100650D01*
G01X97537Y198647D02*
Y196425D01*
X97690Y195960D01*
X97997Y195650D01*
X98380Y195547D01*
X98763Y195650D01*
X99070Y195960D01*
X99223Y196425D01*
Y198647D01*
G01X101940Y195547D02*
Y198647D01*
X100522Y196425D01*
X102438D01*
G01X103737Y196012D02*
X103967Y195754D01*
X104235Y195599D01*
X104580Y195547D01*
X104925Y195650D01*
X105193Y195857D01*
X105385Y196219D01*
X105423Y196632D01*
X105347Y197045D01*
X105155Y197304D01*
X104887Y197510D01*
X104618Y197562D01*
X104350Y197510D01*
X104005Y197304D01*
X104120Y198647D01*
X105155D01*
G01X91106Y200817D02*
X90856Y200977D01*
X90731Y201164D01*
X90689Y201377D01*
X90772Y201644D01*
X90981Y201831D01*
X91231Y201884D01*
X91481Y201857D01*
X91689Y201751D01*
X92106Y201217D01*
X92397Y200977D01*
X92814Y200817D01*
X93189Y200764D01*
Y201884D01*
G01X93372Y196370D02*
X90872D01*
X91372Y196050D01*
G01X93372D02*
Y196690D01*
G01X89844Y202233D02*
Y189233D01*
G01X91106Y193882D02*
X90856Y194042D01*
X90731Y194229D01*
X90689Y194442D01*
X90772Y194709D01*
X90981Y194896D01*
X91231Y194949D01*
X91481Y194922D01*
X91689Y194816D01*
X92106Y194282D01*
X92397Y194042D01*
X92814Y193882D01*
X93189Y193829D01*
Y194949D01*
G01X95132Y194330D02*
X95345Y194122D01*
X95585Y193997D01*
X95799D01*
X96012Y194122D01*
X96172Y194330D01*
X96252Y194622D01*
X96199Y194914D01*
X96065Y195164D01*
X95825Y195330D01*
X95505Y195414D01*
X95319Y195580D01*
X95239Y195872D01*
X95292Y196164D01*
X95425Y196372D01*
X95612Y196497D01*
X95799D01*
X95985Y196414D01*
X96145Y196205D01*
G01X90949Y192916D02*
X103949D01*
G01X96808Y219181D02*
X96995Y219223D01*
X97208Y219348D01*
X97341Y219556D01*
X97395Y219848D01*
X97341Y220139D01*
X97181Y220389D01*
X96941Y220514D01*
X96675D01*
X96515Y220598D01*
X96381Y220806D01*
X96328Y221098D01*
X96408Y221389D01*
X96595Y221598D01*
X96808Y221681D01*
X97021Y221598D01*
X97208Y221389D01*
X97288Y221098D01*
X97235Y220806D01*
X97101Y220598D01*
X96941Y220514D01*
X96675D01*
X96435Y220389D01*
X96275Y220139D01*
X96221Y219848D01*
X96275Y219556D01*
X96408Y219348D01*
X96621Y219223D01*
X96808Y219181D01*
G01X99673Y208550D02*
G02I-894J0D01*
G01X97182Y205348D02*
X96576D01*
G01X96580Y212697D02*
X96576Y217553D01*
G01X98576Y211447D02*
X96580Y212697D01*
G01Y210070D02*
X98576Y211447D01*
G01X96576Y205348D02*
X96580Y210070D01*
G01X96576Y217553D02*
X97082D01*
G01X93833Y230234D02*
Y217234D01*
G01X95022Y204003D02*
Y206503D01*
X94702Y206003D01*
G01Y204003D02*
X95342D01*
G01X94736Y213021D02*
X94896Y213271D01*
X95083Y213396D01*
X95296Y213438D01*
X95563Y213355D01*
X95750Y213146D01*
X95803Y212896D01*
X95776Y212646D01*
X95670Y212438D01*
X95136Y212021D01*
X94896Y211730D01*
X94736Y211313D01*
X94683Y210938D01*
X95803D01*
G01X93773Y216352D02*
Y203352D01*
G01X94498Y219918D02*
Y222418D01*
X94178Y221918D01*
G01Y219918D02*
X94818D01*
G01X92991Y233501D02*
X93151Y233751D01*
X93338Y233876D01*
X93551Y233918D01*
X93818Y233835D01*
X94005Y233626D01*
X94058Y233376D01*
X94031Y233126D01*
X93925Y232918D01*
X93391Y232501D01*
X93151Y232210D01*
X92991Y231793D01*
X92938Y231418D01*
X94058D01*
G01X86985Y234461D02*
Y231261D01*
G01X100843Y227436D02*
Y224236D01*
G01X94643Y227436D02*
X100843D01*
G01X94643Y224236D02*
Y227436D01*
G01X100843Y224236D02*
X94643D01*
G01X111462Y247244D02*
G02I-9100J0D01*
G01X91473Y240227D02*
X88373D01*
Y241186D01*
X88528Y241492D01*
X88735Y241684D01*
X89148Y241761D01*
X89561Y241684D01*
X89820Y241454D01*
X89975Y241186D01*
Y240227D01*
G01Y241186D02*
X91473Y241761D01*
G01X90181Y243366D02*
X89820Y243634D01*
X89613Y243864D01*
X89510Y244171D01*
X89613Y244439D01*
X89820Y244631D01*
X90130Y244784D01*
X90491Y244822D01*
X90801Y244784D01*
X91111Y244631D01*
X91370Y244401D01*
X91473Y244132D01*
X91370Y243826D01*
X91060Y243557D01*
X90595Y243404D01*
X90078Y243366D01*
X89406Y243442D01*
X89045Y243557D01*
X88683Y243749D01*
X88425Y244017D01*
X88373Y244286D01*
X88476Y244554D01*
X88735Y244746D01*
G01X90853Y246351D02*
X91215Y246581D01*
X91421Y246887D01*
X91473Y247232D01*
X91421Y247539D01*
X91163Y247846D01*
X90853Y248037D01*
X90543Y248076D01*
X90181Y247999D01*
X89923Y247731D01*
X89820Y247462D01*
Y247117D01*
G01Y247462D02*
X89665Y247692D01*
X89406Y247884D01*
X89096Y247961D01*
X88786Y247884D01*
X88528Y247692D01*
X88373Y247347D01*
X88425Y247002D01*
X88631Y246657D01*
G01X91473Y250294D02*
X88373D01*
X88993Y249834D01*
G01X91473D02*
Y250754D01*
G01X92091Y251650D02*
X88991D01*
Y252609D01*
X89146Y252915D01*
X89353Y253107D01*
X89766Y253184D01*
X90179Y253107D01*
X90438Y252877D01*
X90593Y252609D01*
Y251650D01*
G01Y252609D02*
X92091Y253184D01*
G01X90799Y254789D02*
X90438Y255057D01*
X90231Y255287D01*
X90128Y255594D01*
X90231Y255862D01*
X90438Y256054D01*
X90748Y256207D01*
X91109Y256245D01*
X91419Y256207D01*
X91729Y256054D01*
X91988Y255824D01*
X92091Y255555D01*
X91988Y255249D01*
X91678Y254980D01*
X91213Y254827D01*
X90696Y254789D01*
X90024Y254865D01*
X89663Y254980D01*
X89301Y255172D01*
X89043Y255440D01*
X88991Y255709D01*
X89094Y255977D01*
X89353Y256169D01*
G01X91471Y257774D02*
X91833Y258004D01*
X92039Y258310D01*
X92091Y258655D01*
X92039Y258962D01*
X91781Y259269D01*
X91471Y259460D01*
X91161Y259499D01*
X90799Y259422D01*
X90541Y259154D01*
X90438Y258885D01*
Y258540D01*
G01Y258885D02*
X90283Y259115D01*
X90024Y259307D01*
X89714Y259384D01*
X89404Y259307D01*
X89146Y259115D01*
X88991Y258770D01*
X89043Y258425D01*
X89249Y258080D01*
G01X91471Y260874D02*
X91833Y261104D01*
X92039Y261410D01*
X92091Y261755D01*
X92039Y262062D01*
X91781Y262369D01*
X91471Y262560D01*
X91161Y262599D01*
X90799Y262522D01*
X90541Y262254D01*
X90438Y261985D01*
Y261640D01*
G01Y261985D02*
X90283Y262215D01*
X90024Y262407D01*
X89714Y262484D01*
X89404Y262407D01*
X89146Y262215D01*
X88991Y261870D01*
X89043Y261525D01*
X89249Y261180D01*
G01X94122Y277557D02*
Y275057D01*
X94442Y275557D01*
G01Y277557D02*
X93802D01*
G01X93199Y281838D02*
Y269338D01*
G01X91713Y284192D02*
X88613D01*
Y284958D01*
X88768Y285265D01*
X88975Y285495D01*
X89285Y285687D01*
X89646Y285840D01*
X90163Y285878D01*
X90680Y285840D01*
X91041Y285687D01*
X91351Y285495D01*
X91558Y285265D01*
X91713Y284958D01*
Y284192D01*
G01Y288058D02*
X91041Y288135D01*
X90473Y288250D01*
X89956Y288403D01*
X89388Y288595D01*
X88613Y288902D01*
Y287368D01*
G01X111462Y349606D02*
G02I-9100J0D01*
G01X101568Y369582D02*
X98368D01*
G01Y375782D02*
X101568D01*
G01X98368Y369582D02*
Y375782D01*
G01X101468Y372682D02*
X98468D01*
G01X97568Y369582D02*
X94368D01*
G01X97568Y375782D02*
Y369582D01*
G01X94368Y375782D02*
X97568D01*
G01X94368Y369582D02*
Y375782D01*
G01X101951Y397468D02*
G02I-1000J0D01*
G01X88567Y413067D02*
Y410845D01*
X88720Y410380D01*
X89027Y410070D01*
X89410Y409967D01*
X89793Y410070D01*
X90100Y410380D01*
X90253Y410845D01*
Y413067D01*
G01X92510Y409967D02*
Y413067D01*
X92050Y412447D01*
G01Y409967D02*
X92970D01*
G01X94767Y410587D02*
X94997Y410225D01*
X95303Y410019D01*
X95648Y409967D01*
X95955Y410019D01*
X96262Y410277D01*
X96453Y410587D01*
X96492Y410897D01*
X96415Y411259D01*
X96147Y411517D01*
X95878Y411620D01*
X95533D01*
G01X95878D02*
X96108Y411775D01*
X96300Y412034D01*
X96377Y412344D01*
X96300Y412654D01*
X96108Y412912D01*
X95763Y413067D01*
X95418Y413015D01*
X95073Y412809D01*
G01X99170Y409967D02*
Y413067D01*
X97752Y410845D01*
X99668D01*
G01X85863Y414316D02*
Y417416D01*
X86783D01*
X87090Y417261D01*
X87320Y416899D01*
X87397Y416486D01*
X87320Y416073D01*
X87128Y415763D01*
X86783Y415608D01*
X85863D01*
G01X90573Y417158D02*
X90343Y417313D01*
X90075Y417416D01*
X89768D01*
X89423Y417261D01*
X89155Y417003D01*
X88963Y416693D01*
X88810Y416176D01*
X88772Y415711D01*
X88848Y415246D01*
X88963Y414936D01*
X89193Y414626D01*
X89462Y414419D01*
X89730Y414316D01*
X89998D01*
X90267Y414419D01*
X90497Y414574D01*
X90688Y414781D01*
G01X92102Y415608D02*
X92370Y415969D01*
X92600Y416176D01*
X92907Y416279D01*
X93175Y416176D01*
X93367Y415969D01*
X93520Y415659D01*
X93558Y415298D01*
X93520Y414988D01*
X93367Y414678D01*
X93137Y414419D01*
X92868Y414316D01*
X92562Y414419D01*
X92293Y414729D01*
X92140Y415194D01*
X92102Y415711D01*
X92178Y416383D01*
X92293Y416744D01*
X92485Y417106D01*
X92753Y417364D01*
X93022Y417416D01*
X93290Y417313D01*
X93482Y417054D01*
G01X95930Y414316D02*
Y417416D01*
X95470Y416796D01*
G01Y414316D02*
X96390D01*
G01X91132Y418474D02*
Y421674D01*
G01X94232Y421574D02*
Y418574D01*
G01X97332Y418474D02*
X91132D01*
G01Y421674D02*
X97332D01*
G01D02*
Y418474D01*
G01X93865Y439242D02*
Y432644D01*
G01X101365Y432543D02*
X86365D01*
G01D02*
Y439343D01*
G01X93865Y430243D02*
Y423643D01*
G01X101365Y423543D02*
X86365D01*
G01Y430343D02*
X101365D01*
G01X86365Y423543D02*
Y430343D01*
G01X101387Y441543D02*
X86387D01*
G01Y448343D02*
X101387D01*
G01X86387Y441543D02*
Y448343D01*
G01X93887Y448243D02*
Y441643D01*
G01X86365Y439343D02*
X101365D01*
G01X90688Y485406D02*
Y452606D01*
G01X93468Y488126D02*
X90368D01*
Y489046D01*
X90523Y489353D01*
X90885Y489583D01*
X91298Y489660D01*
X91711Y489583D01*
X92021Y489391D01*
X92176Y489046D01*
Y488126D01*
G01X93468Y491993D02*
X93416Y491686D01*
X93210Y491418D01*
X92900Y491188D01*
X92538Y491035D01*
X92125Y490958D01*
X91711D01*
X91298Y491035D01*
X90936Y491188D01*
X90626Y491418D01*
X90420Y491686D01*
X90368Y491993D01*
X90420Y492300D01*
X90626Y492568D01*
X90936Y492798D01*
X91298Y492951D01*
X91711Y493028D01*
X92125D01*
X92538Y492951D01*
X92900Y492798D01*
X93210Y492568D01*
X93416Y492300D01*
X93468Y491993D01*
G01X92641Y492300D02*
X93468Y492760D01*
G01Y495093D02*
X90368D01*
X90988Y494633D01*
G01X93468D02*
Y495553D01*
G01X96908Y497652D02*
X93808D01*
Y498572D01*
X93963Y498879D01*
X94325Y499109D01*
X94738Y499186D01*
X95151Y499109D01*
X95461Y498917D01*
X95616Y498572D01*
Y497652D01*
G01X94066Y502362D02*
X93911Y502132D01*
X93808Y501864D01*
Y501557D01*
X93963Y501212D01*
X94221Y500944D01*
X94531Y500752D01*
X95048Y500599D01*
X95513Y500561D01*
X95978Y500637D01*
X96288Y500752D01*
X96598Y500982D01*
X96805Y501251D01*
X96908Y501519D01*
Y501787D01*
X96805Y502056D01*
X96650Y502286D01*
X96443Y502477D01*
G01X95616Y503891D02*
X95255Y504159D01*
X95048Y504389D01*
X94945Y504696D01*
X95048Y504964D01*
X95255Y505156D01*
X95565Y505309D01*
X95926Y505347D01*
X96236Y505309D01*
X96546Y505156D01*
X96805Y504926D01*
X96908Y504657D01*
X96805Y504351D01*
X96495Y504082D01*
X96030Y503929D01*
X95513Y503891D01*
X94841Y503967D01*
X94480Y504082D01*
X94118Y504274D01*
X93860Y504542D01*
X93808Y504811D01*
X93911Y505079D01*
X94170Y505271D01*
G01X93808Y507719D02*
X93911Y507412D01*
X94170Y507182D01*
X94480Y507029D01*
X94893Y506914D01*
X95358Y506876D01*
X95823Y506914D01*
X96236Y507029D01*
X96546Y507182D01*
X96805Y507412D01*
X96908Y507719D01*
X96805Y508026D01*
X96546Y508256D01*
X96236Y508409D01*
X95823Y508524D01*
X95358Y508562D01*
X94893Y508524D01*
X94480Y508409D01*
X94170Y508256D01*
X93911Y508026D01*
X93808Y507719D01*
G01X100986Y497550D02*
X97886D01*
Y498470D01*
X98041Y498777D01*
X98403Y499007D01*
X98816Y499084D01*
X99229Y499007D01*
X99539Y498815D01*
X99694Y498470D01*
Y497550D01*
G01X100986Y500650D02*
X97886D01*
Y501609D01*
X98041Y501915D01*
X98248Y502107D01*
X98661Y502184D01*
X99074Y502107D01*
X99333Y501877D01*
X99488Y501609D01*
Y500650D01*
G01Y501609D02*
X100986Y502184D01*
G01X98403Y503789D02*
X98093Y504019D01*
X97938Y504287D01*
X97886Y504594D01*
X97989Y504977D01*
X98248Y505245D01*
X98558Y505322D01*
X98868Y505284D01*
X99126Y505130D01*
X99643Y504364D01*
X100004Y504019D01*
X100521Y503789D01*
X100986Y503712D01*
Y505322D01*
G01X100366Y506774D02*
X100728Y507004D01*
X100934Y507310D01*
X100986Y507655D01*
X100934Y507962D01*
X100676Y508269D01*
X100366Y508460D01*
X100056Y508499D01*
X99694Y508422D01*
X99436Y508154D01*
X99333Y507885D01*
Y507540D01*
G01Y507885D02*
X99178Y508115D01*
X98919Y508307D01*
X98609Y508384D01*
X98299Y508307D01*
X98041Y508115D01*
X97886Y507770D01*
X97938Y507425D01*
X98144Y507080D01*
G01X99267Y494266D02*
Y492044D01*
X99420Y491579D01*
X99727Y491269D01*
X100110Y491166D01*
X100493Y491269D01*
X100800Y491579D01*
X100953Y492044D01*
Y494266D01*
G01X103210Y491166D02*
Y494266D01*
X102750Y493646D01*
G01Y491166D02*
X103670D01*
G01X105582Y493749D02*
X105812Y494059D01*
X106080Y494214D01*
X106387Y494266D01*
X106770Y494163D01*
X107038Y493904D01*
X107115Y493594D01*
X107077Y493284D01*
X106923Y493026D01*
X106157Y492509D01*
X105812Y492148D01*
X105582Y491631D01*
X105505Y491166D01*
X107115D01*
G01X109410D02*
Y494266D01*
X108950Y493646D01*
G01Y491166D02*
X109870D01*
G01X103494Y511673D02*
X100394D01*
Y512632D01*
X100549Y512938D01*
X100756Y513130D01*
X101169Y513207D01*
X101582Y513130D01*
X101841Y512900D01*
X101996Y512632D01*
Y511673D01*
G01Y512632D02*
X103494Y513207D01*
G01Y515540D02*
X100394D01*
X101014Y515080D01*
G01X103494D02*
Y516000D01*
G01X100394Y518640D02*
X100497Y518333D01*
X100756Y518103D01*
X101066Y517950D01*
X101479Y517835D01*
X101944Y517797D01*
X102409Y517835D01*
X102822Y517950D01*
X103132Y518103D01*
X103391Y518333D01*
X103494Y518640D01*
X103391Y518947D01*
X103132Y519177D01*
X102822Y519330D01*
X102409Y519445D01*
X101944Y519483D01*
X101479Y519445D01*
X101066Y519330D01*
X100756Y519177D01*
X100497Y518947D01*
X100394Y518640D01*
G01X103132Y521088D02*
X103391Y521357D01*
X103494Y521663D01*
X103391Y521970D01*
X103081Y522238D01*
X102616Y522430D01*
X102151Y522507D01*
X101582D01*
X101117Y522430D01*
X100704Y522238D01*
X100497Y522008D01*
X100394Y521740D01*
X100497Y521433D01*
X100704Y521203D01*
X101014Y521050D01*
X101427Y520973D01*
X101789Y521050D01*
X102151Y521242D01*
X102357Y521472D01*
X102409Y521740D01*
X102306Y522047D01*
X102047Y522277D01*
X101582Y522507D01*
G01X103494Y525300D02*
X100394D01*
X102616Y523882D01*
Y525798D01*
G01X89858Y510723D02*
X93058D01*
G01X89858Y504523D02*
Y510723D01*
G01X93058Y504523D02*
X89858D01*
G01X93058Y510723D02*
Y504523D01*
G01X102453Y531109D02*
X102223Y531264D01*
X101955Y531367D01*
X101648D01*
X101303Y531212D01*
X101035Y530954D01*
X100843Y530644D01*
X100690Y530127D01*
X100652Y529662D01*
X100728Y529197D01*
X100843Y528887D01*
X101073Y528577D01*
X101342Y528370D01*
X101610Y528267D01*
X101878D01*
X102147Y528370D01*
X102377Y528525D01*
X102568Y528732D01*
G01X105170Y528267D02*
Y531367D01*
X103752Y529145D01*
X105668D01*
G01X106967Y528887D02*
X107197Y528525D01*
X107503Y528319D01*
X107848Y528267D01*
X108155Y528319D01*
X108462Y528577D01*
X108653Y528887D01*
X108692Y529197D01*
X108615Y529559D01*
X108347Y529817D01*
X108078Y529920D01*
X107733D01*
G01X108078D02*
X108308Y530075D01*
X108500Y530334D01*
X108577Y530644D01*
X108500Y530954D01*
X108308Y531212D01*
X107963Y531367D01*
X107618Y531315D01*
X107273Y531109D01*
G01X110182Y530850D02*
X110412Y531160D01*
X110680Y531315D01*
X110987Y531367D01*
X111370Y531264D01*
X111638Y531005D01*
X111715Y530695D01*
X111677Y530385D01*
X111523Y530127D01*
X110757Y529610D01*
X110412Y529249D01*
X110182Y528732D01*
X110105Y528267D01*
X111715D01*
G01X111080Y532902D02*
X100880D01*
G01D02*
Y537502D01*
G01X88729D02*
Y532902D01*
G01X93829Y537502D02*
Y532902D01*
G01X100880Y537502D02*
X111080D01*
G01X98480Y539302D02*
Y546102D01*
G01D02*
X113480D01*
G01Y539302D02*
X98480D01*
G01X96229Y546102D02*
Y539302D01*
G01X88729Y539402D02*
Y546002D01*
G01X100989Y598130D02*
X94306D01*
Y598151D01*
X96499Y600344D01*
X96520Y600323D01*
Y595495D01*
X94285Y597730D01*
Y598067D01*
G01X89061Y590401D02*
Y593501D01*
X90020D01*
X90326Y593346D01*
X90518Y593139D01*
X90595Y592726D01*
X90518Y592313D01*
X90288Y592054D01*
X90020Y591899D01*
X89061D01*
G01X90020D02*
X90595Y590401D01*
G01X92085Y590866D02*
X92315Y590608D01*
X92583Y590453D01*
X92928Y590401D01*
X93273Y590504D01*
X93541Y590711D01*
X93733Y591073D01*
X93771Y591486D01*
X93695Y591899D01*
X93503Y592158D01*
X93235Y592364D01*
X92966Y592416D01*
X92698Y592364D01*
X92353Y592158D01*
X92468Y593501D01*
X93503D01*
G01X95300Y591693D02*
X95568Y592054D01*
X95798Y592261D01*
X96105Y592364D01*
X96373Y592261D01*
X96565Y592054D01*
X96718Y591744D01*
X96756Y591383D01*
X96718Y591073D01*
X96565Y590763D01*
X96335Y590504D01*
X96066Y590401D01*
X95760Y590504D01*
X95491Y590814D01*
X95338Y591279D01*
X95300Y591796D01*
X95376Y592468D01*
X95491Y592829D01*
X95683Y593191D01*
X95951Y593449D01*
X96220Y593501D01*
X96488Y593398D01*
X96680Y593139D01*
G01X99588Y590401D02*
Y593501D01*
X98170Y591279D01*
X100086D01*
G01X99717Y584777D02*
X89517D01*
G01D02*
Y589377D01*
G01D02*
X99717D01*
G01D02*
Y584777D01*
G01X93194Y600705D02*
X86107Y607792D01*
G01X100139Y600705D02*
X93194D01*
G01X100139Y662123D02*
Y600705D01*
G01X98720Y667693D02*
Y672693D01*
G01X101380D02*
Y667693D01*
G01Y670193D02*
X98720D01*
G01X105150Y667693D02*
X105593Y667776D01*
X106100Y668026D01*
X106417Y668443D01*
X106543Y669026D01*
X106417Y669610D01*
X106037Y670110D01*
X105467Y670360D01*
X104833D01*
X104453Y670526D01*
X104137Y670943D01*
X104010Y671526D01*
X104200Y672110D01*
X104643Y672526D01*
X105150Y672693D01*
X105657Y672526D01*
X106100Y672110D01*
X106290Y671526D01*
X106163Y670943D01*
X105847Y670526D01*
X105467Y670360D01*
X104833D01*
X104263Y670110D01*
X103883Y669610D01*
X103757Y669026D01*
X103883Y668443D01*
X104200Y668026D01*
X104707Y667776D01*
X105150Y667693D01*
G01X118657Y2665D02*
X115557D01*
Y3585D01*
X115712Y3892D01*
X116074Y4122D01*
X116487Y4199D01*
X116900Y4122D01*
X117210Y3930D01*
X117365Y3585D01*
Y2665D01*
G01X115815Y7375D02*
X115660Y7145D01*
X115557Y6877D01*
Y6570D01*
X115712Y6225D01*
X115970Y5957D01*
X116280Y5765D01*
X116797Y5612D01*
X117262Y5574D01*
X117727Y5650D01*
X118037Y5765D01*
X118347Y5995D01*
X118554Y6264D01*
X118657Y6532D01*
Y6800D01*
X118554Y7069D01*
X118399Y7299D01*
X118192Y7490D01*
G01X118657Y9555D02*
X117985Y9632D01*
X117417Y9747D01*
X116900Y9900D01*
X116332Y10092D01*
X115557Y10399D01*
Y8865D01*
G01X118192Y11889D02*
X118450Y12119D01*
X118605Y12387D01*
X118657Y12732D01*
X118554Y13077D01*
X118347Y13345D01*
X117985Y13537D01*
X117572Y13575D01*
X117159Y13499D01*
X116900Y13307D01*
X116694Y13039D01*
X116642Y12770D01*
X116694Y12502D01*
X116900Y12157D01*
X115557Y12272D01*
Y13307D01*
G01X110393Y2665D02*
X107293D01*
Y3585D01*
X107448Y3892D01*
X107810Y4122D01*
X108223Y4199D01*
X108636Y4122D01*
X108946Y3930D01*
X109101Y3585D01*
Y2665D01*
G01X107551Y7375D02*
X107396Y7145D01*
X107293Y6877D01*
Y6570D01*
X107448Y6225D01*
X107706Y5957D01*
X108016Y5765D01*
X108533Y5612D01*
X108998Y5574D01*
X109463Y5650D01*
X109773Y5765D01*
X110083Y5995D01*
X110290Y6264D01*
X110393Y6532D01*
Y6800D01*
X110290Y7069D01*
X110135Y7299D01*
X109928Y7490D01*
G01X109773Y8789D02*
X110135Y9019D01*
X110341Y9325D01*
X110393Y9670D01*
X110341Y9977D01*
X110083Y10284D01*
X109773Y10475D01*
X109463Y10514D01*
X109101Y10437D01*
X108843Y10169D01*
X108740Y9900D01*
Y9555D01*
G01Y9900D02*
X108585Y10130D01*
X108326Y10322D01*
X108016Y10399D01*
X107706Y10322D01*
X107448Y10130D01*
X107293Y9785D01*
X107345Y9440D01*
X107551Y9095D01*
G01X110393Y12732D02*
X107293D01*
X107913Y12272D01*
G01X110393D02*
Y13192D01*
G01X114514Y2665D02*
X111414D01*
Y3585D01*
X111569Y3892D01*
X111931Y4122D01*
X112344Y4199D01*
X112757Y4122D01*
X113067Y3930D01*
X113222Y3585D01*
Y2665D01*
G01X111672Y7375D02*
X111517Y7145D01*
X111414Y6877D01*
Y6570D01*
X111569Y6225D01*
X111827Y5957D01*
X112137Y5765D01*
X112654Y5612D01*
X113119Y5574D01*
X113584Y5650D01*
X113894Y5765D01*
X114204Y5995D01*
X114411Y6264D01*
X114514Y6532D01*
Y6800D01*
X114411Y7069D01*
X114256Y7299D01*
X114049Y7490D01*
G01X114514Y9555D02*
X113842Y9632D01*
X113274Y9747D01*
X112757Y9900D01*
X112189Y10092D01*
X111414Y10399D01*
Y8865D01*
G01X114514Y13192D02*
X111414D01*
X113636Y11774D01*
Y13690D01*
G01X106742Y20564D02*
X103642D01*
Y21484D01*
X103797Y21791D01*
X104159Y22021D01*
X104572Y22098D01*
X104985Y22021D01*
X105295Y21829D01*
X105450Y21484D01*
Y20564D01*
G01X103900Y25274D02*
X103745Y25044D01*
X103642Y24776D01*
Y24469D01*
X103797Y24124D01*
X104055Y23856D01*
X104365Y23664D01*
X104882Y23511D01*
X105347Y23473D01*
X105812Y23549D01*
X106122Y23664D01*
X106432Y23894D01*
X106639Y24163D01*
X106742Y24431D01*
Y24699D01*
X106639Y24968D01*
X106484Y25198D01*
X106277Y25389D01*
G01X106742Y27531D02*
X106690Y27799D01*
X106535Y28106D01*
X106277Y28298D01*
X105915Y28374D01*
X105554Y28298D01*
X105244Y28068D01*
X105089Y27723D01*
Y27339D01*
X104985Y27109D01*
X104727Y26918D01*
X104365Y26841D01*
X104004Y26956D01*
X103745Y27224D01*
X103642Y27531D01*
X103745Y27838D01*
X104004Y28106D01*
X104365Y28221D01*
X104727Y28144D01*
X104985Y27953D01*
X105089Y27723D01*
Y27339D01*
X105244Y26994D01*
X105554Y26764D01*
X105915Y26688D01*
X106277Y26764D01*
X106535Y26956D01*
X106690Y27263D01*
X106742Y27531D01*
G01X105450Y29903D02*
X105089Y30171D01*
X104882Y30401D01*
X104779Y30708D01*
X104882Y30976D01*
X105089Y31168D01*
X105399Y31321D01*
X105760Y31359D01*
X106070Y31321D01*
X106380Y31168D01*
X106639Y30938D01*
X106742Y30669D01*
X106639Y30363D01*
X106329Y30094D01*
X105864Y29941D01*
X105347Y29903D01*
X104675Y29979D01*
X104314Y30094D01*
X103952Y30286D01*
X103694Y30554D01*
X103642Y30823D01*
X103745Y31091D01*
X104004Y31283D01*
G01X119062Y20564D02*
X115962D01*
Y21484D01*
X116117Y21791D01*
X116479Y22021D01*
X116892Y22098D01*
X117305Y22021D01*
X117615Y21829D01*
X117770Y21484D01*
Y20564D01*
G01X119062Y23664D02*
X115962D01*
Y24623D01*
X116117Y24929D01*
X116324Y25121D01*
X116737Y25198D01*
X117150Y25121D01*
X117409Y24891D01*
X117564Y24623D01*
Y23664D01*
G01Y24623D02*
X119062Y25198D01*
G01X118442Y26688D02*
X118804Y26918D01*
X119010Y27224D01*
X119062Y27569D01*
X119010Y27876D01*
X118752Y28183D01*
X118442Y28374D01*
X118132Y28413D01*
X117770Y28336D01*
X117512Y28068D01*
X117409Y27799D01*
Y27454D01*
G01Y27799D02*
X117254Y28029D01*
X116995Y28221D01*
X116685Y28298D01*
X116375Y28221D01*
X116117Y28029D01*
X115962Y27684D01*
X116014Y27339D01*
X116220Y26994D01*
G01X119062Y30554D02*
X118390Y30631D01*
X117822Y30746D01*
X117305Y30899D01*
X116737Y31091D01*
X115962Y31398D01*
Y29864D01*
G01X115142Y20564D02*
X112042D01*
Y21523D01*
X112197Y21829D01*
X112404Y22021D01*
X112817Y22098D01*
X113230Y22021D01*
X113489Y21791D01*
X113644Y21523D01*
Y20564D01*
G01Y21523D02*
X115142Y22098D01*
G01Y24431D02*
X112042D01*
X112662Y23971D01*
G01X115142D02*
Y24891D01*
G01Y27531D02*
X112042D01*
X112662Y27071D01*
G01X115142D02*
Y27991D01*
G01X112559Y29903D02*
X112249Y30133D01*
X112094Y30401D01*
X112042Y30708D01*
X112145Y31091D01*
X112404Y31359D01*
X112714Y31436D01*
X113024Y31398D01*
X113282Y31244D01*
X113799Y30478D01*
X114160Y30133D01*
X114677Y29903D01*
X115142Y29826D01*
Y31436D01*
G01X114522Y32888D02*
X114884Y33118D01*
X115090Y33424D01*
X115142Y33769D01*
X115090Y34076D01*
X114832Y34383D01*
X114522Y34574D01*
X114212Y34613D01*
X113850Y34536D01*
X113592Y34268D01*
X113489Y33999D01*
Y33654D01*
G01Y33999D02*
X113334Y34229D01*
X113075Y34421D01*
X112765Y34498D01*
X112455Y34421D01*
X112197Y34229D01*
X112042Y33884D01*
X112094Y33539D01*
X112300Y33194D01*
G01X110812Y20564D02*
X107712D01*
Y21484D01*
X107867Y21791D01*
X108229Y22021D01*
X108642Y22098D01*
X109055Y22021D01*
X109365Y21829D01*
X109520Y21484D01*
Y20564D01*
G01X110812Y23664D02*
X107712D01*
Y24623D01*
X107867Y24929D01*
X108074Y25121D01*
X108487Y25198D01*
X108900Y25121D01*
X109159Y24891D01*
X109314Y24623D01*
Y23664D01*
G01Y24623D02*
X110812Y25198D01*
G01X110192Y26688D02*
X110554Y26918D01*
X110760Y27224D01*
X110812Y27569D01*
X110760Y27876D01*
X110502Y28183D01*
X110192Y28374D01*
X109882Y28413D01*
X109520Y28336D01*
X109262Y28068D01*
X109159Y27799D01*
Y27454D01*
G01Y27799D02*
X109004Y28029D01*
X108745Y28221D01*
X108435Y28298D01*
X108125Y28221D01*
X107867Y28029D01*
X107712Y27684D01*
X107764Y27339D01*
X107970Y26994D01*
G01X110812Y30631D02*
X107712D01*
X108332Y30171D01*
G01X110812D02*
Y31091D01*
G01X108343Y38796D02*
Y41896D01*
X109263D01*
X109570Y41741D01*
X109800Y41379D01*
X109877Y40966D01*
X109800Y40553D01*
X109608Y40243D01*
X109263Y40088D01*
X108343D01*
G01X111367Y41896D02*
Y39674D01*
X111520Y39209D01*
X111827Y38899D01*
X112210Y38796D01*
X112593Y38899D01*
X112900Y39209D01*
X113053Y39674D01*
Y41896D01*
G01X115233Y38796D02*
X115310Y39468D01*
X115425Y40036D01*
X115578Y40553D01*
X115770Y41121D01*
X116077Y41896D01*
X114543D01*
G01X105804Y154373D02*
X102704D01*
Y155332D01*
X102859Y155638D01*
X103066Y155830D01*
X103479Y155907D01*
X103892Y155830D01*
X104151Y155600D01*
X104306Y155332D01*
Y154373D01*
G01Y155332D02*
X105804Y155907D01*
G01X104512Y157512D02*
X104151Y157780D01*
X103944Y158010D01*
X103841Y158317D01*
X103944Y158585D01*
X104151Y158777D01*
X104461Y158930D01*
X104822Y158968D01*
X105132Y158930D01*
X105442Y158777D01*
X105701Y158547D01*
X105804Y158278D01*
X105701Y157972D01*
X105391Y157703D01*
X104926Y157550D01*
X104409Y157512D01*
X103737Y157588D01*
X103376Y157703D01*
X103014Y157895D01*
X102756Y158163D01*
X102704Y158432D01*
X102807Y158700D01*
X103066Y158892D01*
G01X105184Y160497D02*
X105546Y160727D01*
X105752Y161033D01*
X105804Y161378D01*
X105752Y161685D01*
X105494Y161992D01*
X105184Y162183D01*
X104874Y162222D01*
X104512Y162145D01*
X104254Y161877D01*
X104151Y161608D01*
Y161263D01*
G01Y161608D02*
X103996Y161838D01*
X103737Y162030D01*
X103427Y162107D01*
X103117Y162030D01*
X102859Y161838D01*
X102704Y161493D01*
X102756Y161148D01*
X102962Y160803D01*
G01X103221Y163712D02*
X102911Y163942D01*
X102756Y164210D01*
X102704Y164517D01*
X102807Y164900D01*
X103066Y165168D01*
X103376Y165245D01*
X103686Y165207D01*
X103944Y165053D01*
X104461Y164287D01*
X104822Y163942D01*
X105339Y163712D01*
X105804Y163635D01*
Y165245D01*
G01X145200Y193050D02*
X129170D01*
Y177076D01*
X134078D01*
Y169686D01*
X109591D01*
Y202140D01*
X103120D01*
G01X107158Y168871D02*
X107318Y169121D01*
X107505Y169246D01*
X107718Y169288D01*
X107985Y169205D01*
X108172Y168996D01*
X108225Y168746D01*
X108198Y168496D01*
X108092Y168288D01*
X107558Y167871D01*
X107318Y167580D01*
X107158Y167163D01*
X107105Y166788D01*
X108225D01*
G01X103857Y176724D02*
Y170524D01*
G01X110563Y171470D02*
Y174570D01*
X111522D01*
X111828Y174415D01*
X112020Y174208D01*
X112097Y173795D01*
X112020Y173382D01*
X111790Y173123D01*
X111522Y172968D01*
X110563D01*
G01X111522D02*
X112097Y171470D01*
G01X114353D02*
X114430Y172142D01*
X114545Y172710D01*
X114698Y173227D01*
X114890Y173795D01*
X115197Y174570D01*
X113663D01*
G01X117530Y171470D02*
X117798Y171522D01*
X118105Y171677D01*
X118297Y171935D01*
X118373Y172297D01*
X118297Y172658D01*
X118067Y172968D01*
X117722Y173123D01*
X117338D01*
X117108Y173227D01*
X116917Y173485D01*
X116840Y173847D01*
X116955Y174208D01*
X117223Y174467D01*
X117530Y174570D01*
X117837Y174467D01*
X118105Y174208D01*
X118220Y173847D01*
X118143Y173485D01*
X117952Y173227D01*
X117722Y173123D01*
X117338D01*
X116993Y172968D01*
X116763Y172658D01*
X116687Y172297D01*
X116763Y171935D01*
X116955Y171677D01*
X117262Y171522D01*
X117530Y171470D01*
G01X120630D02*
X120898Y171522D01*
X121205Y171677D01*
X121397Y171935D01*
X121473Y172297D01*
X121397Y172658D01*
X121167Y172968D01*
X120822Y173123D01*
X120438D01*
X120208Y173227D01*
X120017Y173485D01*
X119940Y173847D01*
X120055Y174208D01*
X120323Y174467D01*
X120630Y174570D01*
X120937Y174467D01*
X121205Y174208D01*
X121320Y173847D01*
X121243Y173485D01*
X121052Y173227D01*
X120822Y173123D01*
X120438D01*
X120093Y172968D01*
X119863Y172658D01*
X119787Y172297D01*
X119863Y171935D01*
X120055Y171677D01*
X120362Y171522D01*
X120630Y171470D01*
G01X116198Y178106D02*
X116043Y177876D01*
X115940Y177608D01*
Y177301D01*
X116095Y176956D01*
X116353Y176688D01*
X116663Y176496D01*
X117180Y176343D01*
X117645Y176305D01*
X118110Y176381D01*
X118420Y176496D01*
X118730Y176726D01*
X118937Y176995D01*
X119040Y177263D01*
Y177531D01*
X118937Y177800D01*
X118782Y178030D01*
X118575Y178221D01*
G01Y179520D02*
X118833Y179750D01*
X118988Y180018D01*
X119040Y180363D01*
X118937Y180708D01*
X118730Y180976D01*
X118368Y181168D01*
X117955Y181206D01*
X117542Y181130D01*
X117283Y180938D01*
X117077Y180670D01*
X117025Y180401D01*
X117077Y180133D01*
X117283Y179788D01*
X115940Y179903D01*
Y180938D01*
G01Y183463D02*
X116043Y183156D01*
X116302Y182926D01*
X116612Y182773D01*
X117025Y182658D01*
X117490Y182620D01*
X117955Y182658D01*
X118368Y182773D01*
X118678Y182926D01*
X118937Y183156D01*
X119040Y183463D01*
X118937Y183770D01*
X118678Y184000D01*
X118368Y184153D01*
X117955Y184268D01*
X117490Y184306D01*
X117025Y184268D01*
X116612Y184153D01*
X116302Y184000D01*
X116043Y183770D01*
X115940Y183463D01*
G01X118420Y185720D02*
X118782Y185950D01*
X118988Y186256D01*
X119040Y186601D01*
X118988Y186908D01*
X118730Y187215D01*
X118420Y187406D01*
X118110Y187445D01*
X117748Y187368D01*
X117490Y187100D01*
X117387Y186831D01*
Y186486D01*
G01Y186831D02*
X117232Y187061D01*
X116973Y187253D01*
X116663Y187330D01*
X116353Y187253D01*
X116095Y187061D01*
X115940Y186716D01*
X115992Y186371D01*
X116198Y186026D01*
G01X107793Y183154D02*
X107741Y182847D01*
X107535Y182579D01*
X107225Y182349D01*
X106863Y182196D01*
X106450Y182119D01*
X106036D01*
X105623Y182196D01*
X105261Y182349D01*
X104951Y182579D01*
X104745Y182847D01*
X104693Y183154D01*
X104745Y183461D01*
X104951Y183729D01*
X105261Y183959D01*
X105623Y184112D01*
X106036Y184189D01*
X106450D01*
X106863Y184112D01*
X107225Y183959D01*
X107535Y183729D01*
X107741Y183461D01*
X107793Y183154D01*
G01X106966Y183461D02*
X107793Y183921D01*
G01Y186254D02*
X104693D01*
X105313Y185794D01*
G01X107793D02*
Y186714D01*
G01Y189354D02*
X107741Y189622D01*
X107586Y189929D01*
X107328Y190121D01*
X106966Y190197D01*
X106605Y190121D01*
X106295Y189891D01*
X106140Y189546D01*
Y189162D01*
X106036Y188932D01*
X105778Y188741D01*
X105416Y188664D01*
X105055Y188779D01*
X104796Y189047D01*
X104693Y189354D01*
X104796Y189661D01*
X105055Y189929D01*
X105416Y190044D01*
X105778Y189967D01*
X106036Y189776D01*
X106140Y189546D01*
Y189162D01*
X106295Y188817D01*
X106605Y188587D01*
X106966Y188511D01*
X107328Y188587D01*
X107586Y188779D01*
X107741Y189086D01*
X107793Y189354D01*
G01X104906Y177828D02*
Y180328D01*
X105440D01*
X105653Y180203D01*
X105813Y180036D01*
X105946Y179786D01*
X106053Y179495D01*
X106080Y179078D01*
X106053Y178661D01*
X105946Y178370D01*
X105813Y178120D01*
X105653Y177953D01*
X105440Y177828D01*
X104906D01*
G01X103949Y192916D02*
Y177916D01*
G01X112047Y203107D02*
Y205607D01*
X111060Y203815D01*
X112394D01*
G01X116050Y190515D02*
X115895Y190285D01*
X115792Y190017D01*
Y189710D01*
X115947Y189365D01*
X116205Y189097D01*
X116515Y188905D01*
X117032Y188752D01*
X117497Y188714D01*
X117962Y188790D01*
X118272Y188905D01*
X118582Y189135D01*
X118789Y189404D01*
X118892Y189672D01*
Y189940D01*
X118789Y190209D01*
X118634Y190439D01*
X118427Y190630D01*
G01Y191929D02*
X118685Y192159D01*
X118840Y192427D01*
X118892Y192772D01*
X118789Y193117D01*
X118582Y193385D01*
X118220Y193577D01*
X117807Y193615D01*
X117394Y193539D01*
X117135Y193347D01*
X116929Y193079D01*
X116877Y192810D01*
X116929Y192542D01*
X117135Y192197D01*
X115792Y192312D01*
Y193347D01*
G01Y195872D02*
X115895Y195565D01*
X116154Y195335D01*
X116464Y195182D01*
X116877Y195067D01*
X117342Y195029D01*
X117807Y195067D01*
X118220Y195182D01*
X118530Y195335D01*
X118789Y195565D01*
X118892Y195872D01*
X118789Y196179D01*
X118530Y196409D01*
X118220Y196562D01*
X117807Y196677D01*
X117342Y196715D01*
X116877Y196677D01*
X116464Y196562D01*
X116154Y196409D01*
X115895Y196179D01*
X115792Y195872D01*
G01X117600Y198244D02*
X117239Y198512D01*
X117032Y198742D01*
X116929Y199049D01*
X117032Y199317D01*
X117239Y199509D01*
X117549Y199662D01*
X117910Y199700D01*
X118220Y199662D01*
X118530Y199509D01*
X118789Y199279D01*
X118892Y199010D01*
X118789Y198704D01*
X118479Y198435D01*
X118014Y198282D01*
X117497Y198244D01*
X116825Y198320D01*
X116464Y198435D01*
X116102Y198627D01*
X115844Y198895D01*
X115792Y199164D01*
X115895Y199432D01*
X116154Y199624D01*
G01X106637Y194639D02*
X107170D01*
Y193889D01*
X107010Y193639D01*
X106824Y193472D01*
X106557Y193389D01*
X106290Y193472D01*
X106104Y193639D01*
X105944Y193889D01*
X105837Y194181D01*
X105784Y194514D01*
Y194806D01*
X105837Y195056D01*
X105944Y195347D01*
X106104Y195597D01*
X106264Y195764D01*
X106477Y195889D01*
X106664D01*
X106877Y195806D01*
X107037Y195639D01*
G01X110296Y218294D02*
X110456Y218086D01*
X110643Y217961D01*
X110883Y217919D01*
X111123Y218002D01*
X111310Y218169D01*
X111443Y218461D01*
X111470Y218794D01*
X111416Y219127D01*
X111283Y219336D01*
X111096Y219502D01*
X110910Y219544D01*
X110723Y219502D01*
X110483Y219336D01*
X110563Y220419D01*
X111283D01*
G01X108781Y205348D02*
X107782D01*
G01X108781Y217553D02*
Y205348D01*
G01X107782Y217553D02*
X108781D01*
G01X115686Y207666D02*
X115531Y207436D01*
X115428Y207168D01*
Y206861D01*
X115583Y206516D01*
X115841Y206248D01*
X116151Y206056D01*
X116668Y205903D01*
X117133Y205865D01*
X117598Y205941D01*
X117908Y206056D01*
X118218Y206286D01*
X118425Y206555D01*
X118528Y206823D01*
Y207091D01*
X118425Y207360D01*
X118270Y207590D01*
X118063Y207781D01*
G01Y209080D02*
X118321Y209310D01*
X118476Y209578D01*
X118528Y209923D01*
X118425Y210268D01*
X118218Y210536D01*
X117856Y210728D01*
X117443Y210766D01*
X117030Y210690D01*
X116771Y210498D01*
X116565Y210230D01*
X116513Y209961D01*
X116565Y209693D01*
X116771Y209348D01*
X115428Y209463D01*
Y210498D01*
G01Y213023D02*
X115531Y212716D01*
X115790Y212486D01*
X116100Y212333D01*
X116513Y212218D01*
X116978Y212180D01*
X117443Y212218D01*
X117856Y212333D01*
X118166Y212486D01*
X118425Y212716D01*
X118528Y213023D01*
X118425Y213330D01*
X118166Y213560D01*
X117856Y213713D01*
X117443Y213828D01*
X116978Y213866D01*
X116513Y213828D01*
X116100Y213713D01*
X115790Y213560D01*
X115531Y213330D01*
X115428Y213023D01*
G01X118528Y216583D02*
X115428D01*
X117650Y215165D01*
Y217081D01*
G01X103640Y225380D02*
X148080D01*
G01X103640Y235720D02*
Y225380D01*
G01X115054Y223535D02*
X114824Y223690D01*
X114556Y223793D01*
X114249D01*
X113904Y223638D01*
X113636Y223380D01*
X113444Y223070D01*
X113291Y222553D01*
X113253Y222088D01*
X113329Y221623D01*
X113444Y221313D01*
X113674Y221003D01*
X113943Y220796D01*
X114211Y220693D01*
X114479D01*
X114748Y220796D01*
X114978Y220951D01*
X115169Y221158D01*
G01X116468D02*
X116698Y220900D01*
X116966Y220745D01*
X117311Y220693D01*
X117656Y220796D01*
X117924Y221003D01*
X118116Y221365D01*
X118154Y221778D01*
X118078Y222191D01*
X117886Y222450D01*
X117618Y222656D01*
X117349Y222708D01*
X117081Y222656D01*
X116736Y222450D01*
X116851Y223793D01*
X117886D01*
G01X120411D02*
X120104Y223690D01*
X119874Y223431D01*
X119721Y223121D01*
X119606Y222708D01*
X119568Y222243D01*
X119606Y221778D01*
X119721Y221365D01*
X119874Y221055D01*
X120104Y220796D01*
X120411Y220693D01*
X120718Y220796D01*
X120948Y221055D01*
X121101Y221365D01*
X121216Y221778D01*
X121254Y222243D01*
X121216Y222708D01*
X121101Y223121D01*
X120948Y223431D01*
X120718Y223690D01*
X120411Y223793D01*
G01X123511Y220693D02*
Y223793D01*
X123051Y223173D01*
G01Y220693D02*
X123971D01*
G01X110828Y255671D02*
Y258771D01*
G01X112438D02*
Y255671D01*
G01Y257221D02*
X110828D01*
G01X113890Y256291D02*
X114120Y255929D01*
X114426Y255723D01*
X114771Y255671D01*
X115078Y255723D01*
X115385Y255981D01*
X115576Y256291D01*
X115615Y256601D01*
X115538Y256963D01*
X115270Y257221D01*
X115001Y257324D01*
X114656D01*
G01X115001D02*
X115231Y257479D01*
X115423Y257738D01*
X115500Y258048D01*
X115423Y258358D01*
X115231Y258616D01*
X114886Y258771D01*
X114541Y258719D01*
X114196Y258513D01*
G01X111625Y358377D02*
Y361477D01*
G01X113235D02*
Y358377D01*
G01Y359927D02*
X111625D01*
G01X115530Y358377D02*
Y361477D01*
X115070Y360857D01*
G01Y358377D02*
X115990D01*
G01X108937Y370235D02*
X108782Y370005D01*
X108679Y369737D01*
Y369430D01*
X108834Y369085D01*
X109092Y368817D01*
X109402Y368625D01*
X109919Y368472D01*
X110384Y368434D01*
X110849Y368510D01*
X111159Y368625D01*
X111469Y368855D01*
X111676Y369124D01*
X111779Y369392D01*
Y369660D01*
X111676Y369929D01*
X111521Y370159D01*
X111314Y370350D01*
G01Y371649D02*
X111572Y371879D01*
X111727Y372147D01*
X111779Y372492D01*
X111676Y372837D01*
X111469Y373105D01*
X111107Y373297D01*
X110694Y373335D01*
X110281Y373259D01*
X110022Y373067D01*
X109816Y372799D01*
X109764Y372530D01*
X109816Y372262D01*
X110022Y371917D01*
X108679Y372032D01*
Y373067D01*
G01X111159Y374749D02*
X111521Y374979D01*
X111727Y375285D01*
X111779Y375630D01*
X111727Y375937D01*
X111469Y376244D01*
X111159Y376435D01*
X110849Y376474D01*
X110487Y376397D01*
X110229Y376129D01*
X110126Y375860D01*
Y375515D01*
G01Y375860D02*
X109971Y376090D01*
X109712Y376282D01*
X109402Y376359D01*
X109092Y376282D01*
X108834Y376090D01*
X108679Y375745D01*
X108731Y375400D01*
X108937Y375055D01*
G01X111779Y378615D02*
X111107Y378692D01*
X110539Y378807D01*
X110022Y378960D01*
X109454Y379152D01*
X108679Y379459D01*
Y377925D01*
G01X101568Y375782D02*
Y369582D01*
G01X107436Y368515D02*
X104336D01*
Y369474D01*
X104491Y369780D01*
X104698Y369972D01*
X105111Y370049D01*
X105524Y369972D01*
X105783Y369742D01*
X105938Y369474D01*
Y368515D01*
G01Y369474D02*
X107436Y370049D01*
G01Y372382D02*
X104336D01*
X104956Y371922D01*
G01X107436D02*
Y372842D01*
G01Y375482D02*
X104336D01*
X104956Y375022D01*
G01X107436D02*
Y375942D01*
G01X106971Y377739D02*
X107229Y377969D01*
X107384Y378237D01*
X107436Y378582D01*
X107333Y378927D01*
X107126Y379195D01*
X106764Y379387D01*
X106351Y379425D01*
X105938Y379349D01*
X105679Y379157D01*
X105473Y378889D01*
X105421Y378620D01*
X105473Y378352D01*
X105679Y378007D01*
X104336Y378122D01*
Y379157D01*
G01X107436Y381682D02*
X104336D01*
X104956Y381222D01*
G01X107436D02*
Y382142D01*
G01X103351Y392168D02*
Y388368D01*
G01X107648Y389418D02*
X104548D01*
Y390377D01*
X104703Y390683D01*
X104910Y390875D01*
X105323Y390952D01*
X105736Y390875D01*
X105995Y390645D01*
X106150Y390377D01*
Y389418D01*
G01Y390377D02*
X107648Y390952D01*
G01Y393285D02*
X104548D01*
X105168Y392825D01*
G01X107648D02*
Y393745D01*
G01Y396385D02*
X104548D01*
X105168Y395925D01*
G01X107648D02*
Y396845D01*
G01X104548Y399485D02*
X104651Y399178D01*
X104910Y398948D01*
X105220Y398795D01*
X105633Y398680D01*
X106098Y398642D01*
X106563Y398680D01*
X106976Y398795D01*
X107286Y398948D01*
X107545Y399178D01*
X107648Y399485D01*
X107545Y399792D01*
X107286Y400022D01*
X106976Y400175D01*
X106563Y400290D01*
X106098Y400328D01*
X105633Y400290D01*
X105220Y400175D01*
X104910Y400022D01*
X104651Y399792D01*
X104548Y399485D01*
G01X106356Y401857D02*
X105995Y402125D01*
X105788Y402355D01*
X105685Y402662D01*
X105788Y402930D01*
X105995Y403122D01*
X106305Y403275D01*
X106666Y403313D01*
X106976Y403275D01*
X107286Y403122D01*
X107545Y402892D01*
X107648Y402623D01*
X107545Y402317D01*
X107235Y402048D01*
X106770Y401895D01*
X106253Y401857D01*
X105581Y401933D01*
X105220Y402048D01*
X104858Y402240D01*
X104600Y402508D01*
X104548Y402777D01*
X104651Y403045D01*
X104910Y403237D01*
G01X109099Y390423D02*
Y393623D01*
G01X115299Y390423D02*
X109099D01*
G01X115299Y393623D02*
Y390423D01*
G01X109099Y386378D02*
Y389578D01*
G01X115299Y386378D02*
X109099D01*
G01X115299Y389578D02*
Y386378D01*
G01X109099Y389578D02*
X115299D01*
G01X101551Y393968D02*
X103351Y392168D01*
G01Y395768D02*
X101551Y393968D01*
G01X103351Y399568D02*
Y395768D01*
G01X112020Y396659D02*
Y402859D01*
G01D02*
X115220D01*
G01D02*
Y396659D01*
G01D02*
X112020D01*
G01X115120Y399759D02*
X112120D01*
G01X110918Y407983D02*
Y404783D01*
G01X104718D02*
Y407983D01*
G01X110918Y404783D02*
X104718D01*
G01X109099Y393623D02*
X115299D01*
G01X117296Y396934D02*
Y399434D01*
X116976Y398934D01*
G01Y396934D02*
X117616D01*
G01X119496Y399434D02*
X119283Y399351D01*
X119123Y399142D01*
X119016Y398892D01*
X118936Y398559D01*
X118909Y398184D01*
X118936Y397809D01*
X119016Y397476D01*
X119123Y397226D01*
X119283Y397017D01*
X119496Y396934D01*
X119709Y397017D01*
X119869Y397226D01*
X119976Y397476D01*
X120056Y397809D01*
X120083Y398184D01*
X120056Y398559D01*
X119976Y398892D01*
X119869Y399142D01*
X119709Y399351D01*
X119496Y399434D01*
G01X103842Y411223D02*
X103687Y410993D01*
X103584Y410725D01*
Y410418D01*
X103739Y410073D01*
X103997Y409805D01*
X104307Y409613D01*
X104824Y409460D01*
X105289Y409422D01*
X105754Y409498D01*
X106064Y409613D01*
X106374Y409843D01*
X106581Y410112D01*
X106684Y410380D01*
Y410648D01*
X106581Y410917D01*
X106426Y411147D01*
X106219Y411338D01*
G01X106684Y413480D02*
X106632Y413748D01*
X106477Y414055D01*
X106219Y414247D01*
X105857Y414323D01*
X105496Y414247D01*
X105186Y414017D01*
X105031Y413672D01*
Y413288D01*
X104927Y413058D01*
X104669Y412867D01*
X104307Y412790D01*
X103946Y412905D01*
X103687Y413173D01*
X103584Y413480D01*
X103687Y413787D01*
X103946Y414055D01*
X104307Y414170D01*
X104669Y414093D01*
X104927Y413902D01*
X105031Y413672D01*
Y413288D01*
X105186Y412943D01*
X105496Y412713D01*
X105857Y412637D01*
X106219Y412713D01*
X106477Y412905D01*
X106632Y413212D01*
X106684Y413480D01*
G01Y416580D02*
X103584D01*
X104204Y416120D01*
G01X106684D02*
Y417040D01*
G01X106322Y419028D02*
X106581Y419297D01*
X106684Y419603D01*
X106581Y419910D01*
X106271Y420178D01*
X105806Y420370D01*
X105341Y420447D01*
X104772D01*
X104307Y420370D01*
X103894Y420178D01*
X103687Y419948D01*
X103584Y419680D01*
X103687Y419373D01*
X103894Y419143D01*
X104204Y418990D01*
X104617Y418913D01*
X104979Y418990D01*
X105341Y419182D01*
X105547Y419412D01*
X105599Y419680D01*
X105496Y419987D01*
X105237Y420217D01*
X104772Y420447D01*
G01X107742Y415024D02*
X110942D01*
G01X107842Y411924D02*
X110842D01*
G01X110942Y415024D02*
Y408824D01*
G01D02*
X107742D01*
G01D02*
Y415024D01*
G01X104718Y407983D02*
X110918D01*
G01X115442Y418411D02*
Y416189D01*
X115595Y415724D01*
X115902Y415414D01*
X116285Y415311D01*
X116668Y415414D01*
X116975Y415724D01*
X117128Y416189D01*
Y418411D01*
G01X119385Y415311D02*
Y418411D01*
X118925Y417791D01*
G01Y415311D02*
X119845D01*
G01X121757Y417894D02*
X121987Y418204D01*
X122255Y418359D01*
X122562Y418411D01*
X122945Y418308D01*
X123213Y418049D01*
X123290Y417739D01*
X123252Y417429D01*
X123098Y417171D01*
X122332Y416654D01*
X121987Y416293D01*
X121757Y415776D01*
X121680Y415311D01*
X123290D01*
G01X125585Y418411D02*
X125278Y418308D01*
X125048Y418049D01*
X124895Y417739D01*
X124780Y417326D01*
X124742Y416861D01*
X124780Y416396D01*
X124895Y415983D01*
X125048Y415673D01*
X125278Y415414D01*
X125585Y415311D01*
X125892Y415414D01*
X126122Y415673D01*
X126275Y415983D01*
X126390Y416396D01*
X126428Y416861D01*
X126390Y417326D01*
X126275Y417739D01*
X126122Y418049D01*
X125892Y418308D01*
X125585Y418411D01*
G01X105843Y433037D02*
Y436137D01*
X106763D01*
X107070Y435982D01*
X107300Y435620D01*
X107377Y435207D01*
X107300Y434794D01*
X107108Y434484D01*
X106763Y434329D01*
X105843D01*
G01X110553Y435879D02*
X110323Y436034D01*
X110055Y436137D01*
X109748D01*
X109403Y435982D01*
X109135Y435724D01*
X108943Y435414D01*
X108790Y434897D01*
X108752Y434432D01*
X108828Y433967D01*
X108943Y433657D01*
X109173Y433347D01*
X109442Y433140D01*
X109710Y433037D01*
X109978D01*
X110247Y433140D01*
X110477Y433295D01*
X110668Y433502D01*
G01X112082Y434329D02*
X112350Y434690D01*
X112580Y434897D01*
X112887Y435000D01*
X113155Y434897D01*
X113347Y434690D01*
X113500Y434380D01*
X113538Y434019D01*
X113500Y433709D01*
X113347Y433399D01*
X113117Y433140D01*
X112848Y433037D01*
X112542Y433140D01*
X112273Y433450D01*
X112120Y433915D01*
X112082Y434432D01*
X112158Y435104D01*
X112273Y435465D01*
X112465Y435827D01*
X112733Y436085D01*
X113002Y436137D01*
X113270Y436034D01*
X113462Y435775D01*
G01X115833Y433037D02*
X115910Y433709D01*
X116025Y434277D01*
X116178Y434794D01*
X116370Y435362D01*
X116677Y436137D01*
X115143D01*
G01X101365Y439343D02*
Y432543D01*
G01X105213Y425597D02*
Y428697D01*
X106133D01*
X106440Y428542D01*
X106670Y428180D01*
X106747Y427767D01*
X106670Y427354D01*
X106478Y427044D01*
X106133Y426889D01*
X105213D01*
G01X109923Y428439D02*
X109693Y428594D01*
X109425Y428697D01*
X109118D01*
X108773Y428542D01*
X108505Y428284D01*
X108313Y427974D01*
X108160Y427457D01*
X108122Y426992D01*
X108198Y426527D01*
X108313Y426217D01*
X108543Y425907D01*
X108812Y425700D01*
X109080Y425597D01*
X109348D01*
X109617Y425700D01*
X109847Y425855D01*
X110038Y426062D01*
G01X111452Y426889D02*
X111720Y427250D01*
X111950Y427457D01*
X112257Y427560D01*
X112525Y427457D01*
X112717Y427250D01*
X112870Y426940D01*
X112908Y426579D01*
X112870Y426269D01*
X112717Y425959D01*
X112487Y425700D01*
X112218Y425597D01*
X111912Y425700D01*
X111643Y426010D01*
X111490Y426475D01*
X111452Y426992D01*
X111528Y427664D01*
X111643Y428025D01*
X111835Y428387D01*
X112103Y428645D01*
X112372Y428697D01*
X112640Y428594D01*
X112832Y428335D01*
G01X114552Y426889D02*
X114820Y427250D01*
X115050Y427457D01*
X115357Y427560D01*
X115625Y427457D01*
X115817Y427250D01*
X115970Y426940D01*
X116008Y426579D01*
X115970Y426269D01*
X115817Y425959D01*
X115587Y425700D01*
X115318Y425597D01*
X115012Y425700D01*
X114743Y426010D01*
X114590Y426475D01*
X114552Y426992D01*
X114628Y427664D01*
X114743Y428025D01*
X114935Y428387D01*
X115203Y428645D01*
X115472Y428697D01*
X115740Y428594D01*
X115932Y428335D01*
G01X101365Y430343D02*
Y423543D01*
G01X101387Y448343D02*
Y441543D01*
G01X105973Y442806D02*
Y445906D01*
X106893D01*
X107200Y445751D01*
X107430Y445389D01*
X107507Y444976D01*
X107430Y444563D01*
X107238Y444253D01*
X106893Y444098D01*
X105973D01*
G01X110683Y445648D02*
X110453Y445803D01*
X110185Y445906D01*
X109878D01*
X109533Y445751D01*
X109265Y445493D01*
X109073Y445183D01*
X108920Y444666D01*
X108882Y444201D01*
X108958Y443736D01*
X109073Y443426D01*
X109303Y443116D01*
X109572Y442909D01*
X109840Y442806D01*
X110108D01*
X110377Y442909D01*
X110607Y443064D01*
X110798Y443271D01*
G01X112212Y444098D02*
X112480Y444459D01*
X112710Y444666D01*
X113017Y444769D01*
X113285Y444666D01*
X113477Y444459D01*
X113630Y444149D01*
X113668Y443788D01*
X113630Y443478D01*
X113477Y443168D01*
X113247Y442909D01*
X112978Y442806D01*
X112672Y442909D01*
X112403Y443219D01*
X112250Y443684D01*
X112212Y444201D01*
X112288Y444873D01*
X112403Y445234D01*
X112595Y445596D01*
X112863Y445854D01*
X113132Y445906D01*
X113400Y445803D01*
X113592Y445544D01*
G01X116040Y442806D02*
X116308Y442858D01*
X116615Y443013D01*
X116807Y443271D01*
X116883Y443633D01*
X116807Y443994D01*
X116577Y444304D01*
X116232Y444459D01*
X115848D01*
X115618Y444563D01*
X115427Y444821D01*
X115350Y445183D01*
X115465Y445544D01*
X115733Y445803D01*
X116040Y445906D01*
X116347Y445803D01*
X116615Y445544D01*
X116730Y445183D01*
X116653Y444821D01*
X116462Y444563D01*
X116232Y444459D01*
X115848D01*
X115503Y444304D01*
X115273Y443994D01*
X115197Y443633D01*
X115273Y443271D01*
X115465Y443013D01*
X115772Y442858D01*
X116040Y442806D01*
G01X107823Y453267D02*
Y456367D01*
X108782D01*
X109088Y456212D01*
X109280Y456005D01*
X109357Y455592D01*
X109280Y455179D01*
X109050Y454920D01*
X108782Y454765D01*
X107823D01*
G01X108782D02*
X109357Y453267D01*
G01X111690D02*
Y456367D01*
X111230Y455747D01*
G01Y453267D02*
X112150D01*
G01X114062Y455850D02*
X114292Y456160D01*
X114560Y456315D01*
X114867Y456367D01*
X115250Y456264D01*
X115518Y456005D01*
X115595Y455695D01*
X115557Y455385D01*
X115403Y455127D01*
X114637Y454610D01*
X114292Y454249D01*
X114062Y453732D01*
X113985Y453267D01*
X115595D01*
G01X118350D02*
Y456367D01*
X116932Y454145D01*
X118848D01*
G01X120990Y456367D02*
X120683Y456264D01*
X120453Y456005D01*
X120300Y455695D01*
X120185Y455282D01*
X120147Y454817D01*
X120185Y454352D01*
X120300Y453939D01*
X120453Y453629D01*
X120683Y453370D01*
X120990Y453267D01*
X121297Y453370D01*
X121527Y453629D01*
X121680Y453939D01*
X121795Y454352D01*
X121833Y454817D01*
X121795Y455282D01*
X121680Y455695D01*
X121527Y456005D01*
X121297Y456264D01*
X120990Y456367D01*
G01X109864Y471149D02*
X109709Y470919D01*
X109606Y470651D01*
Y470344D01*
X109761Y469999D01*
X110019Y469731D01*
X110329Y469539D01*
X110846Y469386D01*
X111311Y469348D01*
X111776Y469424D01*
X112086Y469539D01*
X112396Y469769D01*
X112603Y470038D01*
X112706Y470306D01*
Y470574D01*
X112603Y470843D01*
X112448Y471073D01*
X112241Y471264D01*
G01X112706Y473406D02*
X112654Y473674D01*
X112499Y473981D01*
X112241Y474173D01*
X111879Y474249D01*
X111518Y474173D01*
X111208Y473943D01*
X111053Y473598D01*
Y473214D01*
X110949Y472984D01*
X110691Y472793D01*
X110329Y472716D01*
X109968Y472831D01*
X109709Y473099D01*
X109606Y473406D01*
X109709Y473713D01*
X109968Y473981D01*
X110329Y474096D01*
X110691Y474019D01*
X110949Y473828D01*
X111053Y473598D01*
Y473214D01*
X111208Y472869D01*
X111518Y472639D01*
X111879Y472563D01*
X112241Y472639D01*
X112499Y472831D01*
X112654Y473138D01*
X112706Y473406D01*
G01X110123Y475778D02*
X109813Y476008D01*
X109658Y476276D01*
X109606Y476583D01*
X109709Y476966D01*
X109968Y477234D01*
X110278Y477311D01*
X110588Y477273D01*
X110846Y477119D01*
X111363Y476353D01*
X111724Y476008D01*
X112241Y475778D01*
X112706Y475701D01*
Y477311D01*
G01Y479606D02*
X112654Y479874D01*
X112499Y480181D01*
X112241Y480373D01*
X111879Y480449D01*
X111518Y480373D01*
X111208Y480143D01*
X111053Y479798D01*
Y479414D01*
X110949Y479184D01*
X110691Y478993D01*
X110329Y478916D01*
X109968Y479031D01*
X109709Y479299D01*
X109606Y479606D01*
X109709Y479913D01*
X109968Y480181D01*
X110329Y480296D01*
X110691Y480219D01*
X110949Y480028D01*
X111053Y479798D01*
Y479414D01*
X111208Y479069D01*
X111518Y478839D01*
X111879Y478763D01*
X112241Y478839D01*
X112499Y479031D01*
X112654Y479338D01*
X112706Y479606D01*
G01X105704Y471149D02*
X105549Y470919D01*
X105446Y470651D01*
Y470344D01*
X105601Y469999D01*
X105859Y469731D01*
X106169Y469539D01*
X106686Y469386D01*
X107151Y469348D01*
X107616Y469424D01*
X107926Y469539D01*
X108236Y469769D01*
X108443Y470038D01*
X108546Y470306D01*
Y470574D01*
X108443Y470843D01*
X108288Y471073D01*
X108081Y471264D01*
G01X108546Y473406D02*
X108494Y473674D01*
X108339Y473981D01*
X108081Y474173D01*
X107719Y474249D01*
X107358Y474173D01*
X107048Y473943D01*
X106893Y473598D01*
Y473214D01*
X106789Y472984D01*
X106531Y472793D01*
X106169Y472716D01*
X105808Y472831D01*
X105549Y473099D01*
X105446Y473406D01*
X105549Y473713D01*
X105808Y473981D01*
X106169Y474096D01*
X106531Y474019D01*
X106789Y473828D01*
X106893Y473598D01*
Y473214D01*
X107048Y472869D01*
X107358Y472639D01*
X107719Y472563D01*
X108081Y472639D01*
X108339Y472831D01*
X108494Y473138D01*
X108546Y473406D01*
G01X105963Y475778D02*
X105653Y476008D01*
X105498Y476276D01*
X105446Y476583D01*
X105549Y476966D01*
X105808Y477234D01*
X106118Y477311D01*
X106428Y477273D01*
X106686Y477119D01*
X107203Y476353D01*
X107564Y476008D01*
X108081Y475778D01*
X108546Y475701D01*
Y477311D01*
G01X108184Y478954D02*
X108443Y479223D01*
X108546Y479529D01*
X108443Y479836D01*
X108133Y480104D01*
X107668Y480296D01*
X107203Y480373D01*
X106634D01*
X106169Y480296D01*
X105756Y480104D01*
X105549Y479874D01*
X105446Y479606D01*
X105549Y479299D01*
X105756Y479069D01*
X106066Y478916D01*
X106479Y478839D01*
X106841Y478916D01*
X107203Y479108D01*
X107409Y479338D01*
X107461Y479606D01*
X107358Y479913D01*
X107099Y480143D01*
X106634Y480373D01*
G01X109097Y459962D02*
X108867Y460117D01*
X108599Y460220D01*
X108292D01*
X107947Y460065D01*
X107679Y459807D01*
X107487Y459497D01*
X107334Y458980D01*
X107296Y458515D01*
X107372Y458050D01*
X107487Y457740D01*
X107717Y457430D01*
X107986Y457223D01*
X108254Y457120D01*
X108522D01*
X108791Y457223D01*
X109021Y457378D01*
X109212Y457585D01*
G01X111354Y457120D02*
X111622Y457172D01*
X111929Y457327D01*
X112121Y457585D01*
X112197Y457947D01*
X112121Y458308D01*
X111891Y458618D01*
X111546Y458773D01*
X111162D01*
X110932Y458877D01*
X110741Y459135D01*
X110664Y459497D01*
X110779Y459858D01*
X111047Y460117D01*
X111354Y460220D01*
X111661Y460117D01*
X111929Y459858D01*
X112044Y459497D01*
X111967Y459135D01*
X111776Y458877D01*
X111546Y458773D01*
X111162D01*
X110817Y458618D01*
X110587Y458308D01*
X110511Y457947D01*
X110587Y457585D01*
X110779Y457327D01*
X111086Y457172D01*
X111354Y457120D01*
G01X113611Y457585D02*
X113841Y457327D01*
X114109Y457172D01*
X114454Y457120D01*
X114799Y457223D01*
X115067Y457430D01*
X115259Y457792D01*
X115297Y458205D01*
X115221Y458618D01*
X115029Y458877D01*
X114761Y459083D01*
X114492Y459135D01*
X114224Y459083D01*
X113879Y458877D01*
X113994Y460220D01*
X115029D01*
G01X117554D02*
X117247Y460117D01*
X117017Y459858D01*
X116864Y459548D01*
X116749Y459135D01*
X116711Y458670D01*
X116749Y458205D01*
X116864Y457792D01*
X117017Y457482D01*
X117247Y457223D01*
X117554Y457120D01*
X117861Y457223D01*
X118091Y457482D01*
X118244Y457792D01*
X118359Y458205D01*
X118397Y458670D01*
X118359Y459135D01*
X118244Y459548D01*
X118091Y459858D01*
X117861Y460117D01*
X117554Y460220D01*
G01X104296Y469539D02*
X101196D01*
Y470498D01*
X101351Y470804D01*
X101558Y470996D01*
X101971Y471073D01*
X102384Y470996D01*
X102643Y470766D01*
X102798Y470498D01*
Y469539D01*
G01Y470498D02*
X104296Y471073D01*
G01Y473406D02*
X101196D01*
X101816Y472946D01*
G01X104296D02*
Y473866D01*
G01X101713Y475778D02*
X101403Y476008D01*
X101248Y476276D01*
X101196Y476583D01*
X101299Y476966D01*
X101558Y477234D01*
X101868Y477311D01*
X102178Y477273D01*
X102436Y477119D01*
X102953Y476353D01*
X103314Y476008D01*
X103831Y475778D01*
X104296Y475701D01*
Y477311D01*
G01X103676Y478763D02*
X104038Y478993D01*
X104244Y479299D01*
X104296Y479644D01*
X104244Y479951D01*
X103986Y480258D01*
X103676Y480449D01*
X103366Y480488D01*
X103004Y480411D01*
X102746Y480143D01*
X102643Y479874D01*
Y479529D01*
G01Y479874D02*
X102488Y480104D01*
X102229Y480296D01*
X101919Y480373D01*
X101609Y480296D01*
X101351Y480104D01*
X101196Y479759D01*
X101248Y479414D01*
X101454Y479069D01*
G01X103676Y481863D02*
X104038Y482093D01*
X104244Y482399D01*
X104296Y482744D01*
X104244Y483051D01*
X103986Y483358D01*
X103676Y483549D01*
X103366Y483588D01*
X103004Y483511D01*
X102746Y483243D01*
X102643Y482974D01*
Y482629D01*
G01Y482974D02*
X102488Y483204D01*
X102229Y483396D01*
X101919Y483473D01*
X101609Y483396D01*
X101351Y483204D01*
X101196Y482859D01*
X101248Y482514D01*
X101454Y482169D01*
G01X107953Y465437D02*
Y468537D01*
X108912D01*
X109218Y468382D01*
X109410Y468175D01*
X109487Y467762D01*
X109410Y467349D01*
X109180Y467090D01*
X108912Y466935D01*
X107953D01*
G01X108912D02*
X109487Y465437D01*
G01X111820D02*
Y468537D01*
X111360Y467917D01*
G01Y465437D02*
X112280D01*
G01X114920D02*
Y468537D01*
X114460Y467917D01*
G01Y465437D02*
X115380D01*
G01X118020D02*
Y468537D01*
X117560Y467917D01*
G01Y465437D02*
X118480D01*
G01X121043D02*
X121120Y466109D01*
X121235Y466677D01*
X121388Y467194D01*
X121580Y467762D01*
X121887Y468537D01*
X120353D01*
G01X107577Y461479D02*
Y464579D01*
X108536D01*
X108842Y464424D01*
X109034Y464217D01*
X109111Y463804D01*
X109034Y463391D01*
X108804Y463132D01*
X108536Y462977D01*
X107577D01*
G01X108536D02*
X109111Y461479D01*
G01X111444D02*
Y464579D01*
X110984Y463959D01*
G01Y461479D02*
X111904D01*
G01X114544D02*
Y464579D01*
X114084Y463959D01*
G01Y461479D02*
X115004D01*
G01X117644D02*
Y464579D01*
X117184Y463959D01*
G01Y461479D02*
X118104D01*
G01X120016Y462771D02*
X120284Y463132D01*
X120514Y463339D01*
X120821Y463442D01*
X121089Y463339D01*
X121281Y463132D01*
X121434Y462822D01*
X121472Y462461D01*
X121434Y462151D01*
X121281Y461841D01*
X121051Y461582D01*
X120782Y461479D01*
X120476Y461582D01*
X120207Y461892D01*
X120054Y462357D01*
X120016Y462874D01*
X120092Y463546D01*
X120207Y463907D01*
X120399Y464269D01*
X120667Y464527D01*
X120936Y464579D01*
X121204Y464476D01*
X121396Y464217D01*
G01X116672Y473333D02*
Y488333D01*
G01X123472Y473333D02*
X116672D01*
G01X123372Y480833D02*
X116772D01*
G01X113572Y485333D02*
X110572D01*
G01X113672Y482233D02*
X110472D01*
G01X113672Y488433D02*
Y482233D01*
G01X110472D02*
Y488433D01*
G01X106426Y482186D02*
Y488386D01*
G01X109626Y482186D02*
X106426D01*
G01X109626Y488386D02*
Y482186D01*
G01X116672Y488333D02*
X123472D01*
G01X110472Y488433D02*
X113672D01*
G01X106426Y488386D02*
X109626D01*
G01X108808Y496267D02*
X105708D01*
Y497226D01*
X105863Y497532D01*
X106070Y497724D01*
X106483Y497801D01*
X106896Y497724D01*
X107155Y497494D01*
X107310Y497226D01*
Y496267D01*
G01Y497226D02*
X108808Y497801D01*
G01Y500134D02*
X105708D01*
X106328Y499674D01*
G01X108808D02*
Y500594D01*
G01X106225Y502506D02*
X105915Y502736D01*
X105760Y503004D01*
X105708Y503311D01*
X105811Y503694D01*
X106070Y503962D01*
X106380Y504039D01*
X106690Y504001D01*
X106948Y503847D01*
X107465Y503081D01*
X107826Y502736D01*
X108343Y502506D01*
X108808Y502429D01*
Y504039D01*
G01X108188Y505491D02*
X108550Y505721D01*
X108756Y506027D01*
X108808Y506372D01*
X108756Y506679D01*
X108498Y506986D01*
X108188Y507177D01*
X107878Y507216D01*
X107516Y507139D01*
X107258Y506871D01*
X107155Y506602D01*
Y506257D01*
G01Y506602D02*
X107000Y506832D01*
X106741Y507024D01*
X106431Y507101D01*
X106121Y507024D01*
X105863Y506832D01*
X105708Y506487D01*
X105760Y506142D01*
X105966Y505797D01*
G01X108446Y508782D02*
X108705Y509051D01*
X108808Y509357D01*
X108705Y509664D01*
X108395Y509932D01*
X107930Y510124D01*
X107465Y510201D01*
X106896D01*
X106431Y510124D01*
X106018Y509932D01*
X105811Y509702D01*
X105708Y509434D01*
X105811Y509127D01*
X106018Y508897D01*
X106328Y508744D01*
X106741Y508667D01*
X107103Y508744D01*
X107465Y508936D01*
X107671Y509166D01*
X107723Y509434D01*
X107620Y509741D01*
X107361Y509971D01*
X106896Y510201D01*
G01X105094Y497590D02*
X101994D01*
Y498510D01*
X102149Y498817D01*
X102511Y499047D01*
X102924Y499124D01*
X103337Y499047D01*
X103647Y498855D01*
X103802Y498510D01*
Y497590D01*
G01X104474Y500690D02*
X104784Y500882D01*
X104991Y501112D01*
X105094Y501380D01*
X104991Y501687D01*
X104784Y501917D01*
X104474Y502147D01*
X104061Y502224D01*
X101994D01*
G01X103802Y503829D02*
X103441Y504097D01*
X103234Y504327D01*
X103131Y504634D01*
X103234Y504902D01*
X103441Y505094D01*
X103751Y505247D01*
X104112Y505285D01*
X104422Y505247D01*
X104732Y505094D01*
X104991Y504864D01*
X105094Y504595D01*
X104991Y504289D01*
X104681Y504020D01*
X104216Y503867D01*
X103699Y503829D01*
X103027Y503905D01*
X102666Y504020D01*
X102304Y504212D01*
X102046Y504480D01*
X101994Y504749D01*
X102097Y505017D01*
X102356Y505209D01*
G01X116364Y489643D02*
X116073Y489830D01*
X115906Y489990D01*
X115823Y490203D01*
X115906Y490390D01*
X116073Y490523D01*
X116323Y490630D01*
X116614Y490657D01*
X116864Y490630D01*
X117114Y490523D01*
X117323Y490363D01*
X117406Y490177D01*
X117323Y489963D01*
X117073Y489777D01*
X116698Y489670D01*
X116281Y489643D01*
X115739Y489697D01*
X115448Y489777D01*
X115156Y489910D01*
X114948Y490097D01*
X114906Y490283D01*
X114989Y490470D01*
X115198Y490603D01*
G01X114631Y493226D02*
Y505234D01*
G01Y493226D02*
X115435D01*
G01X114631Y495330D02*
Y493226D01*
G01X104640Y513817D02*
X104485Y513587D01*
X104382Y513319D01*
Y513012D01*
X104537Y512667D01*
X104795Y512399D01*
X105105Y512207D01*
X105622Y512054D01*
X106087Y512016D01*
X106552Y512092D01*
X106862Y512207D01*
X107172Y512437D01*
X107379Y512706D01*
X107482Y512974D01*
Y513242D01*
X107379Y513511D01*
X107224Y513741D01*
X107017Y513932D01*
G01X107482Y516074D02*
X107430Y516342D01*
X107275Y516649D01*
X107017Y516841D01*
X106655Y516917D01*
X106294Y516841D01*
X105984Y516611D01*
X105829Y516266D01*
Y515882D01*
X105725Y515652D01*
X105467Y515461D01*
X105105Y515384D01*
X104744Y515499D01*
X104485Y515767D01*
X104382Y516074D01*
X104485Y516381D01*
X104744Y516649D01*
X105105Y516764D01*
X105467Y516687D01*
X105725Y516496D01*
X105829Y516266D01*
Y515882D01*
X105984Y515537D01*
X106294Y515307D01*
X106655Y515231D01*
X107017Y515307D01*
X107275Y515499D01*
X107430Y515806D01*
X107482Y516074D01*
G01X106862Y518331D02*
X107224Y518561D01*
X107430Y518867D01*
X107482Y519212D01*
X107430Y519519D01*
X107172Y519826D01*
X106862Y520017D01*
X106552Y520056D01*
X106190Y519979D01*
X105932Y519711D01*
X105829Y519442D01*
Y519097D01*
G01Y519442D02*
X105674Y519672D01*
X105415Y519864D01*
X105105Y519941D01*
X104795Y519864D01*
X104537Y519672D01*
X104382Y519327D01*
X104434Y518982D01*
X104640Y518637D01*
G01X107482Y522734D02*
X104382D01*
X106604Y521316D01*
Y523232D01*
G01X115872Y514133D02*
X112872D01*
G01X115972Y511033D02*
X112772D01*
G01X115972Y517233D02*
Y511033D01*
G01X112772Y517233D02*
X115972D01*
G01X112772Y511033D02*
Y517233D01*
G01X111572Y511033D02*
X108372D01*
G01X111572Y517233D02*
Y511033D01*
G01X108372Y517233D02*
X111572D01*
G01X108372Y511033D02*
Y517233D01*
G01X116960Y507844D02*
X117168Y508004D01*
X117293Y508191D01*
X117335Y508431D01*
X117252Y508671D01*
X117085Y508858D01*
X116793Y508991D01*
X116460Y509018D01*
X116127Y508964D01*
X115918Y508831D01*
X115752Y508644D01*
X115710Y508458D01*
X115752Y508271D01*
X115918Y508031D01*
X114835Y508111D01*
Y508831D01*
G01X114631Y505234D02*
Y502730D01*
G01X115435Y505234D02*
X114631D01*
G01X117297Y536836D02*
X117067Y536991D01*
X116799Y537094D01*
X116492D01*
X116147Y536939D01*
X115879Y536681D01*
X115687Y536371D01*
X115534Y535854D01*
X115496Y535389D01*
X115572Y534924D01*
X115687Y534614D01*
X115917Y534304D01*
X116186Y534097D01*
X116454Y533994D01*
X116722D01*
X116991Y534097D01*
X117221Y534252D01*
X117412Y534459D01*
G01X119554Y533994D02*
X119822Y534046D01*
X120129Y534201D01*
X120321Y534459D01*
X120397Y534821D01*
X120321Y535182D01*
X120091Y535492D01*
X119746Y535647D01*
X119362D01*
X119132Y535751D01*
X118941Y536009D01*
X118864Y536371D01*
X118979Y536732D01*
X119247Y536991D01*
X119554Y537094D01*
X119861Y536991D01*
X120129Y536732D01*
X120244Y536371D01*
X120167Y536009D01*
X119976Y535751D01*
X119746Y535647D01*
X119362D01*
X119017Y535492D01*
X118787Y535182D01*
X118711Y534821D01*
X118787Y534459D01*
X118979Y534201D01*
X119286Y534046D01*
X119554Y533994D01*
G01X121811Y534614D02*
X122041Y534252D01*
X122347Y534046D01*
X122692Y533994D01*
X122999Y534046D01*
X123306Y534304D01*
X123497Y534614D01*
X123536Y534924D01*
X123459Y535286D01*
X123191Y535544D01*
X122922Y535647D01*
X122577D01*
G01X122922D02*
X123152Y535802D01*
X123344Y536061D01*
X123421Y536371D01*
X123344Y536681D01*
X123152Y536939D01*
X122807Y537094D01*
X122462Y537042D01*
X122117Y536836D01*
G01X124911Y534614D02*
X125141Y534252D01*
X125447Y534046D01*
X125792Y533994D01*
X126099Y534046D01*
X126406Y534304D01*
X126597Y534614D01*
X126636Y534924D01*
X126559Y535286D01*
X126291Y535544D01*
X126022Y535647D01*
X125677D01*
G01X126022D02*
X126252Y535802D01*
X126444Y536061D01*
X126521Y536371D01*
X126444Y536681D01*
X126252Y536939D01*
X125907Y537094D01*
X125562Y537042D01*
X125217Y536836D01*
G01X111080Y537502D02*
Y532902D01*
G01X105980D02*
Y537502D01*
G01X115687Y529961D02*
Y533061D01*
X116646D01*
X116952Y532906D01*
X117144Y532699D01*
X117221Y532286D01*
X117144Y531873D01*
X116914Y531614D01*
X116646Y531459D01*
X115687D01*
G01X116646D02*
X117221Y529961D01*
G01X119554D02*
Y533061D01*
X119094Y532441D01*
G01Y529961D02*
X120014D01*
G01X122654Y533061D02*
X122347Y532958D01*
X122117Y532699D01*
X121964Y532389D01*
X121849Y531976D01*
X121811Y531511D01*
X121849Y531046D01*
X121964Y530633D01*
X122117Y530323D01*
X122347Y530064D01*
X122654Y529961D01*
X122961Y530064D01*
X123191Y530323D01*
X123344Y530633D01*
X123459Y531046D01*
X123497Y531511D01*
X123459Y531976D01*
X123344Y532389D01*
X123191Y532699D01*
X122961Y532958D01*
X122654Y533061D01*
G01X125102Y530323D02*
X125371Y530064D01*
X125677Y529961D01*
X125984Y530064D01*
X126252Y530374D01*
X126444Y530839D01*
X126521Y531304D01*
Y531873D01*
X126444Y532338D01*
X126252Y532751D01*
X126022Y532958D01*
X125754Y533061D01*
X125447Y532958D01*
X125217Y532751D01*
X125064Y532441D01*
X124987Y532028D01*
X125064Y531666D01*
X125256Y531304D01*
X125486Y531098D01*
X125754Y531046D01*
X126061Y531149D01*
X126291Y531408D01*
X126521Y531873D01*
G01X128011Y530426D02*
X128241Y530168D01*
X128509Y530013D01*
X128854Y529961D01*
X129199Y530064D01*
X129467Y530271D01*
X129659Y530633D01*
X129697Y531046D01*
X129621Y531459D01*
X129429Y531718D01*
X129161Y531924D01*
X128892Y531976D01*
X128624Y531924D01*
X128279Y531718D01*
X128394Y533061D01*
X129429D01*
G01X115687Y525746D02*
Y528846D01*
X116607D01*
X116914Y528691D01*
X117144Y528329D01*
X117221Y527916D01*
X117144Y527503D01*
X116952Y527193D01*
X116607Y527038D01*
X115687D01*
G01X118787Y525746D02*
Y528846D01*
X119746D01*
X120052Y528691D01*
X120244Y528484D01*
X120321Y528071D01*
X120244Y527658D01*
X120014Y527399D01*
X119746Y527244D01*
X118787D01*
G01X119746D02*
X120321Y525746D01*
G01X122654D02*
Y528846D01*
X122194Y528226D01*
G01Y525746D02*
X123114D01*
G01X125677D02*
X125754Y526418D01*
X125869Y526986D01*
X126022Y527503D01*
X126214Y528071D01*
X126521Y528846D01*
X124987D01*
G01X117503Y543939D02*
X117273Y544094D01*
X117005Y544197D01*
X116698D01*
X116353Y544042D01*
X116085Y543784D01*
X115893Y543474D01*
X115740Y542957D01*
X115702Y542492D01*
X115778Y542027D01*
X115893Y541717D01*
X116123Y541407D01*
X116392Y541200D01*
X116660Y541097D01*
X116928D01*
X117197Y541200D01*
X117427Y541355D01*
X117618Y541562D01*
G01X120220Y541097D02*
Y544197D01*
X118802Y541975D01*
X120718D01*
G01X122017Y541717D02*
X122247Y541355D01*
X122553Y541149D01*
X122898Y541097D01*
X123205Y541149D01*
X123512Y541407D01*
X123703Y541717D01*
X123742Y542027D01*
X123665Y542389D01*
X123397Y542647D01*
X123128Y542750D01*
X122783D01*
G01X123128D02*
X123358Y542905D01*
X123550Y543164D01*
X123627Y543474D01*
X123550Y543784D01*
X123358Y544042D01*
X123013Y544197D01*
X122668Y544145D01*
X122323Y543939D01*
G01X125960Y541097D02*
Y544197D01*
X125500Y543577D01*
G01Y541097D02*
X126420D01*
G01X105980Y546002D02*
Y539402D01*
G01X113480Y546102D02*
Y539302D01*
G01X118465Y560639D02*
X113865D01*
G01D02*
Y570839D01*
G01X113830Y554837D02*
X113523Y554889D01*
X113255Y555095D01*
X113025Y555405D01*
X112872Y555767D01*
X112795Y556180D01*
Y556594D01*
X112872Y557007D01*
X113025Y557369D01*
X113255Y557679D01*
X113523Y557885D01*
X113830Y557937D01*
X114137Y557885D01*
X114405Y557679D01*
X114635Y557369D01*
X114788Y557007D01*
X114865Y556594D01*
Y556180D01*
X114788Y555767D01*
X114635Y555405D01*
X114405Y555095D01*
X114137Y554889D01*
X113830Y554837D01*
G01X114137Y555664D02*
X114597Y554837D01*
G01X116930D02*
Y557937D01*
X116470Y557317D01*
G01Y554837D02*
X117390D01*
G01X119187Y555302D02*
X119417Y555044D01*
X119685Y554889D01*
X120030Y554837D01*
X120375Y554940D01*
X120643Y555147D01*
X120835Y555509D01*
X120873Y555922D01*
X120797Y556335D01*
X120605Y556594D01*
X120337Y556800D01*
X120068Y556852D01*
X119800Y556800D01*
X119455Y556594D01*
X119570Y557937D01*
X120605D01*
G01X110350Y557702D02*
Y570702D01*
G01X113865Y565739D02*
X118465D01*
G01X113865Y570839D02*
X118465D01*
G01X120083Y573827D02*
X112683D01*
G01D02*
Y591227D01*
G01X103227Y599691D02*
Y594691D01*
X105761D01*
G01X108011D02*
X109594Y599691D01*
X111177Y594691D01*
G01X110607Y596441D02*
X108581D01*
G01X113237Y594691D02*
Y599691D01*
X116151Y594691D01*
Y599691D01*
G01X119794Y594691D02*
Y599691D01*
X119034Y598691D01*
G01Y594691D02*
X120554D01*
G01X103180Y600875D02*
X121461D01*
Y593676D01*
X102192D01*
Y600875D01*
X103180D01*
G01X112683Y591227D02*
X120083D01*
G01X112540Y609150D02*
Y619490D01*
G01X144480Y609150D02*
X112540D01*
G01X115402Y612845D02*
X115172Y613000D01*
X114904Y613103D01*
X114597D01*
X114252Y612948D01*
X113984Y612690D01*
X113792Y612380D01*
X113639Y611863D01*
X113601Y611398D01*
X113677Y610933D01*
X113792Y610623D01*
X114022Y610313D01*
X114291Y610106D01*
X114559Y610003D01*
X114827D01*
X115096Y610106D01*
X115326Y610261D01*
X115517Y610468D01*
G01X116931Y612586D02*
X117161Y612896D01*
X117429Y613051D01*
X117736Y613103D01*
X118119Y613000D01*
X118387Y612741D01*
X118464Y612431D01*
X118426Y612121D01*
X118272Y611863D01*
X117506Y611346D01*
X117161Y610985D01*
X116931Y610468D01*
X116854Y610003D01*
X118464D01*
G01X120031Y611295D02*
X120299Y611656D01*
X120529Y611863D01*
X120836Y611966D01*
X121104Y611863D01*
X121296Y611656D01*
X121449Y611346D01*
X121487Y610985D01*
X121449Y610675D01*
X121296Y610365D01*
X121066Y610106D01*
X120797Y610003D01*
X120491Y610106D01*
X120222Y610416D01*
X120069Y610881D01*
X120031Y611398D01*
X120107Y612070D01*
X120222Y612431D01*
X120414Y612793D01*
X120682Y613051D01*
X120951Y613103D01*
X121219Y613000D01*
X121411Y612741D01*
G01X123131Y612586D02*
X123361Y612896D01*
X123629Y613051D01*
X123936Y613103D01*
X124319Y613000D01*
X124587Y612741D01*
X124664Y612431D01*
X124626Y612121D01*
X124472Y611863D01*
X123706Y611346D01*
X123361Y610985D01*
X123131Y610468D01*
X123054Y610003D01*
X124664D01*
G01X112540Y619490D02*
X125440D01*
G01X113841Y614456D02*
Y617556D01*
X114800D01*
X115106Y617401D01*
X115298Y617194D01*
X115375Y616781D01*
X115298Y616368D01*
X115068Y616109D01*
X114800Y615954D01*
X113841D01*
G01X114800D02*
X115375Y614456D01*
G01X116865Y615076D02*
X117095Y614714D01*
X117401Y614508D01*
X117746Y614456D01*
X118053Y614508D01*
X118360Y614766D01*
X118551Y615076D01*
X118590Y615386D01*
X118513Y615748D01*
X118245Y616006D01*
X117976Y616109D01*
X117631D01*
G01X117976D02*
X118206Y616264D01*
X118398Y616523D01*
X118475Y616833D01*
X118398Y617143D01*
X118206Y617401D01*
X117861Y617556D01*
X117516Y617504D01*
X117171Y617298D01*
G01X120808Y614456D02*
Y617556D01*
X120348Y616936D01*
G01Y614456D02*
X121268D01*
G01X124368D02*
Y617556D01*
X122950Y615334D01*
X124866D01*
G01X112503Y641485D02*
Y644585D01*
X113462D01*
X113768Y644430D01*
X113960Y644223D01*
X114037Y643810D01*
X113960Y643397D01*
X113730Y643138D01*
X113462Y642983D01*
X112503D01*
G01X113462D02*
X114037Y641485D01*
G01X116370D02*
Y644585D01*
X115910Y643965D01*
G01Y641485D02*
X116830D01*
G01X118742Y644068D02*
X118972Y644378D01*
X119240Y644533D01*
X119547Y644585D01*
X119930Y644482D01*
X120198Y644223D01*
X120275Y643913D01*
X120237Y643603D01*
X120083Y643345D01*
X119317Y642828D01*
X118972Y642467D01*
X118742Y641950D01*
X118665Y641485D01*
X120275D01*
G01X122570D02*
X122838Y641537D01*
X123145Y641692D01*
X123337Y641950D01*
X123413Y642312D01*
X123337Y642673D01*
X123107Y642983D01*
X122762Y643138D01*
X122378D01*
X122148Y643242D01*
X121957Y643500D01*
X121880Y643862D01*
X121995Y644223D01*
X122263Y644482D01*
X122570Y644585D01*
X122877Y644482D01*
X123145Y644223D01*
X123260Y643862D01*
X123183Y643500D01*
X122992Y643242D01*
X122762Y643138D01*
X122378D01*
X122033Y642983D01*
X121803Y642673D01*
X121727Y642312D01*
X121803Y641950D01*
X121995Y641692D01*
X122302Y641537D01*
X122570Y641485D01*
G01X125670D02*
Y644585D01*
X125210Y643965D01*
G01Y641485D02*
X126130D01*
G01X110881Y637555D02*
Y640655D01*
X111840D01*
X112146Y640500D01*
X112338Y640293D01*
X112415Y639880D01*
X112338Y639467D01*
X112108Y639208D01*
X111840Y639053D01*
X110881D01*
G01X111840D02*
X112415Y637555D01*
G01X114748D02*
Y640655D01*
X114288Y640035D01*
G01Y637555D02*
X115208D01*
G01X117120Y640138D02*
X117350Y640448D01*
X117618Y640603D01*
X117925Y640655D01*
X118308Y640552D01*
X118576Y640293D01*
X118653Y639983D01*
X118615Y639673D01*
X118461Y639415D01*
X117695Y638898D01*
X117350Y638537D01*
X117120Y638020D01*
X117043Y637555D01*
X118653D01*
G01X120105Y638020D02*
X120335Y637762D01*
X120603Y637607D01*
X120948Y637555D01*
X121293Y637658D01*
X121561Y637865D01*
X121753Y638227D01*
X121791Y638640D01*
X121715Y639053D01*
X121523Y639312D01*
X121255Y639518D01*
X120986Y639570D01*
X120718Y639518D01*
X120373Y639312D01*
X120488Y640655D01*
X121523D01*
G01X124048Y637555D02*
Y640655D01*
X123588Y640035D01*
G01Y637555D02*
X124508D01*
G01X113478Y651378D02*
X113323Y651148D01*
X113220Y650880D01*
Y650573D01*
X113375Y650228D01*
X113633Y649960D01*
X113943Y649768D01*
X114460Y649615D01*
X114925Y649577D01*
X115390Y649653D01*
X115700Y649768D01*
X116010Y649998D01*
X116217Y650267D01*
X116320Y650535D01*
Y650803D01*
X116217Y651072D01*
X116062Y651302D01*
X115855Y651493D01*
G01X116320Y653558D02*
X115648Y653635D01*
X115080Y653750D01*
X114563Y653903D01*
X113995Y654095D01*
X113220Y654402D01*
Y652868D01*
G01X116320Y656658D02*
X115648Y656735D01*
X115080Y656850D01*
X114563Y657003D01*
X113995Y657195D01*
X113220Y657502D01*
Y655968D01*
G01X115958Y659183D02*
X116217Y659452D01*
X116320Y659758D01*
X116217Y660065D01*
X115907Y660333D01*
X115442Y660525D01*
X114977Y660602D01*
X114408D01*
X113943Y660525D01*
X113530Y660333D01*
X113323Y660103D01*
X113220Y659835D01*
X113323Y659528D01*
X113530Y659298D01*
X113840Y659145D01*
X114253Y659068D01*
X114615Y659145D01*
X114977Y659337D01*
X115183Y659567D01*
X115235Y659835D01*
X115132Y660142D01*
X114873Y660372D01*
X114408Y660602D01*
G01X113995Y648029D02*
X113765Y648184D01*
X113497Y648287D01*
X113190D01*
X112845Y648132D01*
X112577Y647874D01*
X112385Y647564D01*
X112232Y647047D01*
X112194Y646582D01*
X112270Y646117D01*
X112385Y645807D01*
X112615Y645497D01*
X112884Y645290D01*
X113152Y645187D01*
X113420D01*
X113689Y645290D01*
X113919Y645445D01*
X114110Y645652D01*
G01X116175Y645187D02*
X116252Y645859D01*
X116367Y646427D01*
X116520Y646944D01*
X116712Y647512D01*
X117019Y648287D01*
X115485D01*
G01X118700Y645549D02*
X118969Y645290D01*
X119275Y645187D01*
X119582Y645290D01*
X119850Y645600D01*
X120042Y646065D01*
X120119Y646530D01*
Y647099D01*
X120042Y647564D01*
X119850Y647977D01*
X119620Y648184D01*
X119352Y648287D01*
X119045Y648184D01*
X118815Y647977D01*
X118662Y647667D01*
X118585Y647254D01*
X118662Y646892D01*
X118854Y646530D01*
X119084Y646324D01*
X119352Y646272D01*
X119659Y646375D01*
X119889Y646634D01*
X120119Y647099D01*
G01X122912Y645187D02*
Y648287D01*
X121494Y646065D01*
X123410D01*
G01X112251Y751776D02*
X112021Y751931D01*
X111753Y752034D01*
X111446D01*
X111101Y751879D01*
X110833Y751621D01*
X110641Y751311D01*
X110488Y750794D01*
X110450Y750329D01*
X110526Y749864D01*
X110641Y749554D01*
X110871Y749244D01*
X111140Y749037D01*
X111408Y748934D01*
X111676D01*
X111945Y749037D01*
X112175Y749192D01*
X112366Y749399D01*
G01X114431Y748934D02*
X114508Y749606D01*
X114623Y750174D01*
X114776Y750691D01*
X114968Y751259D01*
X115275Y752034D01*
X113741D01*
G01X117531Y748934D02*
X117608Y749606D01*
X117723Y750174D01*
X117876Y750691D01*
X118068Y751259D01*
X118375Y752034D01*
X116841D01*
G01X120708Y748934D02*
X120976Y748986D01*
X121283Y749141D01*
X121475Y749399D01*
X121551Y749761D01*
X121475Y750122D01*
X121245Y750432D01*
X120900Y750587D01*
X120516D01*
X120286Y750691D01*
X120095Y750949D01*
X120018Y751311D01*
X120133Y751672D01*
X120401Y751931D01*
X120708Y752034D01*
X121015Y751931D01*
X121283Y751672D01*
X121398Y751311D01*
X121321Y750949D01*
X121130Y750691D01*
X120900Y750587D01*
X120516D01*
X120171Y750432D01*
X119941Y750122D01*
X119865Y749761D01*
X119941Y749399D01*
X120133Y749141D01*
X120440Y748986D01*
X120708Y748934D01*
G01X106203Y745117D02*
X106048Y744887D01*
X105945Y744619D01*
Y744312D01*
X106100Y743967D01*
X106358Y743699D01*
X106668Y743507D01*
X107185Y743354D01*
X107650Y743316D01*
X108115Y743392D01*
X108425Y743507D01*
X108735Y743737D01*
X108942Y744006D01*
X109045Y744274D01*
Y744542D01*
X108942Y744811D01*
X108787Y745041D01*
X108580Y745232D01*
G01X109045Y747297D02*
X108373Y747374D01*
X107805Y747489D01*
X107288Y747642D01*
X106720Y747834D01*
X105945Y748141D01*
Y746607D01*
G01X109045Y750474D02*
X108993Y750742D01*
X108838Y751049D01*
X108580Y751241D01*
X108218Y751317D01*
X107857Y751241D01*
X107547Y751011D01*
X107392Y750666D01*
Y750282D01*
X107288Y750052D01*
X107030Y749861D01*
X106668Y749784D01*
X106307Y749899D01*
X106048Y750167D01*
X105945Y750474D01*
X106048Y750781D01*
X106307Y751049D01*
X106668Y751164D01*
X107030Y751087D01*
X107288Y750896D01*
X107392Y750666D01*
Y750282D01*
X107547Y749937D01*
X107857Y749707D01*
X108218Y749631D01*
X108580Y749707D01*
X108838Y749899D01*
X108993Y750206D01*
X109045Y750474D01*
G01X105945Y753574D02*
X106048Y753267D01*
X106307Y753037D01*
X106617Y752884D01*
X107030Y752769D01*
X107495Y752731D01*
X107960Y752769D01*
X108373Y752884D01*
X108683Y753037D01*
X108942Y753267D01*
X109045Y753574D01*
X108942Y753881D01*
X108683Y754111D01*
X108373Y754264D01*
X107960Y754379D01*
X107495Y754417D01*
X107030Y754379D01*
X106617Y754264D01*
X106307Y754111D01*
X106048Y753881D01*
X105945Y753574D01*
G01X110351Y744437D02*
Y747537D01*
X111310D01*
X111616Y747382D01*
X111808Y747175D01*
X111885Y746762D01*
X111808Y746349D01*
X111578Y746090D01*
X111310Y745935D01*
X110351D01*
G01X111310D02*
X111885Y744437D01*
G01X114218D02*
Y747537D01*
X113758Y746917D01*
G01Y744437D02*
X114678D01*
G01X117318Y747537D02*
X117011Y747434D01*
X116781Y747175D01*
X116628Y746865D01*
X116513Y746452D01*
X116475Y745987D01*
X116513Y745522D01*
X116628Y745109D01*
X116781Y744799D01*
X117011Y744540D01*
X117318Y744437D01*
X117625Y744540D01*
X117855Y744799D01*
X118008Y745109D01*
X118123Y745522D01*
X118161Y745987D01*
X118123Y746452D01*
X118008Y746865D01*
X117855Y747175D01*
X117625Y747434D01*
X117318Y747537D01*
G01X119690Y747020D02*
X119920Y747330D01*
X120188Y747485D01*
X120495Y747537D01*
X120878Y747434D01*
X121146Y747175D01*
X121223Y746865D01*
X121185Y746555D01*
X121031Y746297D01*
X120265Y745780D01*
X119920Y745419D01*
X119690Y744902D01*
X119613Y744437D01*
X121223D01*
G01X122790Y747020D02*
X123020Y747330D01*
X123288Y747485D01*
X123595Y747537D01*
X123978Y747434D01*
X124246Y747175D01*
X124323Y746865D01*
X124285Y746555D01*
X124131Y746297D01*
X123365Y745780D01*
X123020Y745419D01*
X122790Y744902D01*
X122713Y744437D01*
X124323D01*
G01X106770Y755201D02*
Y758301D01*
X107729D01*
X108035Y758146D01*
X108227Y757939D01*
X108304Y757526D01*
X108227Y757113D01*
X107997Y756854D01*
X107729Y756699D01*
X106770D01*
G01X107729D02*
X108304Y755201D01*
G01X110637D02*
Y758301D01*
X110177Y757681D01*
G01Y755201D02*
X111097D01*
G01X113737Y758301D02*
X113430Y758198D01*
X113200Y757939D01*
X113047Y757629D01*
X112932Y757216D01*
X112894Y756751D01*
X112932Y756286D01*
X113047Y755873D01*
X113200Y755563D01*
X113430Y755304D01*
X113737Y755201D01*
X114044Y755304D01*
X114274Y755563D01*
X114427Y755873D01*
X114542Y756286D01*
X114580Y756751D01*
X114542Y757216D01*
X114427Y757629D01*
X114274Y757939D01*
X114044Y758198D01*
X113737Y758301D01*
G01X116109Y757784D02*
X116339Y758094D01*
X116607Y758249D01*
X116914Y758301D01*
X117297Y758198D01*
X117565Y757939D01*
X117642Y757629D01*
X117604Y757319D01*
X117450Y757061D01*
X116684Y756544D01*
X116339Y756183D01*
X116109Y755666D01*
X116032Y755201D01*
X117642D01*
G01X119094Y755666D02*
X119324Y755408D01*
X119592Y755253D01*
X119937Y755201D01*
X120282Y755304D01*
X120550Y755511D01*
X120742Y755873D01*
X120780Y756286D01*
X120704Y756699D01*
X120512Y756958D01*
X120244Y757164D01*
X119975Y757216D01*
X119707Y757164D01*
X119362Y756958D01*
X119477Y758301D01*
X120512D01*
G01X132130Y3840D02*
Y6610D01*
G01X148510Y3840D02*
X132130D01*
G01X147303Y8662D02*
X132303D01*
G01D02*
Y21662D01*
G01X122771Y2665D02*
X119671D01*
Y3585D01*
X119826Y3892D01*
X120188Y4122D01*
X120601Y4199D01*
X121014Y4122D01*
X121324Y3930D01*
X121479Y3585D01*
Y2665D01*
G01X119929Y7375D02*
X119774Y7145D01*
X119671Y6877D01*
Y6570D01*
X119826Y6225D01*
X120084Y5957D01*
X120394Y5765D01*
X120911Y5612D01*
X121376Y5574D01*
X121841Y5650D01*
X122151Y5765D01*
X122461Y5995D01*
X122668Y6264D01*
X122771Y6532D01*
Y6800D01*
X122668Y7069D01*
X122513Y7299D01*
X122306Y7490D01*
G01X122771Y9555D02*
X122099Y9632D01*
X121531Y9747D01*
X121014Y9900D01*
X120446Y10092D01*
X119671Y10399D01*
Y8865D01*
G01X122771Y12732D02*
X119671D01*
X120291Y12272D01*
G01X122771D02*
Y13192D01*
G01X131128Y2665D02*
X128028D01*
Y3585D01*
X128183Y3892D01*
X128545Y4122D01*
X128958Y4199D01*
X129371Y4122D01*
X129681Y3930D01*
X129836Y3585D01*
Y2665D01*
G01X128286Y7375D02*
X128131Y7145D01*
X128028Y6877D01*
Y6570D01*
X128183Y6225D01*
X128441Y5957D01*
X128751Y5765D01*
X129268Y5612D01*
X129733Y5574D01*
X130198Y5650D01*
X130508Y5765D01*
X130818Y5995D01*
X131025Y6264D01*
X131128Y6532D01*
Y6800D01*
X131025Y7069D01*
X130870Y7299D01*
X130663Y7490D01*
G01X131128Y9555D02*
X130456Y9632D01*
X129888Y9747D01*
X129371Y9900D01*
X128803Y10092D01*
X128028Y10399D01*
Y8865D01*
G01X128545Y12004D02*
X128235Y12234D01*
X128080Y12502D01*
X128028Y12809D01*
X128131Y13192D01*
X128390Y13460D01*
X128700Y13537D01*
X129010Y13499D01*
X129268Y13345D01*
X129785Y12579D01*
X130146Y12234D01*
X130663Y12004D01*
X131128Y11927D01*
Y13537D01*
G01X127017Y2665D02*
X123917D01*
Y3585D01*
X124072Y3892D01*
X124434Y4122D01*
X124847Y4199D01*
X125260Y4122D01*
X125570Y3930D01*
X125725Y3585D01*
Y2665D01*
G01X124175Y7375D02*
X124020Y7145D01*
X123917Y6877D01*
Y6570D01*
X124072Y6225D01*
X124330Y5957D01*
X124640Y5765D01*
X125157Y5612D01*
X125622Y5574D01*
X126087Y5650D01*
X126397Y5765D01*
X126707Y5995D01*
X126914Y6264D01*
X127017Y6532D01*
Y6800D01*
X126914Y7069D01*
X126759Y7299D01*
X126552Y7490D01*
G01X127017Y9555D02*
X126345Y9632D01*
X125777Y9747D01*
X125260Y9900D01*
X124692Y10092D01*
X123917Y10399D01*
Y8865D01*
G01X126397Y11889D02*
X126759Y12119D01*
X126965Y12425D01*
X127017Y12770D01*
X126965Y13077D01*
X126707Y13384D01*
X126397Y13575D01*
X126087Y13614D01*
X125725Y13537D01*
X125467Y13269D01*
X125364Y13000D01*
Y12655D01*
G01Y13000D02*
X125209Y13230D01*
X124950Y13422D01*
X124640Y13499D01*
X124330Y13422D01*
X124072Y13230D01*
X123917Y12885D01*
X123969Y12540D01*
X124175Y12195D01*
G01X121590Y15917D02*
X121283Y15969D01*
X121015Y16175D01*
X120785Y16485D01*
X120632Y16847D01*
X120555Y17260D01*
Y17674D01*
X120632Y18087D01*
X120785Y18449D01*
X121015Y18759D01*
X121283Y18965D01*
X121590Y19017D01*
X121897Y18965D01*
X122165Y18759D01*
X122395Y18449D01*
X122548Y18087D01*
X122625Y17674D01*
Y17260D01*
X122548Y16847D01*
X122395Y16485D01*
X122165Y16175D01*
X121897Y15969D01*
X121590Y15917D01*
G01X121897Y16744D02*
X122357Y15917D01*
G01X125150D02*
Y19017D01*
X123732Y16795D01*
X125648D01*
G01X126947Y16537D02*
X127177Y16175D01*
X127483Y15969D01*
X127828Y15917D01*
X128135Y15969D01*
X128442Y16227D01*
X128633Y16537D01*
X128672Y16847D01*
X128595Y17209D01*
X128327Y17467D01*
X128058Y17570D01*
X127713D01*
G01X128058D02*
X128288Y17725D01*
X128480Y17984D01*
X128557Y18294D01*
X128480Y18604D01*
X128288Y18862D01*
X127943Y19017D01*
X127598Y18965D01*
X127253Y18759D01*
G01X132303Y21662D02*
X147303D01*
G01X123302Y20564D02*
X120202D01*
Y21484D01*
X120357Y21791D01*
X120719Y22021D01*
X121132Y22098D01*
X121545Y22021D01*
X121855Y21829D01*
X122010Y21484D01*
Y20564D01*
G01X122682Y23664D02*
X122992Y23856D01*
X123199Y24086D01*
X123302Y24354D01*
X123199Y24661D01*
X122992Y24891D01*
X122682Y25121D01*
X122269Y25198D01*
X120202D01*
G01X123302Y27531D02*
X120202D01*
X120822Y27071D01*
G01X123302D02*
Y27991D01*
G01X120202Y30631D02*
X120305Y30324D01*
X120564Y30094D01*
X120874Y29941D01*
X121287Y29826D01*
X121752Y29788D01*
X122217Y29826D01*
X122630Y29941D01*
X122940Y30094D01*
X123199Y30324D01*
X123302Y30631D01*
X123199Y30938D01*
X122940Y31168D01*
X122630Y31321D01*
X122217Y31436D01*
X121752Y31474D01*
X121287Y31436D01*
X120874Y31321D01*
X120564Y31168D01*
X120305Y30938D01*
X120202Y30631D01*
G01X129254Y36783D02*
X126154D01*
Y37703D01*
X126309Y38010D01*
X126671Y38240D01*
X127084Y38317D01*
X127497Y38240D01*
X127807Y38048D01*
X127962Y37703D01*
Y36783D01*
G01X129254Y40650D02*
X129202Y40343D01*
X128996Y40075D01*
X128686Y39845D01*
X128324Y39692D01*
X127911Y39615D01*
X127497D01*
X127084Y39692D01*
X126722Y39845D01*
X126412Y40075D01*
X126206Y40343D01*
X126154Y40650D01*
X126206Y40957D01*
X126412Y41225D01*
X126722Y41455D01*
X127084Y41608D01*
X127497Y41685D01*
X127911D01*
X128324Y41608D01*
X128686Y41455D01*
X128996Y41225D01*
X129202Y40957D01*
X129254Y40650D01*
G01X128427Y40957D02*
X129254Y41417D01*
G01X126671Y43022D02*
X126361Y43252D01*
X126206Y43520D01*
X126154Y43827D01*
X126257Y44210D01*
X126516Y44478D01*
X126826Y44555D01*
X127136Y44517D01*
X127394Y44363D01*
X127911Y43597D01*
X128272Y43252D01*
X128789Y43022D01*
X129254Y42945D01*
Y44555D01*
G01X125093Y36993D02*
X121993D01*
Y37913D01*
X122148Y38220D01*
X122510Y38450D01*
X122923Y38527D01*
X123336Y38450D01*
X123646Y38258D01*
X123801Y37913D01*
Y36993D01*
G01X122251Y41703D02*
X122096Y41473D01*
X121993Y41205D01*
Y40898D01*
X122148Y40553D01*
X122406Y40285D01*
X122716Y40093D01*
X123233Y39940D01*
X123698Y39902D01*
X124163Y39978D01*
X124473Y40093D01*
X124783Y40323D01*
X124990Y40592D01*
X125093Y40860D01*
Y41128D01*
X124990Y41397D01*
X124835Y41627D01*
X124628Y41818D01*
G01X125093Y43883D02*
X124421Y43960D01*
X123853Y44075D01*
X123336Y44228D01*
X122768Y44420D01*
X121993Y44727D01*
Y43193D01*
G01X125093Y46983D02*
X124421Y47060D01*
X123853Y47175D01*
X123336Y47328D01*
X122768Y47520D01*
X121993Y47827D01*
Y46293D01*
G01X138757Y41839D02*
X132557D01*
G01Y45039D02*
X138757D01*
G01X132557Y41839D02*
Y45039D01*
G01X132561Y40791D02*
X138761D01*
G01Y37591D02*
X132561D01*
G01D02*
Y40791D01*
G01X132855Y52590D02*
X129755D01*
Y53510D01*
X129910Y53817D01*
X130272Y54047D01*
X130685Y54124D01*
X131098Y54047D01*
X131408Y53855D01*
X131563Y53510D01*
Y52590D01*
G01X130013Y57300D02*
X129858Y57070D01*
X129755Y56802D01*
Y56495D01*
X129910Y56150D01*
X130168Y55882D01*
X130478Y55690D01*
X130995Y55537D01*
X131460Y55499D01*
X131925Y55575D01*
X132235Y55690D01*
X132545Y55920D01*
X132752Y56189D01*
X132855Y56457D01*
Y56725D01*
X132752Y56994D01*
X132597Y57224D01*
X132390Y57415D01*
G01X132855Y59557D02*
X132803Y59825D01*
X132648Y60132D01*
X132390Y60324D01*
X132028Y60400D01*
X131667Y60324D01*
X131357Y60094D01*
X131202Y59749D01*
Y59365D01*
X131098Y59135D01*
X130840Y58944D01*
X130478Y58867D01*
X130117Y58982D01*
X129858Y59250D01*
X129755Y59557D01*
X129858Y59864D01*
X130117Y60132D01*
X130478Y60247D01*
X130840Y60170D01*
X131098Y59979D01*
X131202Y59749D01*
Y59365D01*
X131357Y59020D01*
X131667Y58790D01*
X132028Y58714D01*
X132390Y58790D01*
X132648Y58982D01*
X132803Y59289D01*
X132855Y59557D01*
G01X132390Y61814D02*
X132648Y62044D01*
X132803Y62312D01*
X132855Y62657D01*
X132752Y63002D01*
X132545Y63270D01*
X132183Y63462D01*
X131770Y63500D01*
X131357Y63424D01*
X131098Y63232D01*
X130892Y62964D01*
X130840Y62695D01*
X130892Y62427D01*
X131098Y62082D01*
X129755Y62197D01*
Y63232D01*
G01X128590Y52590D02*
X125490D01*
Y53510D01*
X125645Y53817D01*
X126007Y54047D01*
X126420Y54124D01*
X126833Y54047D01*
X127143Y53855D01*
X127298Y53510D01*
Y52590D01*
G01X128590Y55690D02*
X125490D01*
Y56649D01*
X125645Y56955D01*
X125852Y57147D01*
X126265Y57224D01*
X126678Y57147D01*
X126937Y56917D01*
X127092Y56649D01*
Y55690D01*
G01Y56649D02*
X128590Y57224D01*
G01X127970Y58714D02*
X128332Y58944D01*
X128538Y59250D01*
X128590Y59595D01*
X128538Y59902D01*
X128280Y60209D01*
X127970Y60400D01*
X127660Y60439D01*
X127298Y60362D01*
X127040Y60094D01*
X126937Y59825D01*
Y59480D01*
G01Y59825D02*
X126782Y60055D01*
X126523Y60247D01*
X126213Y60324D01*
X125903Y60247D01*
X125645Y60055D01*
X125490Y59710D01*
X125542Y59365D01*
X125748Y59020D01*
G01X128125Y61814D02*
X128383Y62044D01*
X128538Y62312D01*
X128590Y62657D01*
X128487Y63002D01*
X128280Y63270D01*
X127918Y63462D01*
X127505Y63500D01*
X127092Y63424D01*
X126833Y63232D01*
X126627Y62964D01*
X126575Y62695D01*
X126627Y62427D01*
X126833Y62082D01*
X125490Y62197D01*
Y63232D01*
G01X123523Y70056D02*
Y73156D01*
X124482D01*
X124788Y73001D01*
X124980Y72794D01*
X125057Y72381D01*
X124980Y71968D01*
X124750Y71709D01*
X124482Y71554D01*
X123523D01*
G01X124482D02*
X125057Y70056D01*
G01X126662Y72639D02*
X126892Y72949D01*
X127160Y73104D01*
X127467Y73156D01*
X127850Y73053D01*
X128118Y72794D01*
X128195Y72484D01*
X128157Y72174D01*
X128003Y71916D01*
X127237Y71399D01*
X126892Y71038D01*
X126662Y70521D01*
X126585Y70056D01*
X128195D01*
G01X130490D02*
Y73156D01*
X130030Y72536D01*
G01Y70056D02*
X130950D01*
G01X133513D02*
X133590Y70728D01*
X133705Y71296D01*
X133858Y71813D01*
X134050Y72381D01*
X134357Y73156D01*
X132823D01*
G01X132014Y74988D02*
Y78188D01*
G01X138214Y74988D02*
X132014D01*
G01Y78188D02*
X138214D01*
G01X122283Y171345D02*
Y174445D01*
X123242D01*
X123548Y174290D01*
X123740Y174083D01*
X123817Y173670D01*
X123740Y173257D01*
X123510Y172998D01*
X123242Y172843D01*
X122283D01*
G01X123242D02*
X123817Y171345D01*
G01X125422Y172637D02*
X125690Y172998D01*
X125920Y173205D01*
X126227Y173308D01*
X126495Y173205D01*
X126687Y172998D01*
X126840Y172688D01*
X126878Y172327D01*
X126840Y172017D01*
X126687Y171707D01*
X126457Y171448D01*
X126188Y171345D01*
X125882Y171448D01*
X125613Y171758D01*
X125460Y172223D01*
X125422Y172740D01*
X125498Y173412D01*
X125613Y173773D01*
X125805Y174135D01*
X126073Y174393D01*
X126342Y174445D01*
X126610Y174342D01*
X126802Y174083D01*
G01X129710Y171345D02*
Y174445D01*
X128292Y172223D01*
X130208D01*
G01X132350Y171345D02*
Y174445D01*
X131890Y173825D01*
G01Y171345D02*
X132810D01*
G01X120211Y177192D02*
X123311D01*
Y178726D01*
G01Y181519D02*
X120211D01*
X122433Y180101D01*
Y182017D01*
G01X120211Y184159D02*
X120314Y183852D01*
X120573Y183622D01*
X120883Y183469D01*
X121296Y183354D01*
X121761Y183316D01*
X122226Y183354D01*
X122639Y183469D01*
X122949Y183622D01*
X123208Y183852D01*
X123311Y184159D01*
X123208Y184466D01*
X122949Y184696D01*
X122639Y184849D01*
X122226Y184964D01*
X121761Y185002D01*
X121296Y184964D01*
X120883Y184849D01*
X120573Y184696D01*
X120314Y184466D01*
X120211Y184159D01*
G01X124691Y190240D02*
X124536Y190010D01*
X124433Y189742D01*
Y189435D01*
X124588Y189090D01*
X124846Y188822D01*
X125156Y188630D01*
X125673Y188477D01*
X126138Y188439D01*
X126603Y188515D01*
X126913Y188630D01*
X127223Y188860D01*
X127430Y189129D01*
X127533Y189397D01*
Y189665D01*
X127430Y189934D01*
X127275Y190164D01*
X127068Y190355D01*
G01Y191654D02*
X127326Y191884D01*
X127481Y192152D01*
X127533Y192497D01*
X127430Y192842D01*
X127223Y193110D01*
X126861Y193302D01*
X126448Y193340D01*
X126035Y193264D01*
X125776Y193072D01*
X125570Y192804D01*
X125518Y192535D01*
X125570Y192267D01*
X125776Y191922D01*
X124433Y192037D01*
Y193072D01*
G01Y195597D02*
X124536Y195290D01*
X124795Y195060D01*
X125105Y194907D01*
X125518Y194792D01*
X125983Y194754D01*
X126448Y194792D01*
X126861Y194907D01*
X127171Y195060D01*
X127430Y195290D01*
X127533Y195597D01*
X127430Y195904D01*
X127171Y196134D01*
X126861Y196287D01*
X126448Y196402D01*
X125983Y196440D01*
X125518Y196402D01*
X125105Y196287D01*
X124795Y196134D01*
X124536Y195904D01*
X124433Y195597D01*
G01Y198697D02*
X124536Y198390D01*
X124795Y198160D01*
X125105Y198007D01*
X125518Y197892D01*
X125983Y197854D01*
X126448Y197892D01*
X126861Y198007D01*
X127171Y198160D01*
X127430Y198390D01*
X127533Y198697D01*
X127430Y199004D01*
X127171Y199234D01*
X126861Y199387D01*
X126448Y199502D01*
X125983Y199540D01*
X125518Y199502D01*
X125105Y199387D01*
X124795Y199234D01*
X124536Y199004D01*
X124433Y198697D01*
G01X122892Y188905D02*
X119792D01*
Y189864D01*
X119947Y190170D01*
X120154Y190362D01*
X120567Y190439D01*
X120980Y190362D01*
X121239Y190132D01*
X121394Y189864D01*
Y188905D01*
G01Y189864D02*
X122892Y190439D01*
G01X121600Y192044D02*
X121239Y192312D01*
X121032Y192542D01*
X120929Y192849D01*
X121032Y193117D01*
X121239Y193309D01*
X121549Y193462D01*
X121910Y193500D01*
X122220Y193462D01*
X122530Y193309D01*
X122789Y193079D01*
X122892Y192810D01*
X122789Y192504D01*
X122479Y192235D01*
X122014Y192082D01*
X121497Y192044D01*
X120825Y192120D01*
X120464Y192235D01*
X120102Y192427D01*
X119844Y192695D01*
X119792Y192964D01*
X119895Y193232D01*
X120154Y193424D01*
G01X122272Y195029D02*
X122634Y195259D01*
X122840Y195565D01*
X122892Y195910D01*
X122840Y196217D01*
X122582Y196524D01*
X122272Y196715D01*
X121962Y196754D01*
X121600Y196677D01*
X121342Y196409D01*
X121239Y196140D01*
Y195795D01*
G01Y196140D02*
X121084Y196370D01*
X120825Y196562D01*
X120515Y196639D01*
X120205Y196562D01*
X119947Y196370D01*
X119792Y196025D01*
X119844Y195680D01*
X120050Y195335D01*
G01X122892Y198972D02*
X122840Y199240D01*
X122685Y199547D01*
X122427Y199739D01*
X122065Y199815D01*
X121704Y199739D01*
X121394Y199509D01*
X121239Y199164D01*
Y198780D01*
X121135Y198550D01*
X120877Y198359D01*
X120515Y198282D01*
X120154Y198397D01*
X119895Y198665D01*
X119792Y198972D01*
X119895Y199279D01*
X120154Y199547D01*
X120515Y199662D01*
X120877Y199585D01*
X121135Y199394D01*
X121239Y199164D01*
Y198780D01*
X121394Y198435D01*
X121704Y198205D01*
X122065Y198129D01*
X122427Y198205D01*
X122685Y198397D01*
X122840Y198704D01*
X122892Y198972D01*
G01X127754Y200760D02*
X124654D01*
Y201719D01*
X124809Y202025D01*
X125016Y202217D01*
X125429Y202294D01*
X125842Y202217D01*
X126101Y201987D01*
X126256Y201719D01*
Y200760D01*
G01Y201719D02*
X127754Y202294D01*
G01X126462Y203899D02*
X126101Y204167D01*
X125894Y204397D01*
X125791Y204704D01*
X125894Y204972D01*
X126101Y205164D01*
X126411Y205317D01*
X126772Y205355D01*
X127082Y205317D01*
X127392Y205164D01*
X127651Y204934D01*
X127754Y204665D01*
X127651Y204359D01*
X127341Y204090D01*
X126876Y203937D01*
X126359Y203899D01*
X125687Y203975D01*
X125326Y204090D01*
X124964Y204282D01*
X124706Y204550D01*
X124654Y204819D01*
X124757Y205087D01*
X125016Y205279D01*
G01X127289Y206884D02*
X127547Y207114D01*
X127702Y207382D01*
X127754Y207727D01*
X127651Y208072D01*
X127444Y208340D01*
X127082Y208532D01*
X126669Y208570D01*
X126256Y208494D01*
X125997Y208302D01*
X125791Y208034D01*
X125739Y207765D01*
X125791Y207497D01*
X125997Y207152D01*
X124654Y207267D01*
Y208302D01*
G01X127392Y210175D02*
X127651Y210444D01*
X127754Y210750D01*
X127651Y211057D01*
X127341Y211325D01*
X126876Y211517D01*
X126411Y211594D01*
X125842D01*
X125377Y211517D01*
X124964Y211325D01*
X124757Y211095D01*
X124654Y210827D01*
X124757Y210520D01*
X124964Y210290D01*
X125274Y210137D01*
X125687Y210060D01*
X126049Y210137D01*
X126411Y210329D01*
X126617Y210559D01*
X126669Y210827D01*
X126566Y211134D01*
X126307Y211364D01*
X125842Y211594D01*
G01X131563Y222479D02*
X131333Y222634D01*
X131065Y222737D01*
X130758D01*
X130413Y222582D01*
X130145Y222324D01*
X129953Y222014D01*
X129800Y221497D01*
X129762Y221032D01*
X129838Y220567D01*
X129953Y220257D01*
X130183Y219947D01*
X130452Y219740D01*
X130720Y219637D01*
X130988D01*
X131257Y219740D01*
X131487Y219895D01*
X131678Y220102D01*
G01X132977D02*
X133207Y219844D01*
X133475Y219689D01*
X133820Y219637D01*
X134165Y219740D01*
X134433Y219947D01*
X134625Y220309D01*
X134663Y220722D01*
X134587Y221135D01*
X134395Y221394D01*
X134127Y221600D01*
X133858Y221652D01*
X133590Y221600D01*
X133245Y221394D01*
X133360Y222737D01*
X134395D01*
G01X136920D02*
X136613Y222634D01*
X136383Y222375D01*
X136230Y222065D01*
X136115Y221652D01*
X136077Y221187D01*
X136115Y220722D01*
X136230Y220309D01*
X136383Y219999D01*
X136613Y219740D01*
X136920Y219637D01*
X137227Y219740D01*
X137457Y219999D01*
X137610Y220309D01*
X137725Y220722D01*
X137763Y221187D01*
X137725Y221652D01*
X137610Y222065D01*
X137457Y222375D01*
X137227Y222634D01*
X136920Y222737D01*
G01X139368Y219999D02*
X139637Y219740D01*
X139943Y219637D01*
X140250Y219740D01*
X140518Y220050D01*
X140710Y220515D01*
X140787Y220980D01*
Y221549D01*
X140710Y222014D01*
X140518Y222427D01*
X140288Y222634D01*
X140020Y222737D01*
X139713Y222634D01*
X139483Y222427D01*
X139330Y222117D01*
X139253Y221704D01*
X139330Y221342D01*
X139522Y220980D01*
X139752Y220774D01*
X140020Y220722D01*
X140327Y220825D01*
X140557Y221084D01*
X140787Y221549D01*
G01X120041Y206069D02*
X123141D01*
Y207603D01*
G01X122521Y209093D02*
X122883Y209323D01*
X123089Y209629D01*
X123141Y209974D01*
X123089Y210281D01*
X122831Y210588D01*
X122521Y210779D01*
X122211Y210818D01*
X121849Y210741D01*
X121591Y210473D01*
X121488Y210204D01*
Y209859D01*
G01Y210204D02*
X121333Y210434D01*
X121074Y210626D01*
X120764Y210703D01*
X120454Y210626D01*
X120196Y210434D01*
X120041Y210089D01*
X120093Y209744D01*
X120299Y209399D01*
G01X122779Y212384D02*
X123038Y212653D01*
X123141Y212959D01*
X123038Y213266D01*
X122728Y213534D01*
X122263Y213726D01*
X121798Y213803D01*
X121229D01*
X120764Y213726D01*
X120351Y213534D01*
X120144Y213304D01*
X120041Y213036D01*
X120144Y212729D01*
X120351Y212499D01*
X120661Y212346D01*
X121074Y212269D01*
X121436Y212346D01*
X121798Y212538D01*
X122004Y212768D01*
X122056Y213036D01*
X121953Y213343D01*
X121694Y213573D01*
X121229Y213803D01*
G01X127925Y212720D02*
X124825D01*
Y213679D01*
X124980Y213985D01*
X125187Y214177D01*
X125600Y214254D01*
X126013Y214177D01*
X126272Y213947D01*
X126427Y213679D01*
Y212720D01*
G01Y213679D02*
X127925Y214254D01*
G01X126633Y215859D02*
X126272Y216127D01*
X126065Y216357D01*
X125962Y216664D01*
X126065Y216932D01*
X126272Y217124D01*
X126582Y217277D01*
X126943Y217315D01*
X127253Y217277D01*
X127563Y217124D01*
X127822Y216894D01*
X127925Y216625D01*
X127822Y216319D01*
X127512Y216050D01*
X127047Y215897D01*
X126530Y215859D01*
X125858Y215935D01*
X125497Y216050D01*
X125135Y216242D01*
X124877Y216510D01*
X124825Y216779D01*
X124928Y217047D01*
X125187Y217239D01*
G01X127925Y220147D02*
X124825D01*
X127047Y218729D01*
Y220645D01*
G01X125342Y222059D02*
X125032Y222289D01*
X124877Y222557D01*
X124825Y222864D01*
X124928Y223247D01*
X125187Y223515D01*
X125497Y223592D01*
X125807Y223554D01*
X126065Y223400D01*
X126582Y222634D01*
X126943Y222289D01*
X127460Y222059D01*
X127925Y221982D01*
Y223592D01*
G01X131990Y282092D02*
Y285192D01*
X132949D01*
X133255Y285037D01*
X133447Y284830D01*
X133524Y284417D01*
X133447Y284004D01*
X133217Y283745D01*
X132949Y283590D01*
X131990D01*
G01X132949D02*
X133524Y282092D01*
G01X136317D02*
Y285192D01*
X134899Y282970D01*
X136815D01*
G01X138229Y283384D02*
X138497Y283745D01*
X138727Y283952D01*
X139034Y284055D01*
X139302Y283952D01*
X139494Y283745D01*
X139647Y283435D01*
X139685Y283074D01*
X139647Y282764D01*
X139494Y282454D01*
X139264Y282195D01*
X138995Y282092D01*
X138689Y282195D01*
X138420Y282505D01*
X138267Y282970D01*
X138229Y283487D01*
X138305Y284159D01*
X138420Y284520D01*
X138612Y284882D01*
X138880Y285140D01*
X139149Y285192D01*
X139417Y285089D01*
X139609Y284830D01*
G01X122750Y300414D02*
Y297314D01*
X124284D01*
G01X125965Y297676D02*
X126234Y297417D01*
X126540Y297314D01*
X126847Y297417D01*
X127115Y297727D01*
X127307Y298192D01*
X127384Y298657D01*
Y299226D01*
X127307Y299691D01*
X127115Y300104D01*
X126885Y300311D01*
X126617Y300414D01*
X126310Y300311D01*
X126080Y300104D01*
X125927Y299794D01*
X125850Y299381D01*
X125927Y299019D01*
X126119Y298657D01*
X126349Y298451D01*
X126617Y298399D01*
X126924Y298502D01*
X127154Y298761D01*
X127384Y299226D01*
G01X131990Y286335D02*
Y289435D01*
X132949D01*
X133255Y289280D01*
X133447Y289073D01*
X133524Y288660D01*
X133447Y288247D01*
X133217Y287988D01*
X132949Y287833D01*
X131990D01*
G01X132949D02*
X133524Y286335D01*
G01X136317D02*
Y289435D01*
X134899Y287213D01*
X136815D01*
G01X138114Y286800D02*
X138344Y286542D01*
X138612Y286387D01*
X138957Y286335D01*
X139302Y286438D01*
X139570Y286645D01*
X139762Y287007D01*
X139800Y287420D01*
X139724Y287833D01*
X139532Y288092D01*
X139264Y288298D01*
X138995Y288350D01*
X138727Y288298D01*
X138382Y288092D01*
X138497Y289435D01*
X139532D01*
G01X123655Y291186D02*
Y294286D01*
X124614D01*
X124920Y294131D01*
X125112Y293924D01*
X125189Y293511D01*
X125112Y293098D01*
X124882Y292839D01*
X124614Y292684D01*
X123655D01*
G01X124614D02*
X125189Y291186D01*
G01X127522D02*
Y294286D01*
X127062Y293666D01*
G01Y291186D02*
X127982D01*
G01X129779Y291651D02*
X130009Y291393D01*
X130277Y291238D01*
X130622Y291186D01*
X130967Y291289D01*
X131235Y291496D01*
X131427Y291858D01*
X131465Y292271D01*
X131389Y292684D01*
X131197Y292943D01*
X130929Y293149D01*
X130660Y293201D01*
X130392Y293149D01*
X130047Y292943D01*
X130162Y294286D01*
X131197D01*
G01X133722D02*
X133415Y294183D01*
X133185Y293924D01*
X133032Y293614D01*
X132917Y293201D01*
X132879Y292736D01*
X132917Y292271D01*
X133032Y291858D01*
X133185Y291548D01*
X133415Y291289D01*
X133722Y291186D01*
X134029Y291289D01*
X134259Y291548D01*
X134412Y291858D01*
X134527Y292271D01*
X134565Y292736D01*
X134527Y293201D01*
X134412Y293614D01*
X134259Y293924D01*
X134029Y294183D01*
X133722Y294286D01*
G01X124360Y304182D02*
X124130Y304337D01*
X123862Y304440D01*
X123555D01*
X123210Y304285D01*
X122942Y304027D01*
X122750Y303717D01*
X122597Y303200D01*
X122559Y302735D01*
X122635Y302270D01*
X122750Y301960D01*
X122980Y301650D01*
X123249Y301443D01*
X123517Y301340D01*
X123785D01*
X124054Y301443D01*
X124284Y301598D01*
X124475Y301805D01*
G01X126617Y301340D02*
Y304440D01*
X126157Y303820D01*
G01Y301340D02*
X127077D01*
G01X129717D02*
Y304440D01*
X129257Y303820D01*
G01Y301340D02*
X130177D01*
G01X132089Y303923D02*
X132319Y304233D01*
X132587Y304388D01*
X132894Y304440D01*
X133277Y304337D01*
X133545Y304078D01*
X133622Y303768D01*
X133584Y303458D01*
X133430Y303200D01*
X132664Y302683D01*
X132319Y302322D01*
X132089Y301805D01*
X132012Y301340D01*
X133622D01*
G01X124360Y308354D02*
X124130Y308509D01*
X123862Y308612D01*
X123555D01*
X123210Y308457D01*
X122942Y308199D01*
X122750Y307889D01*
X122597Y307372D01*
X122559Y306907D01*
X122635Y306442D01*
X122750Y306132D01*
X122980Y305822D01*
X123249Y305615D01*
X123517Y305512D01*
X123785D01*
X124054Y305615D01*
X124284Y305770D01*
X124475Y305977D01*
G01X126617Y305512D02*
Y308612D01*
X126157Y307992D01*
G01Y305512D02*
X127077D01*
G01X129717D02*
Y308612D01*
X129257Y307992D01*
G01Y305512D02*
X130177D01*
G01X132817D02*
Y308612D01*
X132357Y307992D01*
G01Y305512D02*
X133277D01*
G01X122750Y313569D02*
Y316669D01*
X123709D01*
X124015Y316514D01*
X124207Y316307D01*
X124284Y315894D01*
X124207Y315481D01*
X123977Y315222D01*
X123709Y315067D01*
X122750D01*
G01X123709D02*
X124284Y313569D01*
G01X127077D02*
Y316669D01*
X125659Y314447D01*
X127575D01*
G01X129717Y316669D02*
X129410Y316566D01*
X129180Y316307D01*
X129027Y315997D01*
X128912Y315584D01*
X128874Y315119D01*
X128912Y314654D01*
X129027Y314241D01*
X129180Y313931D01*
X129410Y313672D01*
X129717Y313569D01*
X130024Y313672D01*
X130254Y313931D01*
X130407Y314241D01*
X130522Y314654D01*
X130560Y315119D01*
X130522Y315584D01*
X130407Y315997D01*
X130254Y316307D01*
X130024Y316566D01*
X129717Y316669D01*
G01X122750Y309569D02*
Y312669D01*
X123709D01*
X124015Y312514D01*
X124207Y312307D01*
X124284Y311894D01*
X124207Y311481D01*
X123977Y311222D01*
X123709Y311067D01*
X122750D01*
G01X123709D02*
X124284Y309569D01*
G01X127077D02*
Y312669D01*
X125659Y310447D01*
X127575D01*
G01X128874Y310189D02*
X129104Y309827D01*
X129410Y309621D01*
X129755Y309569D01*
X130062Y309621D01*
X130369Y309879D01*
X130560Y310189D01*
X130599Y310499D01*
X130522Y310861D01*
X130254Y311119D01*
X129985Y311222D01*
X129640D01*
G01X129985D02*
X130215Y311377D01*
X130407Y311636D01*
X130484Y311946D01*
X130407Y312256D01*
X130215Y312514D01*
X129870Y312669D01*
X129525Y312617D01*
X129180Y312411D01*
G01X122750Y326342D02*
Y329442D01*
X123709D01*
X124015Y329287D01*
X124207Y329080D01*
X124284Y328667D01*
X124207Y328254D01*
X123977Y327995D01*
X123709Y327840D01*
X122750D01*
G01X123709D02*
X124284Y326342D01*
G01X126617D02*
Y329442D01*
X126157Y328822D01*
G01Y326342D02*
X127077D01*
G01X129717Y329442D02*
X129410Y329339D01*
X129180Y329080D01*
X129027Y328770D01*
X128912Y328357D01*
X128874Y327892D01*
X128912Y327427D01*
X129027Y327014D01*
X129180Y326704D01*
X129410Y326445D01*
X129717Y326342D01*
X130024Y326445D01*
X130254Y326704D01*
X130407Y327014D01*
X130522Y327427D01*
X130560Y327892D01*
X130522Y328357D01*
X130407Y328770D01*
X130254Y329080D01*
X130024Y329339D01*
X129717Y329442D01*
G01X132740Y326342D02*
X132817Y327014D01*
X132932Y327582D01*
X133085Y328099D01*
X133277Y328667D01*
X133584Y329442D01*
X132050D01*
G01X122750Y322001D02*
Y325101D01*
X123709D01*
X124015Y324946D01*
X124207Y324739D01*
X124284Y324326D01*
X124207Y323913D01*
X123977Y323654D01*
X123709Y323499D01*
X122750D01*
G01X123709D02*
X124284Y322001D01*
G01X127077D02*
Y325101D01*
X125659Y322879D01*
X127575D01*
G01X130177Y322001D02*
Y325101D01*
X128759Y322879D01*
X130675D01*
G01X122750Y318069D02*
Y321169D01*
X123709D01*
X124015Y321014D01*
X124207Y320807D01*
X124284Y320394D01*
X124207Y319981D01*
X123977Y319722D01*
X123709Y319567D01*
X122750D01*
G01X123709D02*
X124284Y318069D01*
G01X127077D02*
Y321169D01*
X125659Y318947D01*
X127575D01*
G01X129717Y318069D02*
Y321169D01*
X129257Y320549D01*
G01Y318069D02*
X130177D01*
G01X122750Y330455D02*
Y333555D01*
X123709D01*
X124015Y333400D01*
X124207Y333193D01*
X124284Y332780D01*
X124207Y332367D01*
X123977Y332108D01*
X123709Y331953D01*
X122750D01*
G01X123709D02*
X124284Y330455D01*
G01X126617D02*
Y333555D01*
X126157Y332935D01*
G01Y330455D02*
X127077D01*
G01X129717Y333555D02*
X129410Y333452D01*
X129180Y333193D01*
X129027Y332883D01*
X128912Y332470D01*
X128874Y332005D01*
X128912Y331540D01*
X129027Y331127D01*
X129180Y330817D01*
X129410Y330558D01*
X129717Y330455D01*
X130024Y330558D01*
X130254Y330817D01*
X130407Y331127D01*
X130522Y331540D01*
X130560Y332005D01*
X130522Y332470D01*
X130407Y332883D01*
X130254Y333193D01*
X130024Y333452D01*
X129717Y333555D01*
G01X132817Y330455D02*
X133085Y330507D01*
X133392Y330662D01*
X133584Y330920D01*
X133660Y331282D01*
X133584Y331643D01*
X133354Y331953D01*
X133009Y332108D01*
X132625D01*
X132395Y332212D01*
X132204Y332470D01*
X132127Y332832D01*
X132242Y333193D01*
X132510Y333452D01*
X132817Y333555D01*
X133124Y333452D01*
X133392Y333193D01*
X133507Y332832D01*
X133430Y332470D01*
X133239Y332212D01*
X133009Y332108D01*
X132625D01*
X132280Y331953D01*
X132050Y331643D01*
X131974Y331282D01*
X132050Y330920D01*
X132242Y330662D01*
X132549Y330507D01*
X132817Y330455D01*
G01X120883Y395859D02*
X120653Y396014D01*
X120385Y396117D01*
X120078D01*
X119733Y395962D01*
X119465Y395704D01*
X119273Y395394D01*
X119120Y394877D01*
X119082Y394412D01*
X119158Y393947D01*
X119273Y393637D01*
X119503Y393327D01*
X119772Y393120D01*
X120040Y393017D01*
X120308D01*
X120577Y393120D01*
X120807Y393275D01*
X120998Y393482D01*
G01X123140Y393017D02*
X123408Y393069D01*
X123715Y393224D01*
X123907Y393482D01*
X123983Y393844D01*
X123907Y394205D01*
X123677Y394515D01*
X123332Y394670D01*
X122948D01*
X122718Y394774D01*
X122527Y395032D01*
X122450Y395394D01*
X122565Y395755D01*
X122833Y396014D01*
X123140Y396117D01*
X123447Y396014D01*
X123715Y395755D01*
X123830Y395394D01*
X123753Y395032D01*
X123562Y394774D01*
X123332Y394670D01*
X122948D01*
X122603Y394515D01*
X122373Y394205D01*
X122297Y393844D01*
X122373Y393482D01*
X122565Y393224D01*
X122872Y393069D01*
X123140Y393017D01*
G01X126240D02*
Y396117D01*
X125780Y395497D01*
G01Y393017D02*
X126700D01*
G01X129263D02*
X129340Y393689D01*
X129455Y394257D01*
X129608Y394774D01*
X129800Y395342D01*
X130107Y396117D01*
X128573D01*
G01X118103Y388917D02*
Y392017D01*
X119062D01*
X119368Y391862D01*
X119560Y391655D01*
X119637Y391242D01*
X119560Y390829D01*
X119330Y390570D01*
X119062Y390415D01*
X118103D01*
G01X119062D02*
X119637Y388917D01*
G01X121970D02*
Y392017D01*
X121510Y391397D01*
G01Y388917D02*
X122430D01*
G01X125070D02*
Y392017D01*
X124610Y391397D01*
G01Y388917D02*
X125530D01*
G01X127327Y389382D02*
X127557Y389124D01*
X127825Y388969D01*
X128170Y388917D01*
X128515Y389020D01*
X128783Y389227D01*
X128975Y389589D01*
X129013Y390002D01*
X128937Y390415D01*
X128745Y390674D01*
X128477Y390880D01*
X128208Y390932D01*
X127940Y390880D01*
X127595Y390674D01*
X127710Y392017D01*
X128745D01*
G01X130542Y391500D02*
X130772Y391810D01*
X131040Y391965D01*
X131347Y392017D01*
X131730Y391914D01*
X131998Y391655D01*
X132075Y391345D01*
X132037Y391035D01*
X131883Y390777D01*
X131117Y390260D01*
X130772Y389899D01*
X130542Y389382D01*
X130465Y388917D01*
X132075D01*
G01X119583Y385137D02*
Y388237D01*
X120542D01*
X120848Y388082D01*
X121040Y387875D01*
X121117Y387462D01*
X121040Y387049D01*
X120810Y386790D01*
X120542Y386635D01*
X119583D01*
G01X120542D02*
X121117Y385137D01*
G01X123450D02*
Y388237D01*
X122990Y387617D01*
G01Y385137D02*
X123910D01*
G01X126550D02*
X126818Y385189D01*
X127125Y385344D01*
X127317Y385602D01*
X127393Y385964D01*
X127317Y386325D01*
X127087Y386635D01*
X126742Y386790D01*
X126358D01*
X126128Y386894D01*
X125937Y387152D01*
X125860Y387514D01*
X125975Y387875D01*
X126243Y388134D01*
X126550Y388237D01*
X126857Y388134D01*
X127125Y387875D01*
X127240Y387514D01*
X127163Y387152D01*
X126972Y386894D01*
X126742Y386790D01*
X126358D01*
X126013Y386635D01*
X125783Y386325D01*
X125707Y385964D01*
X125783Y385602D01*
X125975Y385344D01*
X126282Y385189D01*
X126550Y385137D01*
G01X129650Y388237D02*
X129343Y388134D01*
X129113Y387875D01*
X128960Y387565D01*
X128845Y387152D01*
X128807Y386687D01*
X128845Y386222D01*
X128960Y385809D01*
X129113Y385499D01*
X129343Y385240D01*
X129650Y385137D01*
X129957Y385240D01*
X130187Y385499D01*
X130340Y385809D01*
X130455Y386222D01*
X130493Y386687D01*
X130455Y387152D01*
X130340Y387565D01*
X130187Y387875D01*
X129957Y388134D01*
X129650Y388237D01*
G01X130739Y396496D02*
Y398996D01*
X130419Y398496D01*
G01Y396496D02*
X131059D01*
G01X131146Y400354D02*
Y401158D01*
G01X128542Y400354D02*
X131146D01*
G01X119138Y401158D02*
Y400354D01*
G01D02*
X121442D01*
G01X119138D02*
X131146D01*
G01X133689Y416552D02*
X127489D01*
G01D02*
Y419752D01*
G01D02*
X133689D01*
G01X130589Y419652D02*
Y416652D01*
G01X133703Y420720D02*
X127503D01*
G01D02*
Y423920D01*
G01X132196Y412144D02*
X132356Y411936D01*
X132543Y411811D01*
X132783Y411769D01*
X133023Y411852D01*
X133210Y412019D01*
X133343Y412311D01*
X133370Y412644D01*
X133316Y412977D01*
X133183Y413186D01*
X132996Y413352D01*
X132810Y413394D01*
X132623Y413352D01*
X132383Y413186D01*
X132463Y414269D01*
X133183D01*
G01X117296Y412884D02*
X117483Y413175D01*
X117643Y413342D01*
X117856Y413425D01*
X118043Y413342D01*
X118176Y413175D01*
X118283Y412925D01*
X118310Y412634D01*
X118283Y412384D01*
X118176Y412134D01*
X118016Y411925D01*
X117830Y411842D01*
X117616Y411925D01*
X117430Y412175D01*
X117323Y412550D01*
X117296Y412967D01*
X117350Y413509D01*
X117430Y413800D01*
X117563Y414092D01*
X117750Y414300D01*
X117936Y414342D01*
X118123Y414259D01*
X118256Y414050D01*
G01X131146Y411558D02*
Y412362D01*
G01D02*
X128642D01*
G01X121242D02*
X119138D01*
G01D02*
Y411558D01*
G01Y412362D02*
X131146D01*
G01X127503Y423920D02*
X133703D01*
G01X130004Y446350D02*
X129952Y446043D01*
X129746Y445775D01*
X129436Y445545D01*
X129074Y445392D01*
X128661Y445315D01*
X128247D01*
X127834Y445392D01*
X127472Y445545D01*
X127162Y445775D01*
X126956Y446043D01*
X126904Y446350D01*
X126956Y446657D01*
X127162Y446925D01*
X127472Y447155D01*
X127834Y447308D01*
X128247Y447385D01*
X128661D01*
X129074Y447308D01*
X129436Y447155D01*
X129746Y446925D01*
X129952Y446657D01*
X130004Y446350D01*
G01X129177Y446657D02*
X130004Y447117D01*
G01X129384Y448607D02*
X129746Y448837D01*
X129952Y449143D01*
X130004Y449488D01*
X129952Y449795D01*
X129694Y450102D01*
X129384Y450293D01*
X129074Y450332D01*
X128712Y450255D01*
X128454Y449987D01*
X128351Y449718D01*
Y449373D01*
G01Y449718D02*
X128196Y449948D01*
X127937Y450140D01*
X127627Y450217D01*
X127317Y450140D01*
X127059Y449948D01*
X126904Y449603D01*
X126956Y449258D01*
X127162Y448913D01*
G01X129642Y451898D02*
X129901Y452167D01*
X130004Y452473D01*
X129901Y452780D01*
X129591Y453048D01*
X129126Y453240D01*
X128661Y453317D01*
X128092D01*
X127627Y453240D01*
X127214Y453048D01*
X127007Y452818D01*
X126904Y452550D01*
X127007Y452243D01*
X127214Y452013D01*
X127524Y451860D01*
X127937Y451783D01*
X128299Y451860D01*
X128661Y452052D01*
X128867Y452282D01*
X128919Y452550D01*
X128816Y452857D01*
X128557Y453087D01*
X128092Y453317D01*
G01X132200Y443515D02*
Y444221D01*
G01Y454621D02*
Y455326D01*
G01X136705Y443515D02*
X132200D01*
G01X128176Y461138D02*
Y464338D01*
G01X131276Y461238D02*
Y464238D01*
G01X128176Y464338D02*
X134376D01*
G01Y461138D02*
X128176D01*
G01Y469138D02*
Y472338D01*
G01X134376Y469138D02*
X128176D01*
G01Y465138D02*
Y468338D01*
G01D02*
X134376D01*
G01Y465138D02*
X128176D01*
G01Y460333D02*
X134376D01*
G01X128176Y457133D02*
Y460333D01*
G01X134376Y457133D02*
X128176D01*
G01X132200Y455326D02*
X136705D01*
G01X123472Y488333D02*
Y473333D01*
G01X130002Y476903D02*
X129847Y476673D01*
X129744Y476405D01*
Y476098D01*
X129899Y475753D01*
X130157Y475485D01*
X130467Y475293D01*
X130984Y475140D01*
X131449Y475102D01*
X131914Y475178D01*
X132224Y475293D01*
X132534Y475523D01*
X132741Y475792D01*
X132844Y476060D01*
Y476328D01*
X132741Y476597D01*
X132586Y476827D01*
X132379Y477018D01*
G01X132844Y479160D02*
X132792Y479428D01*
X132637Y479735D01*
X132379Y479927D01*
X132017Y480003D01*
X131656Y479927D01*
X131346Y479697D01*
X131191Y479352D01*
Y478968D01*
X131087Y478738D01*
X130829Y478547D01*
X130467Y478470D01*
X130106Y478585D01*
X129847Y478853D01*
X129744Y479160D01*
X129847Y479467D01*
X130106Y479735D01*
X130467Y479850D01*
X130829Y479773D01*
X131087Y479582D01*
X131191Y479352D01*
Y478968D01*
X131346Y478623D01*
X131656Y478393D01*
X132017Y478317D01*
X132379Y478393D01*
X132637Y478585D01*
X132792Y478892D01*
X132844Y479160D01*
G01X130261Y481532D02*
X129951Y481762D01*
X129796Y482030D01*
X129744Y482337D01*
X129847Y482720D01*
X130106Y482988D01*
X130416Y483065D01*
X130726Y483027D01*
X130984Y482873D01*
X131501Y482107D01*
X131862Y481762D01*
X132379Y481532D01*
X132844Y481455D01*
Y483065D01*
G01Y485283D02*
X132172Y485360D01*
X131604Y485475D01*
X131087Y485628D01*
X130519Y485820D01*
X129744Y486127D01*
Y484593D01*
G01X127572Y485333D02*
X124572D01*
G01X127672Y482233D02*
X124472D01*
G01X127672Y488433D02*
Y482233D01*
G01X124472D02*
Y488433D01*
G01X128176Y472338D02*
X134376D01*
G01X135452Y501432D02*
X128852D01*
G01X128752Y493932D02*
Y508932D01*
G01X135552Y493932D02*
X128752D01*
G01X124472Y488433D02*
X127672D01*
G01X128651Y489115D02*
X126151D01*
X126651Y488795D01*
G01X128651D02*
Y489435D01*
G01X126151Y491315D02*
X126234Y491102D01*
X126443Y490942D01*
X126693Y490835D01*
X127026Y490755D01*
X127401Y490728D01*
X127776Y490755D01*
X128109Y490835D01*
X128359Y490942D01*
X128568Y491102D01*
X128651Y491315D01*
X128568Y491528D01*
X128359Y491688D01*
X128109Y491795D01*
X127776Y491875D01*
X127401Y491902D01*
X127026Y491875D01*
X126693Y491795D01*
X126443Y491688D01*
X126234Y491528D01*
X126151Y491315D01*
G01X126639Y493226D02*
Y505234D01*
G01Y493226D02*
Y495530D01*
G01X125835Y493226D02*
X126639D01*
G01X128752Y508932D02*
X135552D01*
G01X127876Y519490D02*
X127646Y519645D01*
X127378Y519748D01*
X127071D01*
X126726Y519593D01*
X126458Y519335D01*
X126266Y519025D01*
X126113Y518508D01*
X126075Y518043D01*
X126151Y517578D01*
X126266Y517268D01*
X126496Y516958D01*
X126765Y516751D01*
X127033Y516648D01*
X127301D01*
X127570Y516751D01*
X127800Y516906D01*
X127991Y517113D01*
G01X130133Y516648D02*
X130401Y516700D01*
X130708Y516855D01*
X130900Y517113D01*
X130976Y517475D01*
X130900Y517836D01*
X130670Y518146D01*
X130325Y518301D01*
X129941D01*
X129711Y518405D01*
X129520Y518663D01*
X129443Y519025D01*
X129558Y519386D01*
X129826Y519645D01*
X130133Y519748D01*
X130440Y519645D01*
X130708Y519386D01*
X130823Y519025D01*
X130746Y518663D01*
X130555Y518405D01*
X130325Y518301D01*
X129941D01*
X129596Y518146D01*
X129366Y517836D01*
X129290Y517475D01*
X129366Y517113D01*
X129558Y516855D01*
X129865Y516700D01*
X130133Y516648D01*
G01X132390Y517268D02*
X132620Y516906D01*
X132926Y516700D01*
X133271Y516648D01*
X133578Y516700D01*
X133885Y516958D01*
X134076Y517268D01*
X134115Y517578D01*
X134038Y517940D01*
X133770Y518198D01*
X133501Y518301D01*
X133156D01*
G01X133501D02*
X133731Y518456D01*
X133923Y518715D01*
X134000Y519025D01*
X133923Y519335D01*
X133731Y519593D01*
X133386Y519748D01*
X133041Y519696D01*
X132696Y519490D01*
G01X135605Y519231D02*
X135835Y519541D01*
X136103Y519696D01*
X136410Y519748D01*
X136793Y519645D01*
X137061Y519386D01*
X137138Y519076D01*
X137100Y518766D01*
X136946Y518508D01*
X136180Y517991D01*
X135835Y517630D01*
X135605Y517113D01*
X135528Y516648D01*
X137138D01*
G01X132177Y515404D02*
X138377D01*
G01X132177Y512204D02*
Y515404D01*
G01X138377Y512204D02*
X132177D01*
G01X123405Y520631D02*
Y517431D01*
G01X117205D02*
Y520631D01*
G01X123405Y517431D02*
X117205D01*
G01X117305Y512231D02*
Y515431D01*
G01X123505Y512231D02*
X117305D01*
G01X123505Y515431D02*
Y512231D01*
G01X117305Y515431D02*
X123505D01*
G01X128117Y507870D02*
X125617D01*
X126117Y507550D01*
G01X128117D02*
Y508190D01*
G01X126639Y502630D02*
Y505234D01*
G01D02*
X125835D01*
G01X120272Y524533D02*
Y521533D01*
G01X123372Y524633D02*
Y521433D01*
G01X117172Y524633D02*
X123372D01*
G01X117172Y521433D02*
Y524633D01*
G01X123372Y521433D02*
X117172D01*
G01X117205Y520631D02*
X123405D01*
G01X129553Y525687D02*
X129745Y525377D01*
X129975Y525170D01*
X130243Y525067D01*
X130550Y525170D01*
X130780Y525377D01*
X131010Y525687D01*
X131087Y526100D01*
Y528167D01*
G01X132692Y527650D02*
X132922Y527960D01*
X133190Y528115D01*
X133497Y528167D01*
X133880Y528064D01*
X134148Y527805D01*
X134225Y527495D01*
X134187Y527185D01*
X134033Y526927D01*
X133267Y526410D01*
X132922Y526049D01*
X132692Y525532D01*
X132615Y525067D01*
X134225D01*
G01X135792Y527650D02*
X136022Y527960D01*
X136290Y528115D01*
X136597Y528167D01*
X136980Y528064D01*
X137248Y527805D01*
X137325Y527495D01*
X137287Y527185D01*
X137133Y526927D01*
X136367Y526410D01*
X136022Y526049D01*
X135792Y525532D01*
X135715Y525067D01*
X137325D01*
G01X120254Y561951D02*
X120099Y561721D01*
X119996Y561453D01*
Y561146D01*
X120151Y560801D01*
X120409Y560533D01*
X120719Y560341D01*
X121236Y560188D01*
X121701Y560150D01*
X122166Y560226D01*
X122476Y560341D01*
X122786Y560571D01*
X122993Y560840D01*
X123096Y561108D01*
Y561376D01*
X122993Y561645D01*
X122838Y561875D01*
X122631Y562066D01*
G01X123096Y564668D02*
X119996D01*
X122218Y563250D01*
Y565166D01*
G01X120513Y566580D02*
X120203Y566810D01*
X120048Y567078D01*
X119996Y567385D01*
X120099Y567768D01*
X120358Y568036D01*
X120668Y568113D01*
X120978Y568075D01*
X121236Y567921D01*
X121753Y567155D01*
X122114Y566810D01*
X122631Y566580D01*
X123096Y566503D01*
Y568113D01*
G01X122734Y569756D02*
X122993Y570025D01*
X123096Y570331D01*
X122993Y570638D01*
X122683Y570906D01*
X122218Y571098D01*
X121753Y571175D01*
X121184D01*
X120719Y571098D01*
X120306Y570906D01*
X120099Y570676D01*
X119996Y570408D01*
X120099Y570101D01*
X120306Y569871D01*
X120616Y569718D01*
X121029Y569641D01*
X121391Y569718D01*
X121753Y569910D01*
X121959Y570140D01*
X122011Y570408D01*
X121908Y570715D01*
X121649Y570945D01*
X121184Y571175D01*
G01X118465Y570839D02*
Y560639D01*
G01X133767Y571026D02*
X130667D01*
Y571985D01*
X130822Y572291D01*
X131029Y572483D01*
X131442Y572560D01*
X131855Y572483D01*
X132114Y572253D01*
X132269Y571985D01*
Y571026D01*
G01Y571985D02*
X133767Y572560D01*
G01X133302Y574050D02*
X133560Y574280D01*
X133715Y574548D01*
X133767Y574893D01*
X133664Y575238D01*
X133457Y575506D01*
X133095Y575698D01*
X132682Y575736D01*
X132269Y575660D01*
X132010Y575468D01*
X131804Y575200D01*
X131752Y574931D01*
X131804Y574663D01*
X132010Y574318D01*
X130667Y574433D01*
Y575468D01*
G01X133302Y577150D02*
X133560Y577380D01*
X133715Y577648D01*
X133767Y577993D01*
X133664Y578338D01*
X133457Y578606D01*
X133095Y578798D01*
X132682Y578836D01*
X132269Y578760D01*
X132010Y578568D01*
X131804Y578300D01*
X131752Y578031D01*
X131804Y577763D01*
X132010Y577418D01*
X130667Y577533D01*
Y578568D01*
G01X133767Y581016D02*
X133095Y581093D01*
X132527Y581208D01*
X132010Y581361D01*
X131442Y581553D01*
X130667Y581860D01*
Y580326D01*
G01X124725Y578952D02*
X121625D01*
Y579911D01*
X121780Y580217D01*
X121987Y580409D01*
X122400Y580486D01*
X122813Y580409D01*
X123072Y580179D01*
X123227Y579911D01*
Y578952D01*
G01Y579911D02*
X124725Y580486D01*
G01X124260Y581976D02*
X124518Y582206D01*
X124673Y582474D01*
X124725Y582819D01*
X124622Y583164D01*
X124415Y583432D01*
X124053Y583624D01*
X123640Y583662D01*
X123227Y583586D01*
X122968Y583394D01*
X122762Y583126D01*
X122710Y582857D01*
X122762Y582589D01*
X122968Y582244D01*
X121625Y582359D01*
Y583394D01*
G01X123433Y585191D02*
X123072Y585459D01*
X122865Y585689D01*
X122762Y585996D01*
X122865Y586264D01*
X123072Y586456D01*
X123382Y586609D01*
X123743Y586647D01*
X124053Y586609D01*
X124363Y586456D01*
X124622Y586226D01*
X124725Y585957D01*
X124622Y585651D01*
X124312Y585382D01*
X123847Y585229D01*
X123330Y585191D01*
X122658Y585267D01*
X122297Y585382D01*
X121935Y585574D01*
X121677Y585842D01*
X121625Y586111D01*
X121728Y586379D01*
X121987Y586571D01*
G01X124260Y588176D02*
X124518Y588406D01*
X124673Y588674D01*
X124725Y589019D01*
X124622Y589364D01*
X124415Y589632D01*
X124053Y589824D01*
X123640Y589862D01*
X123227Y589786D01*
X122968Y589594D01*
X122762Y589326D01*
X122710Y589057D01*
X122762Y588789D01*
X122968Y588444D01*
X121625Y588559D01*
Y589594D01*
G01X120083Y591227D02*
Y573827D01*
G01X127664Y613238D02*
X127434Y613393D01*
X127166Y613496D01*
X126859D01*
X126514Y613341D01*
X126246Y613083D01*
X126054Y612773D01*
X125901Y612256D01*
X125863Y611791D01*
X125939Y611326D01*
X126054Y611016D01*
X126284Y610706D01*
X126553Y610499D01*
X126821Y610396D01*
X127089D01*
X127358Y610499D01*
X127588Y610654D01*
X127779Y610861D01*
G01X129193Y612979D02*
X129423Y613289D01*
X129691Y613444D01*
X129998Y613496D01*
X130381Y613393D01*
X130649Y613134D01*
X130726Y612824D01*
X130688Y612514D01*
X130534Y612256D01*
X129768Y611739D01*
X129423Y611378D01*
X129193Y610861D01*
X129116Y610396D01*
X130726D01*
G01X132293Y611688D02*
X132561Y612049D01*
X132791Y612256D01*
X133098Y612359D01*
X133366Y612256D01*
X133558Y612049D01*
X133711Y611739D01*
X133749Y611378D01*
X133711Y611068D01*
X133558Y610758D01*
X133328Y610499D01*
X133059Y610396D01*
X132753Y610499D01*
X132484Y610809D01*
X132331Y611274D01*
X132293Y611791D01*
X132369Y612463D01*
X132484Y612824D01*
X132676Y613186D01*
X132944Y613444D01*
X133213Y613496D01*
X133481Y613393D01*
X133673Y613134D01*
G01X136581Y610396D02*
Y613496D01*
X135163Y611274D01*
X137079D01*
G01X125440Y619490D02*
Y640690D01*
G01X128209Y627884D02*
Y630984D01*
X129129D01*
X129436Y630829D01*
X129666Y630467D01*
X129743Y630054D01*
X129666Y629641D01*
X129474Y629331D01*
X129129Y629176D01*
X128209D01*
G01X132919Y630726D02*
X132689Y630881D01*
X132421Y630984D01*
X132114D01*
X131769Y630829D01*
X131501Y630571D01*
X131309Y630261D01*
X131156Y629744D01*
X131118Y629279D01*
X131194Y628814D01*
X131309Y628504D01*
X131539Y628194D01*
X131808Y627987D01*
X132076Y627884D01*
X132344D01*
X132613Y627987D01*
X132843Y628142D01*
X133034Y628349D01*
G01X134333D02*
X134563Y628091D01*
X134831Y627936D01*
X135176Y627884D01*
X135521Y627987D01*
X135789Y628194D01*
X135981Y628556D01*
X136019Y628969D01*
X135943Y629382D01*
X135751Y629641D01*
X135483Y629847D01*
X135214Y629899D01*
X134946Y629847D01*
X134601Y629641D01*
X134716Y630984D01*
X135751D01*
G01X128365Y623899D02*
Y626999D01*
X129285D01*
X129592Y626844D01*
X129822Y626482D01*
X129899Y626069D01*
X129822Y625656D01*
X129630Y625346D01*
X129285Y625191D01*
X128365D01*
G01X133075Y626741D02*
X132845Y626896D01*
X132577Y626999D01*
X132270D01*
X131925Y626844D01*
X131657Y626586D01*
X131465Y626276D01*
X131312Y625759D01*
X131274Y625294D01*
X131350Y624829D01*
X131465Y624519D01*
X131695Y624209D01*
X131964Y624002D01*
X132232Y623899D01*
X132500D01*
X132769Y624002D01*
X132999Y624157D01*
X133190Y624364D01*
G01X135255Y623899D02*
X135332Y624571D01*
X135447Y625139D01*
X135600Y625656D01*
X135792Y626224D01*
X136099Y626999D01*
X134565D01*
G01X127659Y617430D02*
X127429Y617585D01*
X127161Y617688D01*
X126854D01*
X126509Y617533D01*
X126241Y617275D01*
X126049Y616965D01*
X125896Y616448D01*
X125858Y615983D01*
X125934Y615518D01*
X126049Y615208D01*
X126279Y614898D01*
X126548Y614691D01*
X126816Y614588D01*
X127084D01*
X127353Y614691D01*
X127583Y614846D01*
X127774Y615053D01*
G01X129188Y617171D02*
X129418Y617481D01*
X129686Y617636D01*
X129993Y617688D01*
X130376Y617585D01*
X130644Y617326D01*
X130721Y617016D01*
X130683Y616706D01*
X130529Y616448D01*
X129763Y615931D01*
X129418Y615570D01*
X129188Y615053D01*
X129111Y614588D01*
X130721D01*
G01X132288Y615880D02*
X132556Y616241D01*
X132786Y616448D01*
X133093Y616551D01*
X133361Y616448D01*
X133553Y616241D01*
X133706Y615931D01*
X133744Y615570D01*
X133706Y615260D01*
X133553Y614950D01*
X133323Y614691D01*
X133054Y614588D01*
X132748Y614691D01*
X132479Y615001D01*
X132326Y615466D01*
X132288Y615983D01*
X132364Y616655D01*
X132479Y617016D01*
X132671Y617378D01*
X132939Y617636D01*
X133208Y617688D01*
X133476Y617585D01*
X133668Y617326D01*
G01X135273Y615208D02*
X135503Y614846D01*
X135809Y614640D01*
X136154Y614588D01*
X136461Y614640D01*
X136768Y614898D01*
X136959Y615208D01*
X136998Y615518D01*
X136921Y615880D01*
X136653Y616138D01*
X136384Y616241D01*
X136039D01*
G01X136384D02*
X136614Y616396D01*
X136806Y616655D01*
X136883Y616965D01*
X136806Y617275D01*
X136614Y617533D01*
X136269Y617688D01*
X135924Y617636D01*
X135579Y617430D01*
G01X126741Y619402D02*
Y622502D01*
X127700D01*
X128006Y622347D01*
X128198Y622140D01*
X128275Y621727D01*
X128198Y621314D01*
X127968Y621055D01*
X127700Y620900D01*
X126741D01*
G01X127700D02*
X128275Y619402D01*
G01X129765Y619867D02*
X129995Y619609D01*
X130263Y619454D01*
X130608Y619402D01*
X130953Y619505D01*
X131221Y619712D01*
X131413Y620074D01*
X131451Y620487D01*
X131375Y620900D01*
X131183Y621159D01*
X130915Y621365D01*
X130646Y621417D01*
X130378Y621365D01*
X130033Y621159D01*
X130148Y622502D01*
X131183D01*
G01X132865Y619867D02*
X133095Y619609D01*
X133363Y619454D01*
X133708Y619402D01*
X134053Y619505D01*
X134321Y619712D01*
X134513Y620074D01*
X134551Y620487D01*
X134475Y620900D01*
X134283Y621159D01*
X134015Y621365D01*
X133746Y621417D01*
X133478Y621365D01*
X133133Y621159D01*
X133248Y622502D01*
X134283D01*
G01X135965Y619867D02*
X136195Y619609D01*
X136463Y619454D01*
X136808Y619402D01*
X137153Y619505D01*
X137421Y619712D01*
X137613Y620074D01*
X137651Y620487D01*
X137575Y620900D01*
X137383Y621159D01*
X137115Y621365D01*
X136846Y621417D01*
X136578Y621365D01*
X136233Y621159D01*
X136348Y622502D01*
X137383D01*
G01X125440Y640690D02*
X128120D01*
G01D02*
X144480D01*
G01X128541Y636472D02*
Y639572D01*
X129461D01*
X129768Y639417D01*
X129998Y639055D01*
X130075Y638642D01*
X129998Y638229D01*
X129806Y637919D01*
X129461Y637764D01*
X128541D01*
G01X133251Y639314D02*
X133021Y639469D01*
X132753Y639572D01*
X132446D01*
X132101Y639417D01*
X131833Y639159D01*
X131641Y638849D01*
X131488Y638332D01*
X131450Y637867D01*
X131526Y637402D01*
X131641Y637092D01*
X131871Y636782D01*
X132140Y636575D01*
X132408Y636472D01*
X132676D01*
X132945Y636575D01*
X133175Y636730D01*
X133366Y636937D01*
G01X135508Y636472D02*
Y639572D01*
X135048Y638952D01*
G01Y636472D02*
X135968D01*
G01X137765Y637092D02*
X137995Y636730D01*
X138301Y636524D01*
X138646Y636472D01*
X138953Y636524D01*
X139260Y636782D01*
X139451Y637092D01*
X139490Y637402D01*
X139413Y637764D01*
X139145Y638022D01*
X138876Y638125D01*
X138531D01*
G01X138876D02*
X139106Y638280D01*
X139298Y638539D01*
X139375Y638849D01*
X139298Y639159D01*
X139106Y639417D01*
X138761Y639572D01*
X138416Y639520D01*
X138071Y639314D01*
G01X140980Y639055D02*
X141210Y639365D01*
X141478Y639520D01*
X141785Y639572D01*
X142168Y639469D01*
X142436Y639210D01*
X142513Y638900D01*
X142475Y638590D01*
X142321Y638332D01*
X141555Y637815D01*
X141210Y637454D01*
X140980Y636937D01*
X140903Y636472D01*
X142513D01*
G01X128255Y632032D02*
Y635132D01*
X129175D01*
X129482Y634977D01*
X129712Y634615D01*
X129789Y634202D01*
X129712Y633789D01*
X129520Y633479D01*
X129175Y633324D01*
X128255D01*
G01X132965Y634874D02*
X132735Y635029D01*
X132467Y635132D01*
X132160D01*
X131815Y634977D01*
X131547Y634719D01*
X131355Y634409D01*
X131202Y633892D01*
X131164Y633427D01*
X131240Y632962D01*
X131355Y632652D01*
X131585Y632342D01*
X131854Y632135D01*
X132122Y632032D01*
X132390D01*
X132659Y632135D01*
X132889Y632290D01*
X133080Y632497D01*
G01X134494Y633324D02*
X134762Y633685D01*
X134992Y633892D01*
X135299Y633995D01*
X135567Y633892D01*
X135759Y633685D01*
X135912Y633375D01*
X135950Y633014D01*
X135912Y632704D01*
X135759Y632394D01*
X135529Y632135D01*
X135260Y632032D01*
X134954Y632135D01*
X134685Y632445D01*
X134532Y632910D01*
X134494Y633427D01*
X134570Y634099D01*
X134685Y634460D01*
X134877Y634822D01*
X135145Y635080D01*
X135414Y635132D01*
X135682Y635029D01*
X135874Y634770D01*
G01X125320Y649768D02*
X122220D01*
Y650727D01*
X122375Y651033D01*
X122582Y651225D01*
X122995Y651302D01*
X123408Y651225D01*
X123667Y650995D01*
X123822Y650727D01*
Y649768D01*
G01Y650727D02*
X125320Y651302D01*
G01Y653635D02*
X122220D01*
X122840Y653175D01*
G01X125320D02*
Y654095D01*
G01X122220Y656735D02*
X122323Y656428D01*
X122582Y656198D01*
X122892Y656045D01*
X123305Y655930D01*
X123770Y655892D01*
X124235Y655930D01*
X124648Y656045D01*
X124958Y656198D01*
X125217Y656428D01*
X125320Y656735D01*
X125217Y657042D01*
X124958Y657272D01*
X124648Y657425D01*
X124235Y657540D01*
X123770Y657578D01*
X123305Y657540D01*
X122892Y657425D01*
X122582Y657272D01*
X122323Y657042D01*
X122220Y656735D01*
G01X124028Y659107D02*
X123667Y659375D01*
X123460Y659605D01*
X123357Y659912D01*
X123460Y660180D01*
X123667Y660372D01*
X123977Y660525D01*
X124338Y660563D01*
X124648Y660525D01*
X124958Y660372D01*
X125217Y660142D01*
X125320Y659873D01*
X125217Y659567D01*
X124907Y659298D01*
X124442Y659145D01*
X123925Y659107D01*
X123253Y659183D01*
X122892Y659298D01*
X122530Y659490D01*
X122272Y659758D01*
X122220Y660027D01*
X122323Y660295D01*
X122582Y660487D01*
G01X126383Y649937D02*
Y653037D01*
X127342D01*
X127648Y652882D01*
X127840Y652675D01*
X127917Y652262D01*
X127840Y651849D01*
X127610Y651590D01*
X127342Y651435D01*
X126383D01*
G01X127342D02*
X127917Y649937D01*
G01X130250D02*
Y653037D01*
X129790Y652417D01*
G01Y649937D02*
X130710D01*
G01X133350Y653037D02*
X133043Y652934D01*
X132813Y652675D01*
X132660Y652365D01*
X132545Y651952D01*
X132507Y651487D01*
X132545Y651022D01*
X132660Y650609D01*
X132813Y650299D01*
X133043Y650040D01*
X133350Y649937D01*
X133657Y650040D01*
X133887Y650299D01*
X134040Y650609D01*
X134155Y651022D01*
X134193Y651487D01*
X134155Y651952D01*
X134040Y652365D01*
X133887Y652675D01*
X133657Y652934D01*
X133350Y653037D01*
G01X135722Y652520D02*
X135952Y652830D01*
X136220Y652985D01*
X136527Y653037D01*
X136910Y652934D01*
X137178Y652675D01*
X137255Y652365D01*
X137217Y652055D01*
X137063Y651797D01*
X136297Y651280D01*
X135952Y650919D01*
X135722Y650402D01*
X135645Y649937D01*
X137255D01*
G01X138707Y650557D02*
X138937Y650195D01*
X139243Y649989D01*
X139588Y649937D01*
X139895Y649989D01*
X140202Y650247D01*
X140393Y650557D01*
X140432Y650867D01*
X140355Y651229D01*
X140087Y651487D01*
X139818Y651590D01*
X139473D01*
G01X139818D02*
X140048Y651745D01*
X140240Y652004D01*
X140317Y652314D01*
X140240Y652624D01*
X140048Y652882D01*
X139703Y653037D01*
X139358Y652985D01*
X139013Y652779D01*
G01X120820Y649768D02*
X117720D01*
Y650727D01*
X117875Y651033D01*
X118082Y651225D01*
X118495Y651302D01*
X118908Y651225D01*
X119167Y650995D01*
X119322Y650727D01*
Y649768D01*
G01Y650727D02*
X120820Y651302D01*
G01Y653635D02*
X117720D01*
X118340Y653175D01*
G01X120820D02*
Y654095D01*
G01X117720Y656735D02*
X117823Y656428D01*
X118082Y656198D01*
X118392Y656045D01*
X118805Y655930D01*
X119270Y655892D01*
X119735Y655930D01*
X120148Y656045D01*
X120458Y656198D01*
X120717Y656428D01*
X120820Y656735D01*
X120717Y657042D01*
X120458Y657272D01*
X120148Y657425D01*
X119735Y657540D01*
X119270Y657578D01*
X118805Y657540D01*
X118392Y657425D01*
X118082Y657272D01*
X117823Y657042D01*
X117720Y656735D01*
G01X118237Y659107D02*
X117927Y659337D01*
X117772Y659605D01*
X117720Y659912D01*
X117823Y660295D01*
X118082Y660563D01*
X118392Y660640D01*
X118702Y660602D01*
X118960Y660448D01*
X119477Y659682D01*
X119838Y659337D01*
X120355Y659107D01*
X120820Y659030D01*
Y660640D01*
G01Y662935D02*
X117720D01*
X118340Y662475D01*
G01X120820D02*
Y663395D01*
G01X127207Y649107D02*
Y646885D01*
X127360Y646420D01*
X127667Y646110D01*
X128050Y646007D01*
X128433Y646110D01*
X128740Y646420D01*
X128893Y646885D01*
Y649107D01*
G01X131150Y646007D02*
Y649107D01*
X130690Y648487D01*
G01Y646007D02*
X131610D01*
G01X134250Y649107D02*
X133943Y649004D01*
X133713Y648745D01*
X133560Y648435D01*
X133445Y648022D01*
X133407Y647557D01*
X133445Y647092D01*
X133560Y646679D01*
X133713Y646369D01*
X133943Y646110D01*
X134250Y646007D01*
X134557Y646110D01*
X134787Y646369D01*
X134940Y646679D01*
X135055Y647092D01*
X135093Y647557D01*
X135055Y648022D01*
X134940Y648435D01*
X134787Y648745D01*
X134557Y649004D01*
X134250Y649107D01*
G01X136698Y646369D02*
X136967Y646110D01*
X137273Y646007D01*
X137580Y646110D01*
X137848Y646420D01*
X138040Y646885D01*
X138117Y647350D01*
Y647919D01*
X138040Y648384D01*
X137848Y648797D01*
X137618Y649004D01*
X137350Y649107D01*
X137043Y649004D01*
X136813Y648797D01*
X136660Y648487D01*
X136583Y648074D01*
X136660Y647712D01*
X136852Y647350D01*
X137082Y647144D01*
X137350Y647092D01*
X137657Y647195D01*
X137887Y647454D01*
X138117Y647919D01*
G01X126042Y674371D02*
Y677371D01*
G01X122942Y674271D02*
Y677471D01*
G01X129142Y674271D02*
X122942D01*
G01X129142Y677471D02*
Y674271D01*
G01Y672479D02*
Y669279D01*
G01X122942Y672479D02*
X129142D01*
G01X122942Y669279D02*
Y672479D01*
G01X129142Y669279D02*
X122942D01*
G01X119428Y667238D02*
X125628D01*
Y664038D01*
X119428D01*
Y667238D01*
G01X130347Y664964D02*
Y677964D01*
G01X145347Y664964D02*
X130347D01*
G01X123420Y691318D02*
X125642D01*
X126107Y691471D01*
X126417Y691778D01*
X126520Y692161D01*
X126417Y692544D01*
X126107Y692851D01*
X125642Y693004D01*
X123420D01*
G01X126520Y695261D02*
X123420D01*
X124040Y694801D01*
G01X126520D02*
Y695721D01*
G01X123420Y698361D02*
X123523Y698054D01*
X123782Y697824D01*
X124092Y697671D01*
X124505Y697556D01*
X124970Y697518D01*
X125435Y697556D01*
X125848Y697671D01*
X126158Y697824D01*
X126417Y698054D01*
X126520Y698361D01*
X126417Y698668D01*
X126158Y698898D01*
X125848Y699051D01*
X125435Y699166D01*
X124970Y699204D01*
X124505Y699166D01*
X124092Y699051D01*
X123782Y698898D01*
X123523Y698668D01*
X123420Y698361D01*
G01Y701461D02*
X123523Y701154D01*
X123782Y700924D01*
X124092Y700771D01*
X124505Y700656D01*
X124970Y700618D01*
X125435Y700656D01*
X125848Y700771D01*
X126158Y700924D01*
X126417Y701154D01*
X126520Y701461D01*
X126417Y701768D01*
X126158Y701998D01*
X125848Y702151D01*
X125435Y702266D01*
X124970Y702304D01*
X124505Y702266D01*
X124092Y702151D01*
X123782Y701998D01*
X123523Y701768D01*
X123420Y701461D01*
G01X131107Y690787D02*
X128107D01*
G01X131207Y687687D02*
X128007D01*
G01X131207Y693887D02*
Y687687D01*
G01X128007D02*
Y693887D01*
G01X122942Y677471D02*
X129142D01*
G01X135207Y687687D02*
X132007D01*
G01D02*
Y693887D01*
G01X132870Y680667D02*
X133637D01*
Y679737D01*
X133407Y679427D01*
X133138Y679220D01*
X132755Y679117D01*
X132372Y679220D01*
X132103Y679427D01*
X131873Y679737D01*
X131720Y680099D01*
X131643Y680512D01*
Y680874D01*
X131720Y681184D01*
X131873Y681545D01*
X132103Y681855D01*
X132333Y682062D01*
X132640Y682217D01*
X132908D01*
X133215Y682114D01*
X133445Y681907D01*
G01X130347Y677964D02*
X145347D01*
G01X126332Y703347D02*
Y713899D01*
G01X138544Y703347D02*
X126332D01*
G01X128007Y693887D02*
X131207D01*
G01X132007D02*
X135207D01*
G01X126332Y713899D02*
X138544D01*
G01X130759Y728250D02*
Y731250D01*
G01X127659Y728150D02*
Y731350D01*
G01X133859Y728150D02*
X127659D01*
G01Y731350D02*
X133859D01*
G01X122328Y734984D02*
X126928D01*
G01X122328Y724784D02*
Y734984D01*
G01X126928Y724784D02*
X122328D01*
G01X126928Y734984D02*
Y724784D01*
G01Y729884D02*
X122328D01*
G01X127659Y723650D02*
Y726850D01*
G01X133859Y723650D02*
X127659D01*
G01Y726850D02*
X133859D01*
G01X132302Y735765D02*
X122102D01*
G01X132302Y740365D02*
Y735765D01*
G01X122102D02*
Y740365D01*
G01D02*
X132302D01*
G01X142509Y7672D02*
X142217Y7512D01*
X142051Y7298D01*
X142009Y7058D01*
X142051Y6845D01*
X142259Y6632D01*
X142509Y6498D01*
X142759Y6472D01*
X143051Y6525D01*
X143259Y6712D01*
X143342Y6898D01*
Y7138D01*
G01Y6898D02*
X143467Y6738D01*
X143676Y6605D01*
X143926Y6552D01*
X144176Y6605D01*
X144384Y6738D01*
X144509Y6978D01*
X144467Y7218D01*
X144301Y7458D01*
G01X135822Y7592D02*
X136072Y7432D01*
X136197Y7245D01*
X136239Y7032D01*
X136156Y6765D01*
X135947Y6578D01*
X135697Y6525D01*
X135447Y6552D01*
X135239Y6658D01*
X134822Y7192D01*
X134531Y7432D01*
X134114Y7592D01*
X133739Y7645D01*
Y6525D01*
G01X147303Y21662D02*
Y8662D01*
G01X144834Y31229D02*
X145021Y31520D01*
X145181Y31687D01*
X145394Y31770D01*
X145581Y31687D01*
X145714Y31520D01*
X145821Y31270D01*
X145848Y30979D01*
X145821Y30729D01*
X145714Y30479D01*
X145554Y30270D01*
X145368Y30187D01*
X145154Y30270D01*
X144968Y30520D01*
X144861Y30895D01*
X144834Y31312D01*
X144888Y31854D01*
X144968Y32145D01*
X145101Y32437D01*
X145288Y32645D01*
X145474Y32687D01*
X145661Y32604D01*
X145794Y32395D01*
G01X134392Y22972D02*
X136892D01*
X136392Y23292D01*
G01X134392D02*
Y22652D01*
G01X139399Y23294D02*
Y33494D01*
G01X143999Y28394D02*
X139399D01*
G01X143999Y33494D02*
Y23294D01*
G01D02*
X139399D01*
G01X147980Y28891D02*
Y22691D01*
G01D02*
X144780D01*
G01D02*
Y28891D01*
G01D02*
X147980D01*
G01X139709Y37396D02*
X139869Y37188D01*
X140056Y37063D01*
X140296Y37021D01*
X140536Y37104D01*
X140723Y37271D01*
X140856Y37563D01*
X140883Y37896D01*
X140829Y38229D01*
X140696Y38438D01*
X140509Y38604D01*
X140323Y38646D01*
X140136Y38604D01*
X139896Y38438D01*
X139976Y39521D01*
X140696D01*
G01X139949Y46104D02*
Y48604D01*
X139629Y48104D01*
G01Y46104D02*
X140269D01*
G01X143832Y36357D02*
Y34457D01*
G01Y44757D02*
Y45157D01*
G01D02*
X145332Y46657D01*
G01X143832Y34457D02*
X145732D01*
G01X139399Y33494D02*
X143999D01*
G01X138757Y45039D02*
Y41839D01*
G01X138761Y40791D02*
Y37591D01*
G01X135409Y36835D02*
X138609D01*
G01D02*
Y30635D01*
G01D02*
X135409D01*
G01D02*
Y36835D01*
G01X141734Y49786D02*
X141894Y50036D01*
X142081Y50161D01*
X142294Y50203D01*
X142561Y50120D01*
X142748Y49911D01*
X142801Y49661D01*
X142774Y49411D01*
X142668Y49203D01*
X142134Y48786D01*
X141894Y48495D01*
X141734Y48078D01*
X141681Y47703D01*
X142801D01*
G01X144441Y50203D02*
X144228Y50120D01*
X144068Y49911D01*
X143961Y49661D01*
X143881Y49328D01*
X143854Y48953D01*
X143881Y48578D01*
X143961Y48245D01*
X144068Y47995D01*
X144228Y47786D01*
X144441Y47703D01*
X144654Y47786D01*
X144814Y47995D01*
X144921Y48245D01*
X145001Y48578D01*
X145028Y48953D01*
X145001Y49328D01*
X144921Y49661D01*
X144814Y49911D01*
X144654Y50120D01*
X144441Y50203D01*
G01X145332Y46657D02*
X145732D01*
G01X143610Y52985D02*
Y59185D01*
G01D02*
X146810D01*
G01D02*
Y52985D01*
G01D02*
X143610D01*
G01X146710Y56085D02*
X143710D01*
G01X136883Y52523D02*
X133783D01*
Y53443D01*
X133938Y53750D01*
X134300Y53980D01*
X134713Y54057D01*
X135126Y53980D01*
X135436Y53788D01*
X135591Y53443D01*
Y52523D01*
G01X136883Y55623D02*
X133783D01*
Y56582D01*
X133938Y56888D01*
X134145Y57080D01*
X134558Y57157D01*
X134971Y57080D01*
X135230Y56850D01*
X135385Y56582D01*
Y55623D01*
G01Y56582D02*
X136883Y57157D01*
G01Y59490D02*
X133783D01*
X134403Y59030D01*
G01X136883D02*
Y59950D01*
G01X133783Y62590D02*
X133886Y62283D01*
X134145Y62053D01*
X134455Y61900D01*
X134868Y61785D01*
X135333Y61747D01*
X135798Y61785D01*
X136211Y61900D01*
X136521Y62053D01*
X136780Y62283D01*
X136883Y62590D01*
X136780Y62897D01*
X136521Y63127D01*
X136211Y63280D01*
X135798Y63395D01*
X135333Y63433D01*
X134868Y63395D01*
X134455Y63280D01*
X134145Y63127D01*
X133886Y62897D01*
X133783Y62590D01*
G01X136263Y64847D02*
X136625Y65077D01*
X136831Y65383D01*
X136883Y65728D01*
X136831Y66035D01*
X136573Y66342D01*
X136263Y66533D01*
X135953Y66572D01*
X135591Y66495D01*
X135333Y66227D01*
X135230Y65958D01*
Y65613D01*
G01Y65958D02*
X135075Y66188D01*
X134816Y66380D01*
X134506Y66457D01*
X134196Y66380D01*
X133938Y66188D01*
X133783Y65843D01*
X133835Y65498D01*
X134041Y65153D01*
G01X150757Y52905D02*
X147557D01*
G01D02*
Y59105D01*
G01D02*
X150757D01*
G01X142760Y59155D02*
Y52955D01*
G01D02*
X139560D01*
G01D02*
Y59155D01*
G01D02*
X142760D01*
G01X132626Y48970D02*
X138826D01*
G01D02*
Y45770D01*
G01D02*
X132626D01*
G01D02*
Y48970D01*
G01X136863Y72958D02*
X136633Y73113D01*
X136365Y73216D01*
X136058D01*
X135713Y73061D01*
X135445Y72803D01*
X135253Y72493D01*
X135100Y71976D01*
X135062Y71511D01*
X135138Y71046D01*
X135253Y70736D01*
X135483Y70426D01*
X135752Y70219D01*
X136020Y70116D01*
X136288D01*
X136557Y70219D01*
X136787Y70374D01*
X136978Y70581D01*
G01X139120Y70116D02*
Y73216D01*
X138660Y72596D01*
G01Y70116D02*
X139580D01*
G01X142680D02*
Y73216D01*
X141262Y70994D01*
X143178D01*
G01X144477Y70736D02*
X144707Y70374D01*
X145013Y70168D01*
X145358Y70116D01*
X145665Y70168D01*
X145972Y70426D01*
X146163Y70736D01*
X146202Y71046D01*
X146125Y71408D01*
X145857Y71666D01*
X145588Y71769D01*
X145243D01*
G01X145588D02*
X145818Y71924D01*
X146010Y72183D01*
X146087Y72493D01*
X146010Y72803D01*
X145818Y73061D01*
X145473Y73216D01*
X145128Y73164D01*
X144783Y72958D01*
G01X142102Y78088D02*
Y75088D01*
G01X145202Y78188D02*
Y74988D01*
G01D02*
X139002D01*
G01D02*
Y78188D01*
G01X138214D02*
Y74988D01*
G01X147878Y76463D02*
X154078D01*
G01Y73263D02*
X147878D01*
G01D02*
Y76463D01*
G01X147223Y64506D02*
Y67606D01*
X148143D01*
X148450Y67451D01*
X148680Y67089D01*
X148757Y66676D01*
X148680Y66263D01*
X148488Y65953D01*
X148143Y65798D01*
X147223D01*
G01X150323Y64506D02*
Y67606D01*
X151282D01*
X151588Y67451D01*
X151780Y67244D01*
X151857Y66831D01*
X151780Y66418D01*
X151550Y66159D01*
X151282Y66004D01*
X150323D01*
G01X151282D02*
X151857Y64506D01*
G01X153347Y65126D02*
X153577Y64764D01*
X153883Y64558D01*
X154228Y64506D01*
X154535Y64558D01*
X154842Y64816D01*
X155033Y65126D01*
X155072Y65436D01*
X154995Y65798D01*
X154727Y66056D01*
X154458Y66159D01*
X154113D01*
G01X154458D02*
X154688Y66314D01*
X154880Y66573D01*
X154957Y66883D01*
X154880Y67193D01*
X154688Y67451D01*
X154343Y67606D01*
X153998Y67554D01*
X153653Y67348D01*
G01X156447Y65126D02*
X156677Y64764D01*
X156983Y64558D01*
X157328Y64506D01*
X157635Y64558D01*
X157942Y64816D01*
X158133Y65126D01*
X158172Y65436D01*
X158095Y65798D01*
X157827Y66056D01*
X157558Y66159D01*
X157213D01*
G01X157558D02*
X157788Y66314D01*
X157980Y66573D01*
X158057Y66883D01*
X157980Y67193D01*
X157788Y67451D01*
X157443Y67606D01*
X157098Y67554D01*
X156753Y67348D01*
G01X139002Y78188D02*
X145202D01*
G01X137796Y98622D02*
Y79527D01*
G01D02*
X157565D01*
G01X136910Y135930D02*
X137796Y98622D01*
G01X135827Y181496D02*
X136437Y155821D01*
G01X157284Y181496D02*
X135827D01*
G01X145200Y202930D02*
Y193050D01*
G01X163790Y202930D02*
X145200D01*
G01X136477Y199827D02*
Y197605D01*
X136630Y197140D01*
X136937Y196830D01*
X137320Y196727D01*
X137703Y196830D01*
X138010Y197140D01*
X138163Y197605D01*
Y199827D01*
G01X140880Y196727D02*
Y199827D01*
X139462Y197605D01*
X141378D01*
G01X143520Y196727D02*
X143788Y196779D01*
X144095Y196934D01*
X144287Y197192D01*
X144363Y197554D01*
X144287Y197915D01*
X144057Y198225D01*
X143712Y198380D01*
X143328D01*
X143098Y198484D01*
X142907Y198742D01*
X142830Y199104D01*
X142945Y199465D01*
X143213Y199724D01*
X143520Y199827D01*
X143827Y199724D01*
X144095Y199465D01*
X144210Y199104D01*
X144133Y198742D01*
X143942Y198484D01*
X143712Y198380D01*
X143328D01*
X142983Y198225D01*
X142753Y197915D01*
X142677Y197554D01*
X142753Y197192D01*
X142945Y196934D01*
X143252Y196779D01*
X143520Y196727D01*
G01X148080Y217200D02*
X163790D01*
G01X148080Y225380D02*
Y217200D01*
G01X135957Y215797D02*
Y213575D01*
X136110Y213110D01*
X136417Y212800D01*
X136800Y212697D01*
X137183Y212800D01*
X137490Y213110D01*
X137643Y213575D01*
Y215797D01*
G01X140360Y212697D02*
Y215797D01*
X138942Y213575D01*
X140858D01*
G01X143460Y212697D02*
Y215797D01*
X142042Y213575D01*
X143958D01*
G01X146783Y210457D02*
Y213557D01*
X147742D01*
X148048Y213402D01*
X148240Y213195D01*
X148317Y212782D01*
X148240Y212369D01*
X148010Y212110D01*
X147742Y211955D01*
X146783D01*
G01X147742D02*
X148317Y210457D01*
G01X149922Y211749D02*
X150190Y212110D01*
X150420Y212317D01*
X150727Y212420D01*
X150995Y212317D01*
X151187Y212110D01*
X151340Y211800D01*
X151378Y211439D01*
X151340Y211129D01*
X151187Y210819D01*
X150957Y210560D01*
X150688Y210457D01*
X150382Y210560D01*
X150113Y210870D01*
X149960Y211335D01*
X149922Y211852D01*
X149998Y212524D01*
X150113Y212885D01*
X150305Y213247D01*
X150573Y213505D01*
X150842Y213557D01*
X151110Y213454D01*
X151302Y213195D01*
G01X152907Y210922D02*
X153137Y210664D01*
X153405Y210509D01*
X153750Y210457D01*
X154095Y210560D01*
X154363Y210767D01*
X154555Y211129D01*
X154593Y211542D01*
X154517Y211955D01*
X154325Y212214D01*
X154057Y212420D01*
X153788Y212472D01*
X153520Y212420D01*
X153175Y212214D01*
X153290Y213557D01*
X154325D01*
G01X156850Y210457D02*
X157118Y210509D01*
X157425Y210664D01*
X157617Y210922D01*
X157693Y211284D01*
X157617Y211645D01*
X157387Y211955D01*
X157042Y212110D01*
X156658D01*
X156428Y212214D01*
X156237Y212472D01*
X156160Y212834D01*
X156275Y213195D01*
X156543Y213454D01*
X156850Y213557D01*
X157157Y213454D01*
X157425Y213195D01*
X157540Y212834D01*
X157463Y212472D01*
X157272Y212214D01*
X157042Y212110D01*
X156658D01*
X156313Y211955D01*
X156083Y211645D01*
X156007Y211284D01*
X156083Y210922D01*
X156275Y210664D01*
X156582Y210509D01*
X156850Y210457D01*
G01X146226Y298335D02*
Y295135D01*
G01X142776Y298335D02*
Y295135D01*
G01X143476Y298335D02*
Y295135D01*
G01X146226D02*
X140026D01*
G01D02*
Y298335D01*
G01X147618Y286587D02*
Y283387D01*
G01X141418Y286587D02*
X147618D01*
G01Y283387D02*
X141418D01*
G01D02*
Y286587D01*
G01X147618Y290587D02*
Y287387D01*
G01X141418Y290587D02*
X147618D01*
G01Y287387D02*
X141418D01*
G01D02*
Y290587D01*
G01X147618Y291387D02*
X141418D01*
G01D02*
Y294587D01*
G01D02*
X147618D01*
G01D02*
Y291387D01*
G01X145937Y302225D02*
Y299025D01*
G01X142837Y299125D02*
Y302125D01*
G01X139737Y302225D02*
X145937D01*
G01Y299025D02*
X139737D01*
G01D02*
Y302225D01*
G01X147575Y307940D02*
Y303340D01*
G01X137375Y307940D02*
X147575D01*
G01Y303340D02*
X137375D01*
G01D02*
Y307940D01*
G01X142475D02*
Y303340D01*
G01X140026Y298335D02*
X146226D01*
G01X143532Y316143D02*
Y312943D01*
G01D02*
X137332D01*
G01D02*
Y316143D01*
G01Y312143D02*
X143532D01*
G01D02*
Y308943D01*
G01D02*
X137332D01*
G01D02*
Y312143D01*
G01X143913Y329533D02*
Y326333D01*
G01D02*
X137713D01*
G01D02*
Y329533D01*
G01X137332Y325143D02*
X143532D01*
G01D02*
Y321943D01*
G01D02*
X137332D01*
G01D02*
Y325143D01*
G01Y320643D02*
X143532D01*
G01D02*
Y317443D01*
G01D02*
X137332D01*
G01D02*
Y320643D01*
G01Y316143D02*
X143532D01*
G01X144056Y333646D02*
Y330446D01*
G01X137856Y333646D02*
X144056D01*
G01Y330446D02*
X137856D01*
G01D02*
Y333646D01*
G01X137713Y329533D02*
X143913D01*
G01X139084Y387143D02*
X135984D01*
Y388102D01*
X136139Y388408D01*
X136346Y388600D01*
X136759Y388677D01*
X137172Y388600D01*
X137431Y388370D01*
X137586Y388102D01*
Y387143D01*
G01Y388102D02*
X139084Y388677D01*
G01Y391010D02*
X135984D01*
X136604Y390550D01*
G01X139084D02*
Y391470D01*
G01X135984Y394110D02*
X136087Y393803D01*
X136346Y393573D01*
X136656Y393420D01*
X137069Y393305D01*
X137534Y393267D01*
X137999Y393305D01*
X138412Y393420D01*
X138722Y393573D01*
X138981Y393803D01*
X139084Y394110D01*
X138981Y394417D01*
X138722Y394647D01*
X138412Y394800D01*
X137999Y394915D01*
X137534Y394953D01*
X137069Y394915D01*
X136656Y394800D01*
X136346Y394647D01*
X136087Y394417D01*
X135984Y394110D01*
G01X139084Y397210D02*
X139032Y397478D01*
X138877Y397785D01*
X138619Y397977D01*
X138257Y398053D01*
X137896Y397977D01*
X137586Y397747D01*
X137431Y397402D01*
Y397018D01*
X137327Y396788D01*
X137069Y396597D01*
X136707Y396520D01*
X136346Y396635D01*
X136087Y396903D01*
X135984Y397210D01*
X136087Y397517D01*
X136346Y397785D01*
X136707Y397900D01*
X137069Y397823D01*
X137327Y397632D01*
X137431Y397402D01*
Y397018D01*
X137586Y396673D01*
X137896Y396443D01*
X138257Y396367D01*
X138619Y396443D01*
X138877Y396635D01*
X139032Y396942D01*
X139084Y397210D01*
G01X138722Y399658D02*
X138981Y399927D01*
X139084Y400233D01*
X138981Y400540D01*
X138671Y400808D01*
X138206Y401000D01*
X137741Y401077D01*
X137172D01*
X136707Y401000D01*
X136294Y400808D01*
X136087Y400578D01*
X135984Y400310D01*
X136087Y400003D01*
X136294Y399773D01*
X136604Y399620D01*
X137017Y399543D01*
X137379Y399620D01*
X137741Y399812D01*
X137947Y400042D01*
X137999Y400310D01*
X137896Y400617D01*
X137637Y400847D01*
X137172Y401077D01*
G01X141920Y396028D02*
X141690Y396183D01*
X141422Y396286D01*
X141115D01*
X140770Y396131D01*
X140502Y395873D01*
X140310Y395563D01*
X140157Y395046D01*
X140119Y394581D01*
X140195Y394116D01*
X140310Y393806D01*
X140540Y393496D01*
X140809Y393289D01*
X141077Y393186D01*
X141345D01*
X141614Y393289D01*
X141844Y393444D01*
X142035Y393651D01*
G01X144177Y393186D02*
X144445Y393238D01*
X144752Y393393D01*
X144944Y393651D01*
X145020Y394013D01*
X144944Y394374D01*
X144714Y394684D01*
X144369Y394839D01*
X143985D01*
X143755Y394943D01*
X143564Y395201D01*
X143487Y395563D01*
X143602Y395924D01*
X143870Y396183D01*
X144177Y396286D01*
X144484Y396183D01*
X144752Y395924D01*
X144867Y395563D01*
X144790Y395201D01*
X144599Y394943D01*
X144369Y394839D01*
X143985D01*
X143640Y394684D01*
X143410Y394374D01*
X143334Y394013D01*
X143410Y393651D01*
X143602Y393393D01*
X143909Y393238D01*
X144177Y393186D01*
G01X146549Y395769D02*
X146779Y396079D01*
X147047Y396234D01*
X147354Y396286D01*
X147737Y396183D01*
X148005Y395924D01*
X148082Y395614D01*
X148044Y395304D01*
X147890Y395046D01*
X147124Y394529D01*
X146779Y394168D01*
X146549Y393651D01*
X146472Y393186D01*
X148082D01*
G01X149534Y393806D02*
X149764Y393444D01*
X150070Y393238D01*
X150415Y393186D01*
X150722Y393238D01*
X151029Y393496D01*
X151220Y393806D01*
X151259Y394116D01*
X151182Y394478D01*
X150914Y394736D01*
X150645Y394839D01*
X150300D01*
G01X150645D02*
X150875Y394994D01*
X151067Y395253D01*
X151144Y395563D01*
X151067Y395873D01*
X150875Y396131D01*
X150530Y396286D01*
X150185Y396234D01*
X149840Y396028D01*
G01X146185Y405828D02*
X139985D01*
G01D02*
Y409028D01*
G01X146185D02*
Y405828D01*
G01X143085Y408928D02*
Y405928D01*
G01X139304Y413528D02*
Y407328D01*
G01X136104D02*
Y413528D01*
G01X139304Y407328D02*
X136104D01*
G01X140310Y397186D02*
Y400286D01*
X141269D01*
X141575Y400131D01*
X141767Y399924D01*
X141844Y399511D01*
X141767Y399098D01*
X141537Y398839D01*
X141269Y398684D01*
X140310D01*
G01X141269D02*
X141844Y397186D01*
G01X144177D02*
Y400286D01*
X143717Y399666D01*
G01Y397186D02*
X144637D01*
G01X147277Y400286D02*
X146970Y400183D01*
X146740Y399924D01*
X146587Y399614D01*
X146472Y399201D01*
X146434Y398736D01*
X146472Y398271D01*
X146587Y397858D01*
X146740Y397548D01*
X146970Y397289D01*
X147277Y397186D01*
X147584Y397289D01*
X147814Y397548D01*
X147967Y397858D01*
X148082Y398271D01*
X148120Y398736D01*
X148082Y399201D01*
X147967Y399614D01*
X147814Y399924D01*
X147584Y400183D01*
X147277Y400286D01*
G01X150377Y397186D02*
X150645Y397238D01*
X150952Y397393D01*
X151144Y397651D01*
X151220Y398013D01*
X151144Y398374D01*
X150914Y398684D01*
X150569Y398839D01*
X150185D01*
X149955Y398943D01*
X149764Y399201D01*
X149687Y399563D01*
X149802Y399924D01*
X150070Y400183D01*
X150377Y400286D01*
X150684Y400183D01*
X150952Y399924D01*
X151067Y399563D01*
X150990Y399201D01*
X150799Y398943D01*
X150569Y398839D01*
X150185D01*
X149840Y398684D01*
X149610Y398374D01*
X149534Y398013D01*
X149610Y397651D01*
X149802Y397393D01*
X150109Y397238D01*
X150377Y397186D01*
G01X153477D02*
X153745Y397238D01*
X154052Y397393D01*
X154244Y397651D01*
X154320Y398013D01*
X154244Y398374D01*
X154014Y398684D01*
X153669Y398839D01*
X153285D01*
X153055Y398943D01*
X152864Y399201D01*
X152787Y399563D01*
X152902Y399924D01*
X153170Y400183D01*
X153477Y400286D01*
X153784Y400183D01*
X154052Y399924D01*
X154167Y399563D01*
X154090Y399201D01*
X153899Y398943D01*
X153669Y398839D01*
X153285D01*
X152940Y398684D01*
X152710Y398374D01*
X152634Y398013D01*
X152710Y397651D01*
X152902Y397393D01*
X153209Y397238D01*
X153477Y397186D01*
G01X139985Y409028D02*
X146185D01*
G01X138551Y416970D02*
X138321Y417125D01*
X138053Y417228D01*
X137746D01*
X137401Y417073D01*
X137133Y416815D01*
X136941Y416505D01*
X136788Y415988D01*
X136750Y415523D01*
X136826Y415058D01*
X136941Y414748D01*
X137171Y414438D01*
X137440Y414231D01*
X137708Y414128D01*
X137976D01*
X138245Y414231D01*
X138475Y414386D01*
X138666Y414593D01*
G01X140808Y414128D02*
X141076Y414180D01*
X141383Y414335D01*
X141575Y414593D01*
X141651Y414955D01*
X141575Y415316D01*
X141345Y415626D01*
X141000Y415781D01*
X140616D01*
X140386Y415885D01*
X140195Y416143D01*
X140118Y416505D01*
X140233Y416866D01*
X140501Y417125D01*
X140808Y417228D01*
X141115Y417125D01*
X141383Y416866D01*
X141498Y416505D01*
X141421Y416143D01*
X141230Y415885D01*
X141000Y415781D01*
X140616D01*
X140271Y415626D01*
X140041Y415316D01*
X139965Y414955D01*
X140041Y414593D01*
X140233Y414335D01*
X140540Y414180D01*
X140808Y414128D01*
G01X143180Y416711D02*
X143410Y417021D01*
X143678Y417176D01*
X143985Y417228D01*
X144368Y417125D01*
X144636Y416866D01*
X144713Y416556D01*
X144675Y416246D01*
X144521Y415988D01*
X143755Y415471D01*
X143410Y415110D01*
X143180Y414593D01*
X143103Y414128D01*
X144713D01*
G01X147468D02*
Y417228D01*
X146050Y415006D01*
X147966D01*
G01X133689Y419752D02*
Y416552D01*
G01X136104Y413528D02*
X139304D01*
G01X139985Y413028D02*
X146185D01*
G01Y409828D02*
X139985D01*
G01D02*
Y413028D01*
G01X146185D02*
Y409828D01*
G01X137003Y418157D02*
Y421257D01*
X137962D01*
X138268Y421102D01*
X138460Y420895D01*
X138537Y420482D01*
X138460Y420069D01*
X138230Y419810D01*
X137962Y419655D01*
X137003D01*
G01X137962D02*
X138537Y418157D01*
G01X140870D02*
Y421257D01*
X140410Y420637D01*
G01Y418157D02*
X141330D01*
G01X143970Y421257D02*
X143663Y421154D01*
X143433Y420895D01*
X143280Y420585D01*
X143165Y420172D01*
X143127Y419707D01*
X143165Y419242D01*
X143280Y418829D01*
X143433Y418519D01*
X143663Y418260D01*
X143970Y418157D01*
X144277Y418260D01*
X144507Y418519D01*
X144660Y418829D01*
X144775Y419242D01*
X144813Y419707D01*
X144775Y420172D01*
X144660Y420585D01*
X144507Y420895D01*
X144277Y421154D01*
X143970Y421257D01*
G01X147070Y418157D02*
X147338Y418209D01*
X147645Y418364D01*
X147837Y418622D01*
X147913Y418984D01*
X147837Y419345D01*
X147607Y419655D01*
X147262Y419810D01*
X146878D01*
X146648Y419914D01*
X146457Y420172D01*
X146380Y420534D01*
X146495Y420895D01*
X146763Y421154D01*
X147070Y421257D01*
X147377Y421154D01*
X147645Y420895D01*
X147760Y420534D01*
X147683Y420172D01*
X147492Y419914D01*
X147262Y419810D01*
X146878D01*
X146533Y419655D01*
X146303Y419345D01*
X146227Y418984D01*
X146303Y418622D01*
X146495Y418364D01*
X146802Y418209D01*
X147070Y418157D01*
G01X150093D02*
X150170Y418829D01*
X150285Y419397D01*
X150438Y419914D01*
X150630Y420482D01*
X150937Y421257D01*
X149403D01*
G01X133703Y423920D02*
Y420720D01*
G01X148984Y425963D02*
X145884D01*
Y426922D01*
X146039Y427228D01*
X146246Y427420D01*
X146659Y427497D01*
X147072Y427420D01*
X147331Y427190D01*
X147486Y426922D01*
Y425963D01*
G01Y426922D02*
X148984Y427497D01*
G01Y429830D02*
X145884D01*
X146504Y429370D01*
G01X148984D02*
Y430290D01*
G01Y432930D02*
X145884D01*
X146504Y432470D01*
G01X148984D02*
Y433390D01*
G01Y436030D02*
X145884D01*
X146504Y435570D01*
G01X148984D02*
Y436490D01*
G01Y439130D02*
X148932Y439398D01*
X148777Y439705D01*
X148519Y439897D01*
X148157Y439973D01*
X147796Y439897D01*
X147486Y439667D01*
X147331Y439322D01*
Y438938D01*
X147227Y438708D01*
X146969Y438517D01*
X146607Y438440D01*
X146246Y438555D01*
X145987Y438823D01*
X145884Y439130D01*
X145987Y439437D01*
X146246Y439705D01*
X146607Y439820D01*
X146969Y439743D01*
X147227Y439552D01*
X147331Y439322D01*
Y438938D01*
X147486Y438593D01*
X147796Y438363D01*
X148157Y438287D01*
X148519Y438363D01*
X148777Y438555D01*
X148932Y438862D01*
X148984Y439130D01*
G01X144011Y444321D02*
Y443515D01*
G01D02*
X139505D01*
G01X144011Y455326D02*
Y454621D01*
G01X134376Y464338D02*
Y461138D01*
G01Y472338D02*
Y469138D01*
G01Y468338D02*
Y465138D01*
G01Y460333D02*
Y457133D01*
G01X139505Y455326D02*
X144011D01*
G01X135288Y464909D02*
X135501Y464701D01*
X135741Y464576D01*
X135955D01*
X136168Y464701D01*
X136328Y464909D01*
X136408Y465201D01*
X136355Y465493D01*
X136221Y465743D01*
X135981Y465909D01*
X135661Y465993D01*
X135475Y466159D01*
X135395Y466451D01*
X135448Y466743D01*
X135581Y466951D01*
X135768Y467076D01*
X135955D01*
X136141Y466993D01*
X136301Y466784D01*
G01X134426Y459127D02*
Y461627D01*
X134960D01*
X135173Y461502D01*
X135333Y461335D01*
X135466Y461085D01*
X135573Y460794D01*
X135600Y460377D01*
X135573Y459960D01*
X135466Y459669D01*
X135333Y459419D01*
X135173Y459252D01*
X134960Y459127D01*
X134426D01*
G01X136594Y470655D02*
X148406D01*
G01Y458031D02*
X136594D01*
G01D02*
Y470655D01*
G01X137090Y472427D02*
X136783Y472479D01*
X136515Y472685D01*
X136285Y472995D01*
X136132Y473357D01*
X136055Y473770D01*
Y474184D01*
X136132Y474597D01*
X136285Y474959D01*
X136515Y475269D01*
X136783Y475475D01*
X137090Y475527D01*
X137397Y475475D01*
X137665Y475269D01*
X137895Y474959D01*
X138048Y474597D01*
X138125Y474184D01*
Y473770D01*
X138048Y473357D01*
X137895Y472995D01*
X137665Y472685D01*
X137397Y472479D01*
X137090Y472427D01*
G01X137397Y473254D02*
X137857Y472427D01*
G01X140650D02*
Y475527D01*
X139232Y473305D01*
X141148D01*
G01X143290Y475527D02*
X142983Y475424D01*
X142753Y475165D01*
X142600Y474855D01*
X142485Y474442D01*
X142447Y473977D01*
X142485Y473512D01*
X142600Y473099D01*
X142753Y472789D01*
X142983Y472530D01*
X143290Y472427D01*
X143597Y472530D01*
X143827Y472789D01*
X143980Y473099D01*
X144095Y473512D01*
X144133Y473977D01*
X144095Y474442D01*
X143980Y474855D01*
X143827Y475165D01*
X143597Y475424D01*
X143290Y475527D01*
G01X137104Y498623D02*
X136949Y498393D01*
X136846Y498125D01*
Y497818D01*
X137001Y497473D01*
X137259Y497205D01*
X137569Y497013D01*
X138086Y496860D01*
X138551Y496822D01*
X139016Y496898D01*
X139326Y497013D01*
X139636Y497243D01*
X139843Y497512D01*
X139946Y497780D01*
Y498048D01*
X139843Y498317D01*
X139688Y498547D01*
X139481Y498738D01*
G01X139946Y500880D02*
X139894Y501148D01*
X139739Y501455D01*
X139481Y501647D01*
X139119Y501723D01*
X138758Y501647D01*
X138448Y501417D01*
X138293Y501072D01*
Y500688D01*
X138189Y500458D01*
X137931Y500267D01*
X137569Y500190D01*
X137208Y500305D01*
X136949Y500573D01*
X136846Y500880D01*
X136949Y501187D01*
X137208Y501455D01*
X137569Y501570D01*
X137931Y501493D01*
X138189Y501302D01*
X138293Y501072D01*
Y500688D01*
X138448Y500343D01*
X138758Y500113D01*
X139119Y500037D01*
X139481Y500113D01*
X139739Y500305D01*
X139894Y500612D01*
X139946Y500880D01*
G01X139326Y503137D02*
X139688Y503367D01*
X139894Y503673D01*
X139946Y504018D01*
X139894Y504325D01*
X139636Y504632D01*
X139326Y504823D01*
X139016Y504862D01*
X138654Y504785D01*
X138396Y504517D01*
X138293Y504248D01*
Y503903D01*
G01Y504248D02*
X138138Y504478D01*
X137879Y504670D01*
X137569Y504747D01*
X137259Y504670D01*
X137001Y504478D01*
X136846Y504133D01*
X136898Y503788D01*
X137104Y503443D01*
G01X136846Y507080D02*
X136949Y506773D01*
X137208Y506543D01*
X137518Y506390D01*
X137931Y506275D01*
X138396Y506237D01*
X138861Y506275D01*
X139274Y506390D01*
X139584Y506543D01*
X139843Y506773D01*
X139946Y507080D01*
X139843Y507387D01*
X139584Y507617D01*
X139274Y507770D01*
X138861Y507885D01*
X138396Y507923D01*
X137931Y507885D01*
X137518Y507770D01*
X137208Y507617D01*
X136949Y507387D01*
X136846Y507080D01*
G01X135552Y508932D02*
Y493932D01*
G01X142650Y493164D02*
Y569542D01*
G01X196193Y493164D02*
X142650D01*
G01X145551Y509646D02*
Y512746D01*
X147315Y509646D01*
Y512746D01*
G01X145666Y503347D02*
Y506447D01*
X146625D01*
X146931Y506292D01*
X147123Y506085D01*
X147200Y505672D01*
X147123Y505259D01*
X146893Y505000D01*
X146625Y504845D01*
X145666D01*
G01X146625D02*
X147200Y503347D01*
G01X145666Y519045D02*
Y515945D01*
X147200D01*
G01X135277Y515304D02*
Y512304D01*
G01X138377Y515404D02*
Y512204D01*
G01X137883Y533394D02*
X140105D01*
X140570Y533547D01*
X140880Y533854D01*
X140983Y534237D01*
X140880Y534620D01*
X140570Y534927D01*
X140105Y535080D01*
X137883D01*
G01X140983Y537337D02*
X137883D01*
X138503Y536877D01*
G01X140983D02*
Y537797D01*
G01X140518Y539594D02*
X140776Y539824D01*
X140931Y540092D01*
X140983Y540437D01*
X140880Y540782D01*
X140673Y541050D01*
X140311Y541242D01*
X139898Y541280D01*
X139485Y541204D01*
X139226Y541012D01*
X139020Y540744D01*
X138968Y540475D01*
X139020Y540207D01*
X139226Y539862D01*
X137883Y539977D01*
Y541012D01*
G01X146663Y530094D02*
X147430D01*
Y529164D01*
X147200Y528854D01*
X146931Y528647D01*
X146548Y528544D01*
X146165Y528647D01*
X145896Y528854D01*
X145666Y529164D01*
X145513Y529526D01*
X145436Y529939D01*
Y530301D01*
X145513Y530611D01*
X145666Y530972D01*
X145896Y531282D01*
X146126Y531489D01*
X146433Y531644D01*
X146701D01*
X147008Y531541D01*
X147238Y531334D01*
G01X145666Y522865D02*
X145858Y522555D01*
X146088Y522348D01*
X146356Y522245D01*
X146663Y522348D01*
X146893Y522555D01*
X147123Y522865D01*
X147200Y523278D01*
Y525345D01*
G01X148200Y541343D02*
X146666D01*
Y544443D01*
X148200D01*
G01X147586Y542945D02*
X146666D01*
G01X148431Y552465D02*
X148201Y552620D01*
X147933Y552723D01*
X147626D01*
X147281Y552568D01*
X147013Y552310D01*
X146821Y552000D01*
X146668Y551483D01*
X146630Y551018D01*
X146706Y550553D01*
X146821Y550243D01*
X147051Y549933D01*
X147320Y549726D01*
X147588Y549623D01*
X147856D01*
X148125Y549726D01*
X148355Y549881D01*
X148546Y550088D01*
G01X146475Y553942D02*
X147433Y557042D01*
X148391Y553942D01*
G01X148046Y555027D02*
X146820D01*
G01X142650Y569542D02*
X196193D01*
G01X138000Y571026D02*
X134900D01*
Y571985D01*
X135055Y572291D01*
X135262Y572483D01*
X135675Y572560D01*
X136088Y572483D01*
X136347Y572253D01*
X136502Y571985D01*
Y571026D01*
G01Y571985D02*
X138000Y572560D01*
G01X137535Y574050D02*
X137793Y574280D01*
X137948Y574548D01*
X138000Y574893D01*
X137897Y575238D01*
X137690Y575506D01*
X137328Y575698D01*
X136915Y575736D01*
X136502Y575660D01*
X136243Y575468D01*
X136037Y575200D01*
X135985Y574931D01*
X136037Y574663D01*
X136243Y574318D01*
X134900Y574433D01*
Y575468D01*
G01X137535Y577150D02*
X137793Y577380D01*
X137948Y577648D01*
X138000Y577993D01*
X137897Y578338D01*
X137690Y578606D01*
X137328Y578798D01*
X136915Y578836D01*
X136502Y578760D01*
X136243Y578568D01*
X136037Y578300D01*
X135985Y578031D01*
X136037Y577763D01*
X136243Y577418D01*
X134900Y577533D01*
Y578568D01*
G01Y581093D02*
X135003Y580786D01*
X135262Y580556D01*
X135572Y580403D01*
X135985Y580288D01*
X136450Y580250D01*
X136915Y580288D01*
X137328Y580403D01*
X137638Y580556D01*
X137897Y580786D01*
X138000Y581093D01*
X137897Y581400D01*
X137638Y581630D01*
X137328Y581783D01*
X136915Y581898D01*
X136450Y581936D01*
X135985Y581898D01*
X135572Y581783D01*
X135262Y581630D01*
X135003Y581400D01*
X134900Y581093D01*
G01X146267Y571026D02*
X143167D01*
Y571985D01*
X143322Y572291D01*
X143529Y572483D01*
X143942Y572560D01*
X144355Y572483D01*
X144614Y572253D01*
X144769Y571985D01*
Y571026D01*
G01Y571985D02*
X146267Y572560D01*
G01X145802Y574050D02*
X146060Y574280D01*
X146215Y574548D01*
X146267Y574893D01*
X146164Y575238D01*
X145957Y575506D01*
X145595Y575698D01*
X145182Y575736D01*
X144769Y575660D01*
X144510Y575468D01*
X144304Y575200D01*
X144252Y574931D01*
X144304Y574663D01*
X144510Y574318D01*
X143167Y574433D01*
Y575468D01*
G01X145802Y577150D02*
X146060Y577380D01*
X146215Y577648D01*
X146267Y577993D01*
X146164Y578338D01*
X145957Y578606D01*
X145595Y578798D01*
X145182Y578836D01*
X144769Y578760D01*
X144510Y578568D01*
X144304Y578300D01*
X144252Y578031D01*
X144304Y577763D01*
X144510Y577418D01*
X143167Y577533D01*
Y578568D01*
G01X144975Y580365D02*
X144614Y580633D01*
X144407Y580863D01*
X144304Y581170D01*
X144407Y581438D01*
X144614Y581630D01*
X144924Y581783D01*
X145285Y581821D01*
X145595Y581783D01*
X145905Y581630D01*
X146164Y581400D01*
X146267Y581131D01*
X146164Y580825D01*
X145854Y580556D01*
X145389Y580403D01*
X144872Y580365D01*
X144200Y580441D01*
X143839Y580556D01*
X143477Y580748D01*
X143219Y581016D01*
X143167Y581285D01*
X143270Y581553D01*
X143529Y581745D01*
G01X142000Y571026D02*
X138900D01*
Y571985D01*
X139055Y572291D01*
X139262Y572483D01*
X139675Y572560D01*
X140088Y572483D01*
X140347Y572253D01*
X140502Y571985D01*
Y571026D01*
G01Y571985D02*
X142000Y572560D01*
G01X141535Y574050D02*
X141793Y574280D01*
X141948Y574548D01*
X142000Y574893D01*
X141897Y575238D01*
X141690Y575506D01*
X141328Y575698D01*
X140915Y575736D01*
X140502Y575660D01*
X140243Y575468D01*
X140037Y575200D01*
X139985Y574931D01*
X140037Y574663D01*
X140243Y574318D01*
X138900Y574433D01*
Y575468D01*
G01X142000Y578453D02*
X138900D01*
X141122Y577035D01*
Y578951D01*
G01X142000Y581093D02*
X141948Y581361D01*
X141793Y581668D01*
X141535Y581860D01*
X141173Y581936D01*
X140812Y581860D01*
X140502Y581630D01*
X140347Y581285D01*
Y580901D01*
X140243Y580671D01*
X139985Y580480D01*
X139623Y580403D01*
X139262Y580518D01*
X139003Y580786D01*
X138900Y581093D01*
X139003Y581400D01*
X139262Y581668D01*
X139623Y581783D01*
X139985Y581706D01*
X140243Y581515D01*
X140347Y581285D01*
Y580901D01*
X140502Y580556D01*
X140812Y580326D01*
X141173Y580250D01*
X141535Y580326D01*
X141793Y580518D01*
X141948Y580825D01*
X142000Y581093D01*
G01X150600Y571026D02*
X147500D01*
Y571985D01*
X147655Y572291D01*
X147862Y572483D01*
X148275Y572560D01*
X148688Y572483D01*
X148947Y572253D01*
X149102Y571985D01*
Y571026D01*
G01Y571985D02*
X150600Y572560D01*
G01X150135Y574050D02*
X150393Y574280D01*
X150548Y574548D01*
X150600Y574893D01*
X150497Y575238D01*
X150290Y575506D01*
X149928Y575698D01*
X149515Y575736D01*
X149102Y575660D01*
X148843Y575468D01*
X148637Y575200D01*
X148585Y574931D01*
X148637Y574663D01*
X148843Y574318D01*
X147500Y574433D01*
Y575468D01*
G01X150600Y578453D02*
X147500D01*
X149722Y577035D01*
Y578951D01*
G01X149308Y580365D02*
X148947Y580633D01*
X148740Y580863D01*
X148637Y581170D01*
X148740Y581438D01*
X148947Y581630D01*
X149257Y581783D01*
X149618Y581821D01*
X149928Y581783D01*
X150238Y581630D01*
X150497Y581400D01*
X150600Y581131D01*
X150497Y580825D01*
X150187Y580556D01*
X149722Y580403D01*
X149205Y580365D01*
X148533Y580441D01*
X148172Y580556D01*
X147810Y580748D01*
X147552Y581016D01*
X147500Y581285D01*
X147603Y581553D01*
X147862Y581745D01*
G01X147430Y592790D02*
X153640D01*
G01X147430Y609150D02*
Y592790D01*
G01X144480Y609150D02*
X147430D01*
G01X144480Y640690D02*
Y609150D01*
G01X134315Y661340D02*
X134622Y661082D01*
X134967Y660927D01*
X135273D01*
X135580Y661082D01*
X135810Y661340D01*
X135925Y661702D01*
X135848Y662064D01*
X135657Y662374D01*
X135312Y662580D01*
X134852Y662684D01*
X134583Y662890D01*
X134468Y663252D01*
X134545Y663614D01*
X134737Y663872D01*
X135005Y664027D01*
X135273D01*
X135542Y663924D01*
X135772Y663665D01*
G01X147009Y671322D02*
Y674422D01*
X147775D01*
X148082Y674267D01*
X148312Y674060D01*
X148504Y673750D01*
X148657Y673389D01*
X148695Y672872D01*
X148657Y672355D01*
X148504Y671994D01*
X148312Y671684D01*
X148082Y671477D01*
X147775Y671322D01*
X147009D01*
G01X145347Y677964D02*
Y664964D01*
G01X141924Y681469D02*
X141694Y681624D01*
X141426Y681727D01*
X141119D01*
X140774Y681572D01*
X140506Y681314D01*
X140314Y681004D01*
X140161Y680487D01*
X140123Y680022D01*
X140199Y679557D01*
X140314Y679247D01*
X140544Y678937D01*
X140813Y678730D01*
X141081Y678627D01*
X141349D01*
X141618Y678730D01*
X141848Y678885D01*
X142039Y679092D01*
G01X144104Y678627D02*
X144181Y679299D01*
X144296Y679867D01*
X144449Y680384D01*
X144641Y680952D01*
X144948Y681727D01*
X143414D01*
G01X147204Y678627D02*
X147281Y679299D01*
X147396Y679867D01*
X147549Y680384D01*
X147741Y680952D01*
X148048Y681727D01*
X146514D01*
G01X150381Y678627D02*
Y681727D01*
X149921Y681107D01*
G01Y678627D02*
X150841D01*
G01X140923Y691239D02*
X158323D01*
G01X140923Y683839D02*
Y691239D01*
G01X158323Y683839D02*
X140923D01*
G01X139359Y687650D02*
X136159D01*
G01X139359Y693850D02*
Y687650D01*
G01X136159D02*
Y693850D01*
G01X139359Y679650D02*
X136159D01*
G01X139359Y685850D02*
Y679650D01*
G01X136159Y685850D02*
X139359D01*
G01X136159Y679650D02*
Y685850D01*
G01X135207Y693887D02*
Y687687D01*
G01X143930Y692609D02*
Y693242D01*
G01X162434Y692609D02*
X143930D01*
G01X138544Y706655D02*
Y703347D01*
G01X136099Y708623D02*
X138544Y706655D01*
G01X136159Y693850D02*
X139359D01*
G01X139740Y717207D02*
X139433Y717259D01*
X139165Y717465D01*
X138935Y717775D01*
X138782Y718137D01*
X138705Y718550D01*
Y718964D01*
X138782Y719377D01*
X138935Y719739D01*
X139165Y720049D01*
X139433Y720255D01*
X139740Y720307D01*
X140047Y720255D01*
X140315Y720049D01*
X140545Y719739D01*
X140698Y719377D01*
X140775Y718964D01*
Y718550D01*
X140698Y718137D01*
X140545Y717775D01*
X140315Y717465D01*
X140047Y717259D01*
X139740Y717207D01*
G01X140047Y718034D02*
X140507Y717207D01*
G01X142112Y719790D02*
X142342Y720100D01*
X142610Y720255D01*
X142917Y720307D01*
X143300Y720204D01*
X143568Y719945D01*
X143645Y719635D01*
X143607Y719325D01*
X143453Y719067D01*
X142687Y718550D01*
X142342Y718189D01*
X142112Y717672D01*
X142035Y717207D01*
X143645D01*
G01X145212Y719790D02*
X145442Y720100D01*
X145710Y720255D01*
X146017Y720307D01*
X146400Y720204D01*
X146668Y719945D01*
X146745Y719635D01*
X146707Y719325D01*
X146553Y719067D01*
X145787Y718550D01*
X145442Y718189D01*
X145212Y717672D01*
X145135Y717207D01*
X146745D01*
G01X143930Y712842D02*
Y713475D01*
G01D02*
X162434D01*
G01X138544Y710591D02*
X136099Y708623D01*
G01X138544Y713899D02*
Y710591D01*
G01X143170Y726367D02*
Y728867D01*
X142850Y728367D01*
G01Y726367D02*
X143490D01*
G01X144120Y724342D02*
Y736842D01*
G01X156088Y724342D02*
X144120D01*
G01Y736942D02*
X156088D01*
G01X133859Y731350D02*
Y728150D01*
G01X135652Y737126D02*
Y740326D01*
G01X141852Y737126D02*
X135652D01*
G01X141852Y740326D02*
Y737126D01*
G01X138752Y737226D02*
Y740226D01*
G01X135753Y723573D02*
Y726773D01*
G01X141953Y723573D02*
X135753D01*
G01X141953Y726773D02*
Y723573D01*
G01X135753Y726773D02*
X141953D01*
G01X138853Y723673D02*
Y726673D01*
G01X135652Y729126D02*
Y732326D01*
G01X141852Y729126D02*
X135652D01*
G01X141852Y732326D02*
Y729126D01*
G01X135652Y732326D02*
X141852D01*
G01X138752Y729226D02*
Y732226D01*
G01X135652Y733126D02*
Y736326D01*
G01X141852Y733126D02*
X135652D01*
G01X141852Y736326D02*
Y733126D01*
G01X135652Y736326D02*
X141852D01*
G01X138752Y733226D02*
Y736226D01*
G01X133859Y726850D02*
Y723650D01*
G01X135652Y741126D02*
Y744326D01*
G01X141852Y741126D02*
X135652D01*
G01X141852Y744326D02*
Y741126D01*
G01X135652Y744326D02*
X141852D01*
G01X138752Y741226D02*
Y744226D01*
G01X135652Y740326D02*
X141852D01*
G01X134715Y748613D02*
X134485Y748768D01*
X134217Y748871D01*
X133910D01*
X133565Y748716D01*
X133297Y748458D01*
X133105Y748148D01*
X132952Y747631D01*
X132914Y747166D01*
X132990Y746701D01*
X133105Y746391D01*
X133335Y746081D01*
X133604Y745874D01*
X133872Y745771D01*
X134140D01*
X134409Y745874D01*
X134639Y746029D01*
X134830Y746236D01*
G01X136895Y745771D02*
X136972Y746443D01*
X137087Y747011D01*
X137240Y747528D01*
X137432Y748096D01*
X137739Y748871D01*
X136205D01*
G01X139995Y745771D02*
X140072Y746443D01*
X140187Y747011D01*
X140340Y747528D01*
X140532Y748096D01*
X140839Y748871D01*
X139305D01*
G01X143095Y745771D02*
X143172Y746443D01*
X143287Y747011D01*
X143440Y747528D01*
X143632Y748096D01*
X143939Y748871D01*
X142405D01*
G01X134715Y752689D02*
X134485Y752844D01*
X134217Y752947D01*
X133910D01*
X133565Y752792D01*
X133297Y752534D01*
X133105Y752224D01*
X132952Y751707D01*
X132914Y751242D01*
X132990Y750777D01*
X133105Y750467D01*
X133335Y750157D01*
X133604Y749950D01*
X133872Y749847D01*
X134140D01*
X134409Y749950D01*
X134639Y750105D01*
X134830Y750312D01*
G01X136895Y749847D02*
X136972Y750519D01*
X137087Y751087D01*
X137240Y751604D01*
X137432Y752172D01*
X137739Y752947D01*
X136205D01*
G01X139344Y751139D02*
X139612Y751500D01*
X139842Y751707D01*
X140149Y751810D01*
X140417Y751707D01*
X140609Y751500D01*
X140762Y751190D01*
X140800Y750829D01*
X140762Y750519D01*
X140609Y750209D01*
X140379Y749950D01*
X140110Y749847D01*
X139804Y749950D01*
X139535Y750260D01*
X139382Y750725D01*
X139344Y751242D01*
X139420Y751914D01*
X139535Y752275D01*
X139727Y752637D01*
X139995Y752895D01*
X140264Y752947D01*
X140532Y752844D01*
X140724Y752585D01*
G01X143095Y749847D02*
X143172Y750519D01*
X143287Y751087D01*
X143440Y751604D01*
X143632Y752172D01*
X143939Y752947D01*
X142405D01*
G01X134715Y756689D02*
X134485Y756844D01*
X134217Y756947D01*
X133910D01*
X133565Y756792D01*
X133297Y756534D01*
X133105Y756224D01*
X132952Y755707D01*
X132914Y755242D01*
X132990Y754777D01*
X133105Y754467D01*
X133335Y754157D01*
X133604Y753950D01*
X133872Y753847D01*
X134140D01*
X134409Y753950D01*
X134639Y754105D01*
X134830Y754312D01*
G01X136895Y753847D02*
X136972Y754519D01*
X137087Y755087D01*
X137240Y755604D01*
X137432Y756172D01*
X137739Y756947D01*
X136205D01*
G01X139344Y755139D02*
X139612Y755500D01*
X139842Y755707D01*
X140149Y755810D01*
X140417Y755707D01*
X140609Y755500D01*
X140762Y755190D01*
X140800Y754829D01*
X140762Y754519D01*
X140609Y754209D01*
X140379Y753950D01*
X140110Y753847D01*
X139804Y753950D01*
X139535Y754260D01*
X139382Y754725D01*
X139344Y755242D01*
X139420Y755914D01*
X139535Y756275D01*
X139727Y756637D01*
X139995Y756895D01*
X140264Y756947D01*
X140532Y756844D01*
X140724Y756585D01*
G01X143172Y753847D02*
X143440Y753899D01*
X143747Y754054D01*
X143939Y754312D01*
X144015Y754674D01*
X143939Y755035D01*
X143709Y755345D01*
X143364Y755500D01*
X142980D01*
X142750Y755604D01*
X142559Y755862D01*
X142482Y756224D01*
X142597Y756585D01*
X142865Y756844D01*
X143172Y756947D01*
X143479Y756844D01*
X143747Y756585D01*
X143862Y756224D01*
X143785Y755862D01*
X143594Y755604D01*
X143364Y755500D01*
X142980D01*
X142635Y755345D01*
X142405Y755035D01*
X142329Y754674D01*
X142405Y754312D01*
X142597Y754054D01*
X142904Y753899D01*
X143172Y753847D01*
G01X134715Y764689D02*
X134485Y764844D01*
X134217Y764947D01*
X133910D01*
X133565Y764792D01*
X133297Y764534D01*
X133105Y764224D01*
X132952Y763707D01*
X132914Y763242D01*
X132990Y762777D01*
X133105Y762467D01*
X133335Y762157D01*
X133604Y761950D01*
X133872Y761847D01*
X134140D01*
X134409Y761950D01*
X134639Y762105D01*
X134830Y762312D01*
G01X136895Y761847D02*
X136972Y762519D01*
X137087Y763087D01*
X137240Y763604D01*
X137432Y764172D01*
X137739Y764947D01*
X136205D01*
G01X139344Y763139D02*
X139612Y763500D01*
X139842Y763707D01*
X140149Y763810D01*
X140417Y763707D01*
X140609Y763500D01*
X140762Y763190D01*
X140800Y762829D01*
X140762Y762519D01*
X140609Y762209D01*
X140379Y761950D01*
X140110Y761847D01*
X139804Y761950D01*
X139535Y762260D01*
X139382Y762725D01*
X139344Y763242D01*
X139420Y763914D01*
X139535Y764275D01*
X139727Y764637D01*
X139995Y764895D01*
X140264Y764947D01*
X140532Y764844D01*
X140724Y764585D01*
G01X142520Y762209D02*
X142789Y761950D01*
X143095Y761847D01*
X143402Y761950D01*
X143670Y762260D01*
X143862Y762725D01*
X143939Y763190D01*
Y763759D01*
X143862Y764224D01*
X143670Y764637D01*
X143440Y764844D01*
X143172Y764947D01*
X142865Y764844D01*
X142635Y764637D01*
X142482Y764327D01*
X142405Y763914D01*
X142482Y763552D01*
X142674Y763190D01*
X142904Y762984D01*
X143172Y762932D01*
X143479Y763035D01*
X143709Y763294D01*
X143939Y763759D01*
G01X134715Y760689D02*
X134485Y760844D01*
X134217Y760947D01*
X133910D01*
X133565Y760792D01*
X133297Y760534D01*
X133105Y760224D01*
X132952Y759707D01*
X132914Y759242D01*
X132990Y758777D01*
X133105Y758467D01*
X133335Y758157D01*
X133604Y757950D01*
X133872Y757847D01*
X134140D01*
X134409Y757950D01*
X134639Y758105D01*
X134830Y758312D01*
G01X136895Y757847D02*
X136972Y758519D01*
X137087Y759087D01*
X137240Y759604D01*
X137432Y760172D01*
X137739Y760947D01*
X136205D01*
G01X139995Y757847D02*
X140072Y758519D01*
X140187Y759087D01*
X140340Y759604D01*
X140532Y760172D01*
X140839Y760947D01*
X139305D01*
G01X143172D02*
X142865Y760844D01*
X142635Y760585D01*
X142482Y760275D01*
X142367Y759862D01*
X142329Y759397D01*
X142367Y758932D01*
X142482Y758519D01*
X142635Y758209D01*
X142865Y757950D01*
X143172Y757847D01*
X143479Y757950D01*
X143709Y758209D01*
X143862Y758519D01*
X143977Y758932D01*
X144015Y759397D01*
X143977Y759862D01*
X143862Y760275D01*
X143709Y760585D01*
X143479Y760844D01*
X143172Y760947D01*
G01X148510Y20670D02*
Y3840D01*
G01X156581Y12925D02*
Y19125D01*
G01X159781D02*
Y12925D01*
G01D02*
X156581D01*
G01X168648Y5717D02*
X161248D01*
G01D02*
Y23117D01*
G01X155462Y13751D02*
Y10551D01*
G01X149262Y13751D02*
X155462D01*
G01Y10551D02*
X149262D01*
G01D02*
Y13751D01*
G01X160050Y20670D02*
X148510D01*
G01X160050Y27790D02*
Y20670D01*
G01X195150Y27790D02*
X160050D01*
G01X154069Y29648D02*
Y32148D01*
X153749Y31648D01*
G01Y29648D02*
X154389D01*
G01X156269Y32148D02*
X156056Y32065D01*
X155896Y31856D01*
X155789Y31606D01*
X155709Y31273D01*
X155682Y30898D01*
X155709Y30523D01*
X155789Y30190D01*
X155896Y29940D01*
X156056Y29731D01*
X156269Y29648D01*
X156482Y29731D01*
X156642Y29940D01*
X156749Y30190D01*
X156829Y30523D01*
X156856Y30898D01*
X156829Y31273D01*
X156749Y31606D01*
X156642Y31856D01*
X156482Y32065D01*
X156269Y32148D01*
G01X156581Y19125D02*
X159781D01*
G01X159681Y16025D02*
X156681D01*
G01X149188Y19318D02*
X155388D01*
G01D02*
Y16118D01*
G01D02*
X149188D01*
G01D02*
Y19318D01*
G01X152288Y16218D02*
Y19218D01*
G01X161248Y23117D02*
X168648D01*
G01X161248Y14417D02*
X168648D01*
G01X152992Y22691D02*
Y28891D01*
G01D02*
X156192D01*
G01D02*
Y22691D01*
G01D02*
X152992D01*
G01X152192Y28891D02*
Y22691D01*
G01D02*
X148992D01*
G01D02*
Y28891D01*
G01D02*
X152192D01*
G01X158377Y32250D02*
Y34750D01*
X158057Y34250D01*
G01Y32250D02*
X158697D01*
G01X160577D02*
Y34750D01*
X160257Y34250D01*
G01Y32250D02*
X160897D01*
G01X158923Y44398D02*
Y46898D01*
X158603Y46398D01*
G01Y44398D02*
X159243D01*
G01X160536Y44773D02*
X160696Y44565D01*
X160883Y44440D01*
X161123Y44398D01*
X161363Y44481D01*
X161550Y44648D01*
X161683Y44940D01*
X161710Y45273D01*
X161656Y45606D01*
X161523Y45815D01*
X161336Y45981D01*
X161150Y46023D01*
X160963Y45981D01*
X160723Y45815D01*
X160803Y46898D01*
X161523D01*
G01X156032Y46657D02*
Y44757D01*
G01Y36257D02*
Y34457D01*
G01D02*
X154132D01*
G01X162333Y39000D02*
X165533D01*
G01X162333Y32800D02*
Y39000D01*
G01X162433Y35900D02*
X165433D01*
G01X165533Y32800D02*
X162333D01*
G01X153450Y49503D02*
Y52003D01*
X153130Y51503D01*
G01Y49503D02*
X153770D01*
G01X155143Y50545D02*
X155330Y50836D01*
X155490Y51003D01*
X155703Y51086D01*
X155890Y51003D01*
X156023Y50836D01*
X156130Y50586D01*
X156157Y50295D01*
X156130Y50045D01*
X156023Y49795D01*
X155863Y49586D01*
X155677Y49503D01*
X155463Y49586D01*
X155277Y49836D01*
X155170Y50211D01*
X155143Y50628D01*
X155197Y51170D01*
X155277Y51461D01*
X155410Y51753D01*
X155597Y51961D01*
X155783Y52003D01*
X155970Y51920D01*
X156103Y51711D01*
G01X154232Y46657D02*
X156032D01*
G01X157512Y48668D02*
Y53268D01*
G01X162612D02*
Y48668D01*
G01X157512Y53268D02*
X167712D01*
G01Y48668D02*
X157512D01*
G01X151614Y57506D02*
X157814D01*
G01D02*
Y54306D01*
G01D02*
X151614D01*
G01D02*
Y57506D01*
G01X150757Y59105D02*
Y52905D01*
G01X159173Y73457D02*
Y76557D01*
X160132D01*
X160438Y76402D01*
X160630Y76195D01*
X160707Y75782D01*
X160630Y75369D01*
X160400Y75110D01*
X160132Y74955D01*
X159173D01*
G01X160132D02*
X160707Y73457D01*
G01X162312Y76040D02*
X162542Y76350D01*
X162810Y76505D01*
X163117Y76557D01*
X163500Y76454D01*
X163768Y76195D01*
X163845Y75885D01*
X163807Y75575D01*
X163653Y75317D01*
X162887Y74800D01*
X162542Y74439D01*
X162312Y73922D01*
X162235Y73457D01*
X163845D01*
G01X166140D02*
Y76557D01*
X165680Y75937D01*
G01Y73457D02*
X166600D01*
G01X168512Y76040D02*
X168742Y76350D01*
X169010Y76505D01*
X169317Y76557D01*
X169700Y76454D01*
X169968Y76195D01*
X170045Y75885D01*
X170007Y75575D01*
X169853Y75317D01*
X169087Y74800D01*
X168742Y74439D01*
X168512Y73922D01*
X168435Y73457D01*
X170045D01*
G01X154078Y76463D02*
Y73263D01*
G01X162213Y62183D02*
X159113D01*
Y63103D01*
X159268Y63410D01*
X159630Y63640D01*
X160043Y63717D01*
X160456Y63640D01*
X160766Y63448D01*
X160921Y63103D01*
Y62183D01*
G01X161593Y65283D02*
X161903Y65475D01*
X162110Y65705D01*
X162213Y65973D01*
X162110Y66280D01*
X161903Y66510D01*
X161593Y66740D01*
X161180Y66817D01*
X159113D01*
G01X161851Y68498D02*
X162110Y68767D01*
X162213Y69073D01*
X162110Y69380D01*
X161800Y69648D01*
X161335Y69840D01*
X160870Y69917D01*
X160301D01*
X159836Y69840D01*
X159423Y69648D01*
X159216Y69418D01*
X159113Y69150D01*
X159216Y68843D01*
X159423Y68613D01*
X159733Y68460D01*
X160146Y68383D01*
X160508Y68460D01*
X160870Y68652D01*
X161076Y68882D01*
X161128Y69150D01*
X161025Y69457D01*
X160766Y69687D01*
X160301Y69917D01*
G01X156600Y75400D02*
Y77900D01*
X156280Y77400D01*
G01Y75400D02*
X156920D01*
G01X159439Y124070D02*
X159669Y124380D01*
X159937Y124535D01*
X160244Y124587D01*
X160627Y124484D01*
X160895Y124225D01*
X160972Y123915D01*
X160934Y123605D01*
X160780Y123347D01*
X160014Y122830D01*
X159669Y122469D01*
X159439Y121952D01*
X159362Y121487D01*
X160972D01*
G01X157284Y112204D02*
Y181496D01*
G01X158665Y112204D02*
X157284D01*
G01X158840Y129120D02*
Y196270D01*
G01X235220Y129120D02*
X158840D01*
G01X161233Y157195D02*
X161003Y157350D01*
X160735Y157453D01*
X160428D01*
X160083Y157298D01*
X159815Y157040D01*
X159623Y156730D01*
X159470Y156213D01*
X159432Y155748D01*
X159508Y155283D01*
X159623Y154973D01*
X159853Y154663D01*
X160122Y154456D01*
X160390Y154353D01*
X160658D01*
X160927Y154456D01*
X161157Y154611D01*
X161348Y154818D01*
G01X162762Y155645D02*
X163030Y156006D01*
X163260Y156213D01*
X163567Y156316D01*
X163835Y156213D01*
X164027Y156006D01*
X164180Y155696D01*
X164218Y155335D01*
X164180Y155025D01*
X164027Y154715D01*
X163797Y154456D01*
X163528Y154353D01*
X163222Y154456D01*
X162953Y154766D01*
X162800Y155231D01*
X162762Y155748D01*
X162838Y156420D01*
X162953Y156781D01*
X163145Y157143D01*
X163413Y157401D01*
X163682Y157453D01*
X163950Y157350D01*
X164142Y157091D01*
G01X165862Y156936D02*
X166092Y157246D01*
X166360Y157401D01*
X166667Y157453D01*
X167050Y157350D01*
X167318Y157091D01*
X167395Y156781D01*
X167357Y156471D01*
X167203Y156213D01*
X166437Y155696D01*
X166092Y155335D01*
X165862Y154818D01*
X165785Y154353D01*
X167395D01*
G01X169690D02*
Y157453D01*
X169230Y156833D01*
G01Y154353D02*
X170150D01*
G01X158840Y196270D02*
X166700D01*
G01X163790Y217200D02*
Y202930D01*
G01X159694Y204824D02*
X161916D01*
X162381Y204977D01*
X162691Y205284D01*
X162794Y205667D01*
X162691Y206050D01*
X162381Y206357D01*
X161916Y206510D01*
X159694D01*
G01X162794Y208767D02*
X159694D01*
X160314Y208307D01*
G01X162794D02*
Y209227D01*
G01X162174Y211024D02*
X162536Y211254D01*
X162742Y211560D01*
X162794Y211905D01*
X162742Y212212D01*
X162484Y212519D01*
X162174Y212710D01*
X161864Y212749D01*
X161502Y212672D01*
X161244Y212404D01*
X161141Y212135D01*
Y211790D01*
G01Y212135D02*
X160986Y212365D01*
X160727Y212557D01*
X160417Y212634D01*
X160107Y212557D01*
X159849Y212365D01*
X159694Y212020D01*
X159746Y211675D01*
X159952Y211330D01*
G01X160211Y214239D02*
X159901Y214469D01*
X159746Y214737D01*
X159694Y215044D01*
X159797Y215427D01*
X160056Y215695D01*
X160366Y215772D01*
X160676Y215734D01*
X160934Y215580D01*
X161451Y214814D01*
X161812Y214469D01*
X162329Y214239D01*
X162794Y214162D01*
Y215772D01*
G01X307210Y365434D02*
X149488D01*
Y231412D01*
X307210D01*
Y289683D01*
G01X156462Y248589D02*
X156569Y248714D01*
X156649Y248923D01*
X156702Y249214D01*
X156649Y249464D01*
X156542Y249631D01*
X156356Y249756D01*
X155636D01*
Y247256D01*
X156516D01*
X156702Y247423D01*
X156809Y247673D01*
X156862Y247964D01*
X156809Y248256D01*
X156649Y248506D01*
X156462Y248589D01*
X155636D01*
G01X157836Y247256D02*
Y249756D01*
X159062Y247256D01*
Y249756D01*
G01X152462Y250589D02*
X152569Y250714D01*
X152649Y250923D01*
X152702Y251214D01*
X152649Y251464D01*
X152542Y251631D01*
X152356Y251756D01*
X151636D01*
Y249256D01*
X152516D01*
X152702Y249423D01*
X152809Y249673D01*
X152862Y249964D01*
X152809Y250256D01*
X152649Y250506D01*
X152462Y250589D01*
X151636D01*
G01X153756Y249256D02*
Y251756D01*
X154449Y249673D01*
X155142Y251756D01*
Y249256D01*
G01X152462Y246589D02*
X152569Y246714D01*
X152649Y246923D01*
X152702Y247214D01*
X152649Y247464D01*
X152542Y247631D01*
X152356Y247756D01*
X151636D01*
Y245256D01*
X152516D01*
X152702Y245423D01*
X152809Y245673D01*
X152862Y245964D01*
X152809Y246256D01*
X152649Y246506D01*
X152462Y246589D01*
X151636D01*
G01X153916Y245256D02*
Y247756D01*
X154556D01*
X154769Y247631D01*
X154929Y247339D01*
X154982Y247006D01*
X154929Y246673D01*
X154796Y246423D01*
X154556Y246298D01*
X153916D01*
G01X295399Y353623D02*
X161299D01*
Y243223D01*
X295399D01*
Y353623D01*
G01X152462Y255089D02*
X152569Y255214D01*
X152649Y255423D01*
X152702Y255714D01*
X152649Y255964D01*
X152542Y256131D01*
X152356Y256256D01*
X151636D01*
Y253756D01*
X152516D01*
X152702Y253923D01*
X152809Y254173D01*
X152862Y254464D01*
X152809Y254756D01*
X152649Y255006D01*
X152462Y255089D01*
X151636D01*
G01X153862Y253756D02*
Y256256D01*
G01X154876D02*
X153862Y254714D01*
G01X155036Y253756D02*
X154316Y255423D01*
G01X156462Y253089D02*
X156569Y253214D01*
X156649Y253423D01*
X156702Y253714D01*
X156649Y253964D01*
X156542Y254131D01*
X156356Y254256D01*
X155636D01*
Y251756D01*
X156516D01*
X156702Y251923D01*
X156809Y252173D01*
X156862Y252464D01*
X156809Y252756D01*
X156649Y253006D01*
X156462Y253089D01*
X155636D01*
G01X157916Y254256D02*
Y251756D01*
X158982D01*
G01X156462Y265089D02*
X156569Y265214D01*
X156649Y265423D01*
X156702Y265714D01*
X156649Y265964D01*
X156542Y266131D01*
X156356Y266256D01*
X155636D01*
Y263756D01*
X156516D01*
X156702Y263923D01*
X156809Y264173D01*
X156862Y264464D01*
X156809Y264756D01*
X156649Y265006D01*
X156462Y265089D01*
X155636D01*
G01X158982Y263756D02*
X157916D01*
Y266256D01*
X158982D01*
G01X158556Y265048D02*
X157916D01*
G01X156462Y261589D02*
X156569Y261714D01*
X156649Y261923D01*
X156702Y262214D01*
X156649Y262464D01*
X156542Y262631D01*
X156356Y262756D01*
X155636D01*
Y260256D01*
X156516D01*
X156702Y260423D01*
X156809Y260673D01*
X156862Y260964D01*
X156809Y261256D01*
X156649Y261506D01*
X156462Y261589D01*
X155636D01*
G01X158609Y261506D02*
X159142D01*
Y260756D01*
X158982Y260506D01*
X158796Y260339D01*
X158529Y260256D01*
X158262Y260339D01*
X158076Y260506D01*
X157916Y260756D01*
X157809Y261048D01*
X157756Y261381D01*
Y261673D01*
X157809Y261923D01*
X157916Y262214D01*
X158076Y262464D01*
X158236Y262631D01*
X158449Y262756D01*
X158636D01*
X158849Y262673D01*
X159009Y262506D01*
G01X156462Y257089D02*
X156569Y257214D01*
X156649Y257423D01*
X156702Y257714D01*
X156649Y257964D01*
X156542Y258131D01*
X156356Y258256D01*
X155636D01*
Y255756D01*
X156516D01*
X156702Y255923D01*
X156809Y256173D01*
X156862Y256464D01*
X156809Y256756D01*
X156649Y257006D01*
X156462Y257089D01*
X155636D01*
G01X157916Y256256D02*
X158049Y256006D01*
X158209Y255839D01*
X158396Y255756D01*
X158609Y255839D01*
X158769Y256006D01*
X158929Y256256D01*
X158982Y256589D01*
Y258256D01*
G01X152462Y266589D02*
X152569Y266714D01*
X152649Y266923D01*
X152702Y267214D01*
X152649Y267464D01*
X152542Y267631D01*
X152356Y267756D01*
X151636D01*
Y265256D01*
X152516D01*
X152702Y265423D01*
X152809Y265673D01*
X152862Y265964D01*
X152809Y266256D01*
X152649Y266506D01*
X152462Y266589D01*
X151636D01*
G01X153862Y265256D02*
Y267756D01*
X154396D01*
X154609Y267631D01*
X154769Y267464D01*
X154902Y267214D01*
X155009Y266923D01*
X155036Y266506D01*
X155009Y266089D01*
X154902Y265798D01*
X154769Y265548D01*
X154609Y265381D01*
X154396Y265256D01*
X153862D01*
G01X152462Y263089D02*
X152569Y263214D01*
X152649Y263423D01*
X152702Y263714D01*
X152649Y263964D01*
X152542Y264131D01*
X152356Y264256D01*
X151636D01*
Y261756D01*
X152516D01*
X152702Y261923D01*
X152809Y262173D01*
X152862Y262464D01*
X152809Y262756D01*
X152649Y263006D01*
X152462Y263089D01*
X151636D01*
G01X153942Y261756D02*
Y264256D01*
X154956D01*
G01X154582Y263048D02*
X153942D01*
G01X152462Y259589D02*
X152569Y259714D01*
X152649Y259923D01*
X152702Y260214D01*
X152649Y260464D01*
X152542Y260631D01*
X152356Y260756D01*
X151636D01*
Y258256D01*
X152516D01*
X152702Y258423D01*
X152809Y258673D01*
X152862Y258964D01*
X152809Y259256D01*
X152649Y259506D01*
X152462Y259589D01*
X151636D01*
G01X153889Y258256D02*
Y260756D01*
G01X155009D02*
Y258256D01*
G01Y259506D02*
X153889D01*
G01X155582Y278756D02*
X156249Y281256D01*
X156916Y278756D01*
G01X156676Y279631D02*
X155822D01*
G01X157862Y281256D02*
Y279464D01*
X157969Y279089D01*
X158182Y278839D01*
X158449Y278756D01*
X158716Y278839D01*
X158929Y279089D01*
X159036Y279464D01*
Y281256D01*
G01X155582Y275256D02*
X156249Y277756D01*
X156916Y275256D01*
G01X156676Y276131D02*
X155822D01*
G01X157649Y277756D02*
X158022Y275256D01*
X158449Y277756D01*
X158876Y275256D01*
X159249Y277756D01*
G01X156462Y272589D02*
X156569Y272714D01*
X156649Y272923D01*
X156702Y273214D01*
X156649Y273464D01*
X156542Y273631D01*
X156356Y273756D01*
X155636D01*
Y271256D01*
X156516D01*
X156702Y271423D01*
X156809Y271673D01*
X156862Y271964D01*
X156809Y272256D01*
X156649Y272506D01*
X156462Y272589D01*
X155636D01*
G01X157782Y271256D02*
X158449Y273756D01*
X159116Y271256D01*
G01X158876Y272131D02*
X158022D01*
G01X156462Y268589D02*
X156569Y268714D01*
X156649Y268923D01*
X156702Y269214D01*
X156649Y269464D01*
X156542Y269631D01*
X156356Y269756D01*
X155636D01*
Y267256D01*
X156516D01*
X156702Y267423D01*
X156809Y267673D01*
X156862Y267964D01*
X156809Y268256D01*
X156649Y268506D01*
X156462Y268589D01*
X155636D01*
G01X159036Y269548D02*
X158876Y269673D01*
X158689Y269756D01*
X158476D01*
X158236Y269631D01*
X158049Y269423D01*
X157916Y269173D01*
X157809Y268756D01*
X157782Y268381D01*
X157836Y268006D01*
X157916Y267756D01*
X158076Y267506D01*
X158262Y267339D01*
X158449Y267256D01*
X158636D01*
X158822Y267339D01*
X158982Y267464D01*
X159116Y267631D01*
G01X151582Y276756D02*
X152249Y279256D01*
X152916Y276756D01*
G01X152676Y277631D02*
X151822D01*
G01X153782Y279256D02*
X154449Y276756D01*
X155116Y279256D01*
G01X151582Y272756D02*
X152249Y275256D01*
X152916Y272756D01*
G01X152676Y273631D02*
X151822D01*
G01X154449Y272756D02*
Y273881D01*
X153916Y275256D01*
G01X154982D02*
X154449Y273881D01*
G01X152462Y270589D02*
X152569Y270714D01*
X152649Y270923D01*
X152702Y271214D01*
X152649Y271464D01*
X152542Y271631D01*
X152356Y271756D01*
X151636D01*
Y269256D01*
X152516D01*
X152702Y269423D01*
X152809Y269673D01*
X152862Y269964D01*
X152809Y270256D01*
X152649Y270506D01*
X152462Y270589D01*
X151636D01*
G01X154662D02*
X154769Y270714D01*
X154849Y270923D01*
X154902Y271214D01*
X154849Y271464D01*
X154742Y271631D01*
X154556Y271756D01*
X153836D01*
Y269256D01*
X154716D01*
X154902Y269423D01*
X155009Y269673D01*
X155062Y269964D01*
X155009Y270256D01*
X154849Y270506D01*
X154662Y270589D01*
X153836D01*
G01X155582Y282256D02*
X156249Y284756D01*
X156916Y282256D01*
G01X156676Y283131D02*
X155822D01*
G01X157916Y282256D02*
Y284756D01*
X158582D01*
X158796Y284631D01*
X158929Y284464D01*
X158982Y284131D01*
X158929Y283798D01*
X158769Y283589D01*
X158582Y283464D01*
X157916D01*
G01X158582D02*
X158982Y282256D01*
G01X151582Y280256D02*
X152249Y282756D01*
X152916Y280256D01*
G01X152676Y281131D02*
X151822D01*
G01X154449Y282756D02*
Y280256D01*
G01X153836Y282756D02*
X155062D01*
G01X155582Y298256D02*
X156249Y300756D01*
X156916Y298256D01*
G01X156676Y299131D02*
X155822D01*
G01X158609Y299506D02*
X159142D01*
Y298756D01*
X158982Y298506D01*
X158796Y298339D01*
X158529Y298256D01*
X158262Y298339D01*
X158076Y298506D01*
X157916Y298756D01*
X157809Y299048D01*
X157756Y299381D01*
Y299673D01*
X157809Y299923D01*
X157916Y300214D01*
X158076Y300464D01*
X158236Y300631D01*
X158449Y300756D01*
X158636D01*
X158849Y300673D01*
X159009Y300506D01*
G01X155582Y293756D02*
X156249Y296256D01*
X156916Y293756D01*
G01X156676Y294631D02*
X155822D01*
G01X157916Y294256D02*
X158049Y294006D01*
X158209Y293839D01*
X158396Y293756D01*
X158609Y293839D01*
X158769Y294006D01*
X158929Y294256D01*
X158982Y294589D01*
Y296256D01*
G01X155582Y290256D02*
X156249Y292756D01*
X156916Y290256D01*
G01X156676Y291131D02*
X155822D01*
G01X157916Y292756D02*
Y290256D01*
X158982D01*
G01X155582Y285756D02*
X156249Y288256D01*
X156916Y285756D01*
G01X156676Y286631D02*
X155822D01*
G01X157836Y285756D02*
Y288256D01*
X159062Y285756D01*
Y288256D01*
G01X151582Y295756D02*
X152249Y298256D01*
X152916Y295756D01*
G01X152676Y296631D02*
X151822D01*
G01X153889Y295756D02*
Y298256D01*
G01X155009D02*
Y295756D01*
G01Y297006D02*
X153889D01*
G01X151582Y292256D02*
X152249Y294756D01*
X152916Y292256D01*
G01X152676Y293131D02*
X151822D01*
G01X153862Y292256D02*
Y294756D01*
G01X154876D02*
X153862Y293214D01*
G01X155036Y292256D02*
X154316Y293923D01*
G01X151582Y287756D02*
X152249Y290256D01*
X152916Y287756D01*
G01X152676Y288631D02*
X151822D01*
G01X153756Y287756D02*
Y290256D01*
X154449Y288173D01*
X155142Y290256D01*
Y287756D01*
G01X151582Y283756D02*
X152249Y286256D01*
X152916Y283756D01*
G01X152676Y284631D02*
X151822D01*
G01X153916Y283756D02*
Y286256D01*
X154556D01*
X154769Y286131D01*
X154929Y285839D01*
X154982Y285506D01*
X154929Y285173D01*
X154796Y284923D01*
X154556Y284798D01*
X153916D01*
G01X155582Y311756D02*
X156249Y314256D01*
X156916Y311756D01*
G01X156676Y312631D02*
X155822D01*
G01X157782Y311756D02*
X158449Y314256D01*
X159116Y311756D01*
G01X158876Y312631D02*
X158022D01*
G01X152549Y312756D02*
Y313881D01*
X152016Y315256D01*
G01X153082D02*
X152549Y313881D01*
G01X155582Y302256D02*
X156249Y304756D01*
X156916Y302256D01*
G01X156676Y303131D02*
X155822D01*
G01X158982Y302256D02*
X157916D01*
Y304756D01*
X158982D01*
G01X158556Y303548D02*
X157916D01*
G01X151582Y304256D02*
X152249Y306756D01*
X152916Y304256D01*
G01X152676Y305131D02*
X151822D01*
G01X153862Y304256D02*
Y306756D01*
X154396D01*
X154609Y306631D01*
X154769Y306464D01*
X154902Y306214D01*
X155009Y305923D01*
X155036Y305506D01*
X155009Y305089D01*
X154902Y304798D01*
X154769Y304548D01*
X154609Y304381D01*
X154396Y304256D01*
X153862D01*
G01X151582Y299756D02*
X152249Y302256D01*
X152916Y299756D01*
G01X152676Y300631D02*
X151822D01*
G01X153942Y299756D02*
Y302256D01*
X154956D01*
G01X154582Y301048D02*
X153942D01*
G01X155582Y306756D02*
X156249Y309256D01*
X156916Y306756D01*
G01X156676Y307631D02*
X155822D01*
G01X159036Y309048D02*
X158876Y309173D01*
X158689Y309256D01*
X158476D01*
X158236Y309131D01*
X158049Y308923D01*
X157916Y308673D01*
X157809Y308256D01*
X157782Y307881D01*
X157836Y307506D01*
X157916Y307256D01*
X158076Y307006D01*
X158262Y306839D01*
X158449Y306756D01*
X158636D01*
X158822Y306839D01*
X158982Y306964D01*
X159116Y307131D01*
G01X151582Y308756D02*
X152249Y311256D01*
X152916Y308756D01*
G01X152676Y309631D02*
X151822D01*
G01X154662Y310089D02*
X154769Y310214D01*
X154849Y310423D01*
X154902Y310714D01*
X154849Y310964D01*
X154742Y311131D01*
X154556Y311256D01*
X153836D01*
Y308756D01*
X154716D01*
X154902Y308923D01*
X155009Y309173D01*
X155062Y309464D01*
X155009Y309756D01*
X154849Y310006D01*
X154662Y310089D01*
X153836D01*
G01X155936Y327756D02*
Y330256D01*
X157162Y327756D01*
Y330256D01*
G01X156016Y323256D02*
Y325756D01*
X156682D01*
X156896Y325631D01*
X157029Y325464D01*
X157082Y325131D01*
X157029Y324798D01*
X156869Y324589D01*
X156682Y324464D01*
X156016D01*
G01X156682D02*
X157082Y323256D01*
G01X155962Y321756D02*
Y319964D01*
X156069Y319589D01*
X156282Y319339D01*
X156549Y319256D01*
X156816Y319339D01*
X157029Y319589D01*
X157136Y319964D01*
Y321756D01*
G01X155749Y317756D02*
X156122Y315256D01*
X156549Y317756D01*
X156976Y315256D01*
X157349Y317756D01*
G01X151882Y319256D02*
X152549Y316756D01*
X153216Y319256D01*
G01X152549Y323756D02*
Y321256D01*
G01X151936Y323756D02*
X153162D01*
G01X152016Y325256D02*
Y327756D01*
X152656D01*
X152869Y327631D01*
X153029Y327339D01*
X153082Y327006D01*
X153029Y326673D01*
X152896Y326423D01*
X152656Y326298D01*
X152016D01*
G01X151856Y329256D02*
Y331756D01*
X152549Y329673D01*
X153242Y331756D01*
Y329256D01*
G01X157082Y343256D02*
X156016D01*
Y345756D01*
X157082D01*
G01X156656Y344548D02*
X156016D01*
G01X156709Y340006D02*
X157242D01*
Y339256D01*
X157082Y339006D01*
X156896Y338839D01*
X156629Y338756D01*
X156362Y338839D01*
X156176Y339006D01*
X156016Y339256D01*
X155909Y339548D01*
X155856Y339881D01*
Y340173D01*
X155909Y340423D01*
X156016Y340714D01*
X156176Y340964D01*
X156336Y341131D01*
X156549Y341256D01*
X156736D01*
X156949Y341173D01*
X157109Y341006D01*
G01X156016Y335756D02*
X156149Y335506D01*
X156309Y335339D01*
X156496Y335256D01*
X156709Y335339D01*
X156869Y335506D01*
X157029Y335756D01*
X157082Y336089D01*
Y337756D01*
G01X156016Y334256D02*
Y331756D01*
X157082D01*
G01X151962Y333756D02*
Y336256D01*
G01X152976D02*
X151962Y334714D01*
G01X153136Y333756D02*
X152416Y335423D01*
G01X151989Y337256D02*
Y339756D01*
G01X153109D02*
Y337256D01*
G01Y338506D02*
X151989D01*
G01X152042Y340756D02*
Y343256D01*
X153056D01*
G01X152682Y342048D02*
X152042D01*
G01X151962Y344756D02*
Y347256D01*
X152496D01*
X152709Y347131D01*
X152869Y346964D01*
X153002Y346714D01*
X153109Y346423D01*
X153136Y346006D01*
X153109Y345589D01*
X153002Y345298D01*
X152869Y345048D01*
X152709Y344881D01*
X152496Y344756D01*
X151962D01*
G01X164549Y356756D02*
Y359256D01*
X164229Y358756D01*
G01Y356756D02*
X164869D01*
G01X157136Y349048D02*
X156976Y349173D01*
X156789Y349256D01*
X156576D01*
X156336Y349131D01*
X156149Y348923D01*
X156016Y348673D01*
X155909Y348256D01*
X155882Y347881D01*
X155936Y347506D01*
X156016Y347256D01*
X156176Y347006D01*
X156362Y346839D01*
X156549Y346756D01*
X156736D01*
X156922Y346839D01*
X157082Y346964D01*
X157216Y347131D01*
G01X152762Y349589D02*
X152869Y349714D01*
X152949Y349923D01*
X153002Y350214D01*
X152949Y350464D01*
X152842Y350631D01*
X152656Y350756D01*
X151936D01*
Y348256D01*
X152816D01*
X153002Y348423D01*
X153109Y348673D01*
X153162Y348964D01*
X153109Y349256D01*
X152949Y349506D01*
X152762Y349589D01*
X151936D01*
G01X149276Y374190D02*
Y369675D01*
X149589Y368730D01*
X150216Y368100D01*
X150999Y367890D01*
X151782Y368100D01*
X152409Y368730D01*
X152722Y369675D01*
Y374190D01*
G01X155811Y373140D02*
X156281Y373770D01*
X156829Y374085D01*
X157456Y374190D01*
X158239Y373980D01*
X158787Y373455D01*
X158944Y372825D01*
X158866Y372195D01*
X158552Y371670D01*
X156986Y370620D01*
X156281Y369885D01*
X155811Y368835D01*
X155654Y367890D01*
X158944D01*
G01X154373Y423956D02*
Y427056D01*
X155293D01*
X155600Y426901D01*
X155830Y426539D01*
X155907Y426126D01*
X155830Y425713D01*
X155638Y425403D01*
X155293Y425248D01*
X154373D01*
G01X159083Y426798D02*
X158853Y426953D01*
X158585Y427056D01*
X158278D01*
X157933Y426901D01*
X157665Y426643D01*
X157473Y426333D01*
X157320Y425816D01*
X157282Y425351D01*
X157358Y424886D01*
X157473Y424576D01*
X157703Y424266D01*
X157972Y424059D01*
X158240Y423956D01*
X158508D01*
X158777Y424059D01*
X159007Y424214D01*
X159198Y424421D01*
G01X160612Y426539D02*
X160842Y426849D01*
X161110Y427004D01*
X161417Y427056D01*
X161800Y426953D01*
X162068Y426694D01*
X162145Y426384D01*
X162107Y426074D01*
X161953Y425816D01*
X161187Y425299D01*
X160842Y424938D01*
X160612Y424421D01*
X160535Y423956D01*
X162145D01*
G01X164440Y427056D02*
X164133Y426953D01*
X163903Y426694D01*
X163750Y426384D01*
X163635Y425971D01*
X163597Y425506D01*
X163635Y425041D01*
X163750Y424628D01*
X163903Y424318D01*
X164133Y424059D01*
X164440Y423956D01*
X164747Y424059D01*
X164977Y424318D01*
X165130Y424628D01*
X165245Y425041D01*
X165283Y425506D01*
X165245Y425971D01*
X165130Y426384D01*
X164977Y426694D01*
X164747Y426953D01*
X164440Y427056D01*
G01X160352Y410417D02*
X157252D01*
Y411337D01*
X157407Y411644D01*
X157769Y411874D01*
X158182Y411951D01*
X158595Y411874D01*
X158905Y411682D01*
X159060Y411337D01*
Y410417D01*
G01X160352Y413517D02*
X157252D01*
Y414476D01*
X157407Y414782D01*
X157614Y414974D01*
X158027Y415051D01*
X158440Y414974D01*
X158699Y414744D01*
X158854Y414476D01*
Y413517D01*
G01Y414476D02*
X160352Y415051D01*
G01X159887Y416541D02*
X160145Y416771D01*
X160300Y417039D01*
X160352Y417384D01*
X160249Y417729D01*
X160042Y417997D01*
X159680Y418189D01*
X159267Y418227D01*
X158854Y418151D01*
X158595Y417959D01*
X158389Y417691D01*
X158337Y417422D01*
X158389Y417154D01*
X158595Y416809D01*
X157252Y416924D01*
Y417959D01*
G01X164852Y410417D02*
X161752D01*
Y411337D01*
X161907Y411644D01*
X162269Y411874D01*
X162682Y411951D01*
X163095Y411874D01*
X163405Y411682D01*
X163560Y411337D01*
Y410417D01*
G01X164852Y413517D02*
X161752D01*
Y414476D01*
X161907Y414782D01*
X162114Y414974D01*
X162527Y415051D01*
X162940Y414974D01*
X163199Y414744D01*
X163354Y414476D01*
Y413517D01*
G01Y414476D02*
X164852Y415051D01*
G01X163560Y416656D02*
X163199Y416924D01*
X162992Y417154D01*
X162889Y417461D01*
X162992Y417729D01*
X163199Y417921D01*
X163509Y418074D01*
X163870Y418112D01*
X164180Y418074D01*
X164490Y417921D01*
X164749Y417691D01*
X164852Y417422D01*
X164749Y417116D01*
X164439Y416847D01*
X163974Y416694D01*
X163457Y416656D01*
X162785Y416732D01*
X162424Y416847D01*
X162062Y417039D01*
X161804Y417307D01*
X161752Y417576D01*
X161855Y417844D01*
X162114Y418036D01*
G01X162922Y430921D02*
Y434121D01*
G01X169122Y430921D02*
X162922D01*
G01Y434121D02*
X169122D01*
G01X162720Y435234D02*
Y438434D01*
G01D02*
X168920D01*
G01Y435234D02*
X162720D01*
G01X163249Y439477D02*
Y442677D01*
G01X169449Y439477D02*
X163249D01*
G01Y442677D02*
X169449D01*
G01X160934Y449612D02*
Y452712D01*
X161854D01*
X162161Y452557D01*
X162391Y452195D01*
X162468Y451782D01*
X162391Y451369D01*
X162199Y451059D01*
X161854Y450904D01*
X160934D01*
G01X165644Y452454D02*
X165414Y452609D01*
X165146Y452712D01*
X164839D01*
X164494Y452557D01*
X164226Y452299D01*
X164034Y451989D01*
X163881Y451472D01*
X163843Y451007D01*
X163919Y450542D01*
X164034Y450232D01*
X164264Y449922D01*
X164533Y449715D01*
X164801Y449612D01*
X165069D01*
X165338Y449715D01*
X165568Y449870D01*
X165759Y450077D01*
G01X167901Y449612D02*
Y452712D01*
X167441Y452092D01*
G01Y449612D02*
X168361D01*
G01X170349Y449974D02*
X170618Y449715D01*
X170924Y449612D01*
X171231Y449715D01*
X171499Y450025D01*
X171691Y450490D01*
X171768Y450955D01*
Y451524D01*
X171691Y451989D01*
X171499Y452402D01*
X171269Y452609D01*
X171001Y452712D01*
X170694Y452609D01*
X170464Y452402D01*
X170311Y452092D01*
X170234Y451679D01*
X170311Y451317D01*
X170503Y450955D01*
X170733Y450749D01*
X171001Y450697D01*
X171308Y450800D01*
X171538Y451059D01*
X171768Y451524D01*
G01X154771Y454679D02*
X154616Y454449D01*
X154513Y454181D01*
Y453874D01*
X154668Y453529D01*
X154926Y453261D01*
X155236Y453069D01*
X155753Y452916D01*
X156218Y452878D01*
X156683Y452954D01*
X156993Y453069D01*
X157303Y453299D01*
X157510Y453568D01*
X157613Y453836D01*
Y454104D01*
X157510Y454373D01*
X157355Y454603D01*
X157148Y454794D01*
G01X157613Y456936D02*
X157561Y457204D01*
X157406Y457511D01*
X157148Y457703D01*
X156786Y457779D01*
X156425Y457703D01*
X156115Y457473D01*
X155960Y457128D01*
Y456744D01*
X155856Y456514D01*
X155598Y456323D01*
X155236Y456246D01*
X154875Y456361D01*
X154616Y456629D01*
X154513Y456936D01*
X154616Y457243D01*
X154875Y457511D01*
X155236Y457626D01*
X155598Y457549D01*
X155856Y457358D01*
X155960Y457128D01*
Y456744D01*
X156115Y456399D01*
X156425Y456169D01*
X156786Y456093D01*
X157148Y456169D01*
X157406Y456361D01*
X157561Y456668D01*
X157613Y456936D01*
G01Y460496D02*
X154513D01*
X156735Y459078D01*
Y460994D01*
G01X157251Y462484D02*
X157510Y462753D01*
X157613Y463059D01*
X157510Y463366D01*
X157200Y463634D01*
X156735Y463826D01*
X156270Y463903D01*
X155701D01*
X155236Y463826D01*
X154823Y463634D01*
X154616Y463404D01*
X154513Y463136D01*
X154616Y462829D01*
X154823Y462599D01*
X155133Y462446D01*
X155546Y462369D01*
X155908Y462446D01*
X156270Y462638D01*
X156476Y462868D01*
X156528Y463136D01*
X156425Y463443D01*
X156166Y463673D01*
X155701Y463903D01*
G01X153401Y457487D02*
Y447287D01*
G01X148801Y452387D02*
X153401D01*
G01X148801Y447287D02*
Y457487D01*
G01X153401Y447287D02*
X148801D01*
G01X149501Y440404D02*
Y446604D01*
G01X152701Y440404D02*
X149501D01*
G01Y446604D02*
X152701D01*
G01D02*
Y440404D01*
G01X163249Y443434D02*
Y446634D01*
G01X169449Y443434D02*
X163249D01*
G01Y446634D02*
X169449D01*
G01X160934Y453771D02*
Y456871D01*
X161854D01*
X162161Y456716D01*
X162391Y456354D01*
X162468Y455941D01*
X162391Y455528D01*
X162199Y455218D01*
X161854Y455063D01*
X160934D01*
G01X164034Y453771D02*
Y456871D01*
X164993D01*
X165299Y456716D01*
X165491Y456509D01*
X165568Y456096D01*
X165491Y455683D01*
X165261Y455424D01*
X164993Y455269D01*
X164034D01*
G01X164993D02*
X165568Y453771D01*
G01X167901D02*
X168169Y453823D01*
X168476Y453978D01*
X168668Y454236D01*
X168744Y454598D01*
X168668Y454959D01*
X168438Y455269D01*
X168093Y455424D01*
X167709D01*
X167479Y455528D01*
X167288Y455786D01*
X167211Y456148D01*
X167326Y456509D01*
X167594Y456768D01*
X167901Y456871D01*
X168208Y456768D01*
X168476Y456509D01*
X168591Y456148D01*
X168514Y455786D01*
X168323Y455528D01*
X168093Y455424D01*
X167709D01*
X167364Y455269D01*
X167134Y454959D01*
X167058Y454598D01*
X167134Y454236D01*
X167326Y453978D01*
X167633Y453823D01*
X167901Y453771D01*
G01X160934Y457815D02*
Y460915D01*
X161854D01*
X162161Y460760D01*
X162391Y460398D01*
X162468Y459985D01*
X162391Y459572D01*
X162199Y459262D01*
X161854Y459107D01*
X160934D01*
G01X165644Y460657D02*
X165414Y460812D01*
X165146Y460915D01*
X164839D01*
X164494Y460760D01*
X164226Y460502D01*
X164034Y460192D01*
X163881Y459675D01*
X163843Y459210D01*
X163919Y458745D01*
X164034Y458435D01*
X164264Y458125D01*
X164533Y457918D01*
X164801Y457815D01*
X165069D01*
X165338Y457918D01*
X165568Y458073D01*
X165759Y458280D01*
G01X167173Y460398D02*
X167403Y460708D01*
X167671Y460863D01*
X167978Y460915D01*
X168361Y460812D01*
X168629Y460553D01*
X168706Y460243D01*
X168668Y459933D01*
X168514Y459675D01*
X167748Y459158D01*
X167403Y458797D01*
X167173Y458280D01*
X167096Y457815D01*
X168706D01*
G01X171001D02*
Y460915D01*
X170541Y460295D01*
G01Y457815D02*
X171461D01*
G01X148801Y457487D02*
X153401D01*
G01X157408Y466050D02*
X154308D01*
Y467009D01*
X154463Y467315D01*
X154670Y467507D01*
X155083Y467584D01*
X155496Y467507D01*
X155755Y467277D01*
X155910Y467009D01*
Y466050D01*
G01Y467009D02*
X157408Y467584D01*
G01Y469917D02*
X154308D01*
X154928Y469457D01*
G01X157408D02*
Y470377D01*
G01Y473017D02*
X154308D01*
X154928Y472557D01*
G01X157408D02*
Y473477D01*
G01Y476117D02*
X154308D01*
X154928Y475657D01*
G01X157408D02*
Y476577D01*
G01X156943Y478374D02*
X157201Y478604D01*
X157356Y478872D01*
X157408Y479217D01*
X157305Y479562D01*
X157098Y479830D01*
X156736Y480022D01*
X156323Y480060D01*
X155910Y479984D01*
X155651Y479792D01*
X155445Y479524D01*
X155393Y479255D01*
X155445Y478987D01*
X155651Y478642D01*
X154308Y478757D01*
Y479792D01*
G01X152745Y468109D02*
Y461909D01*
G01X149545D02*
Y468109D01*
G01D02*
X152745D01*
G01Y461909D02*
X149545D01*
G01X160934Y461871D02*
Y464971D01*
X161854D01*
X162161Y464816D01*
X162391Y464454D01*
X162468Y464041D01*
X162391Y463628D01*
X162199Y463318D01*
X161854Y463163D01*
X160934D01*
G01X164034Y461871D02*
Y464971D01*
X164993D01*
X165299Y464816D01*
X165491Y464609D01*
X165568Y464196D01*
X165491Y463783D01*
X165261Y463524D01*
X164993Y463369D01*
X164034D01*
G01X164993D02*
X165568Y461871D01*
G01X167824D02*
X167901Y462543D01*
X168016Y463111D01*
X168169Y463628D01*
X168361Y464196D01*
X168668Y464971D01*
X167134D01*
G01X149972Y471548D02*
X150505D01*
Y470798D01*
X150345Y470548D01*
X150159Y470381D01*
X149892Y470298D01*
X149625Y470381D01*
X149439Y470548D01*
X149279Y470798D01*
X149172Y471090D01*
X149119Y471423D01*
Y471715D01*
X149172Y471965D01*
X149279Y472256D01*
X149439Y472506D01*
X149599Y472673D01*
X149812Y472798D01*
X149999D01*
X150212Y472715D01*
X150372Y472548D01*
G01X148406Y470655D02*
Y458031D01*
G01X161093Y479239D02*
X160863Y479394D01*
X160595Y479497D01*
X160288D01*
X159943Y479342D01*
X159675Y479084D01*
X159483Y478774D01*
X159330Y478257D01*
X159292Y477792D01*
X159368Y477327D01*
X159483Y477017D01*
X159713Y476707D01*
X159982Y476500D01*
X160250Y476397D01*
X160518D01*
X160787Y476500D01*
X161017Y476655D01*
X161208Y476862D01*
G01X162622Y478980D02*
X162852Y479290D01*
X163120Y479445D01*
X163427Y479497D01*
X163810Y479394D01*
X164078Y479135D01*
X164155Y478825D01*
X164117Y478515D01*
X163963Y478257D01*
X163197Y477740D01*
X162852Y477379D01*
X162622Y476862D01*
X162545Y476397D01*
X164155D01*
G01X165722Y478980D02*
X165952Y479290D01*
X166220Y479445D01*
X166527Y479497D01*
X166910Y479394D01*
X167178Y479135D01*
X167255Y478825D01*
X167217Y478515D01*
X167063Y478257D01*
X166297Y477740D01*
X165952Y477379D01*
X165722Y476862D01*
X165645Y476397D01*
X167255D01*
G01X168707Y476862D02*
X168937Y476604D01*
X169205Y476449D01*
X169550Y476397D01*
X169895Y476500D01*
X170163Y476707D01*
X170355Y477069D01*
X170393Y477482D01*
X170317Y477895D01*
X170125Y478154D01*
X169857Y478360D01*
X169588Y478412D01*
X169320Y478360D01*
X168975Y478154D01*
X169090Y479497D01*
X170125D01*
G01X161904Y481593D02*
X158804D01*
Y482552D01*
X158959Y482858D01*
X159166Y483050D01*
X159579Y483127D01*
X159992Y483050D01*
X160251Y482820D01*
X160406Y482552D01*
Y481593D01*
G01Y482552D02*
X161904Y483127D01*
G01X159321Y484732D02*
X159011Y484962D01*
X158856Y485230D01*
X158804Y485537D01*
X158907Y485920D01*
X159166Y486188D01*
X159476Y486265D01*
X159786Y486227D01*
X160044Y486073D01*
X160561Y485307D01*
X160922Y484962D01*
X161439Y484732D01*
X161904Y484655D01*
Y486265D01*
G01X161439Y487717D02*
X161697Y487947D01*
X161852Y488215D01*
X161904Y488560D01*
X161801Y488905D01*
X161594Y489173D01*
X161232Y489365D01*
X160819Y489403D01*
X160406Y489327D01*
X160147Y489135D01*
X159941Y488867D01*
X159889Y488598D01*
X159941Y488330D01*
X160147Y487985D01*
X158804Y488100D01*
Y489135D01*
G01X161542Y491008D02*
X161801Y491277D01*
X161904Y491583D01*
X161801Y491890D01*
X161491Y492158D01*
X161026Y492350D01*
X160561Y492427D01*
X159992D01*
X159527Y492350D01*
X159114Y492158D01*
X158907Y491928D01*
X158804Y491660D01*
X158907Y491353D01*
X159114Y491123D01*
X159424Y490970D01*
X159837Y490893D01*
X160199Y490970D01*
X160561Y491162D01*
X160767Y491392D01*
X160819Y491660D01*
X160716Y491967D01*
X160457Y492197D01*
X159992Y492427D01*
G01X151627Y508256D02*
Y505156D01*
G01X150745Y508256D02*
X152509D01*
G01X150891Y511997D02*
Y515097D01*
X151811D01*
X152118Y514942D01*
X152348Y514580D01*
X152425Y514167D01*
X152348Y513754D01*
X152156Y513444D01*
X151811Y513289D01*
X150891D01*
G01X150661Y518296D02*
Y521396D01*
X151658Y518813D01*
X152655Y521396D01*
Y518296D01*
G01X154461Y504975D02*
Y557731D01*
G01X184382Y504975D02*
X154461D01*
G01X150815Y524595D02*
Y527695D01*
G01X152271D02*
X150815Y525783D01*
G01X152501Y524595D02*
X151466Y526662D01*
G01X150853Y530894D02*
Y533994D01*
G01X152463D02*
Y530894D01*
G01Y532444D02*
X150853D01*
G01X151315Y544493D02*
Y547593D01*
X152081D01*
X152388Y547438D01*
X152618Y547231D01*
X152810Y546921D01*
X152963Y546560D01*
X153001Y546043D01*
X152963Y545526D01*
X152810Y545165D01*
X152618Y544855D01*
X152388Y544648D01*
X152081Y544493D01*
X151315D01*
G01X151430Y538194D02*
Y541294D01*
X152886D01*
G01X152350Y539796D02*
X151430D01*
G01X152465Y552445D02*
X152618Y552600D01*
X152733Y552859D01*
X152810Y553220D01*
X152733Y553530D01*
X152580Y553737D01*
X152311Y553892D01*
X151276D01*
Y550792D01*
X152541D01*
X152810Y550999D01*
X152963Y551309D01*
X153040Y551670D01*
X152963Y552032D01*
X152733Y552342D01*
X152465Y552445D01*
X151276D01*
G01X157611Y563819D02*
Y566919D01*
X157151Y566299D01*
G01Y563819D02*
X158071D01*
G01X160032Y561902D02*
X160262Y562212D01*
X160530Y562367D01*
X160837Y562419D01*
X161220Y562316D01*
X161488Y562057D01*
X161565Y561747D01*
X161527Y561437D01*
X161373Y561179D01*
X160607Y560662D01*
X160262Y560301D01*
X160032Y559784D01*
X159955Y559319D01*
X161565D01*
G01X163067Y564439D02*
X163297Y564077D01*
X163603Y563871D01*
X163948Y563819D01*
X164255Y563871D01*
X164562Y564129D01*
X164753Y564439D01*
X164792Y564749D01*
X164715Y565111D01*
X164447Y565369D01*
X164178Y565472D01*
X163833D01*
G01X164178D02*
X164408Y565627D01*
X164600Y565886D01*
X164677Y566196D01*
X164600Y566506D01*
X164408Y566764D01*
X164063Y566919D01*
X163718Y566867D01*
X163373Y566661D01*
G01X154461Y557731D02*
X184382D01*
G01X164263Y570933D02*
X161063D01*
G01D02*
Y577133D01*
G01D02*
X164263D01*
G01X160030Y577235D02*
Y571035D01*
G01D02*
X156830D01*
G01D02*
Y577235D01*
G01D02*
X160030D01*
G01X154600Y571026D02*
X151500D01*
Y571985D01*
X151655Y572291D01*
X151862Y572483D01*
X152275Y572560D01*
X152688Y572483D01*
X152947Y572253D01*
X153102Y571985D01*
Y571026D01*
G01Y571985D02*
X154600Y572560D01*
G01X154135Y574050D02*
X154393Y574280D01*
X154548Y574548D01*
X154600Y574893D01*
X154497Y575238D01*
X154290Y575506D01*
X153928Y575698D01*
X153515Y575736D01*
X153102Y575660D01*
X152843Y575468D01*
X152637Y575200D01*
X152585Y574931D01*
X152637Y574663D01*
X152843Y574318D01*
X151500Y574433D01*
Y575468D01*
G01X154600Y578453D02*
X151500D01*
X153722Y577035D01*
Y578951D01*
G01X154600Y581553D02*
X151500D01*
X153722Y580135D01*
Y582051D01*
G01X153640Y585060D02*
X170590D01*
G01X153640Y592790D02*
Y585060D01*
G01X159696Y592266D02*
X157796Y594166D01*
G01X149038Y608136D02*
X151260D01*
X151725Y608289D01*
X152035Y608596D01*
X152138Y608979D01*
X152035Y609362D01*
X151725Y609669D01*
X151260Y609822D01*
X149038D01*
G01X151518Y611236D02*
X151880Y611466D01*
X152086Y611772D01*
X152138Y612117D01*
X152086Y612424D01*
X151828Y612731D01*
X151518Y612922D01*
X151208Y612961D01*
X150846Y612884D01*
X150588Y612616D01*
X150485Y612347D01*
Y612002D01*
G01Y612347D02*
X150330Y612577D01*
X150071Y612769D01*
X149761Y612846D01*
X149451Y612769D01*
X149193Y612577D01*
X149038Y612232D01*
X149090Y611887D01*
X149296Y611542D01*
G01X151673Y614336D02*
X151931Y614566D01*
X152086Y614834D01*
X152138Y615179D01*
X152035Y615524D01*
X151828Y615792D01*
X151466Y615984D01*
X151053Y616022D01*
X150640Y615946D01*
X150381Y615754D01*
X150175Y615486D01*
X150123Y615217D01*
X150175Y614949D01*
X150381Y614604D01*
X149038Y614719D01*
Y615754D01*
G01X155258Y625235D02*
X152758D01*
X154550Y624248D01*
Y625582D01*
G01X154966Y626662D02*
X155175Y626848D01*
X155258Y627062D01*
X155175Y627275D01*
X154925Y627462D01*
X154550Y627595D01*
X154175Y627648D01*
X153716D01*
X153341Y627595D01*
X153008Y627462D01*
X152841Y627302D01*
X152758Y627115D01*
X152841Y626902D01*
X153008Y626742D01*
X153258Y626635D01*
X153591Y626582D01*
X153883Y626635D01*
X154175Y626768D01*
X154341Y626928D01*
X154383Y627115D01*
X154300Y627328D01*
X154091Y627488D01*
X153716Y627648D01*
G01X157746Y627650D02*
X159663D01*
G01X154963Y612886D02*
X152963D01*
G01X157746Y625833D02*
Y627650D01*
G01X159574Y629769D02*
X157074D01*
X158866Y628782D01*
Y630116D01*
G01X159574Y631649D02*
X159532Y631836D01*
X159407Y632049D01*
X159199Y632182D01*
X158907Y632236D01*
X158616Y632182D01*
X158366Y632022D01*
X158241Y631782D01*
Y631516D01*
X158157Y631356D01*
X157949Y631222D01*
X157657Y631169D01*
X157366Y631249D01*
X157157Y631436D01*
X157074Y631649D01*
X157157Y631862D01*
X157366Y632049D01*
X157657Y632129D01*
X157949Y632076D01*
X158157Y631942D01*
X158241Y631782D01*
Y631516D01*
X158366Y631276D01*
X158616Y631116D01*
X158907Y631062D01*
X159199Y631116D01*
X159407Y631249D01*
X159532Y631462D01*
X159574Y631649D01*
G01X162471Y641163D02*
X162241Y641318D01*
X161973Y641421D01*
X161666D01*
X161321Y641266D01*
X161053Y641008D01*
X160861Y640698D01*
X160708Y640181D01*
X160670Y639716D01*
X160746Y639251D01*
X160861Y638941D01*
X161091Y638631D01*
X161360Y638424D01*
X161628Y638321D01*
X161896D01*
X162165Y638424D01*
X162395Y638579D01*
X162586Y638786D01*
G01X163885Y638941D02*
X164115Y638579D01*
X164421Y638373D01*
X164766Y638321D01*
X165073Y638373D01*
X165380Y638631D01*
X165571Y638941D01*
X165610Y639251D01*
X165533Y639613D01*
X165265Y639871D01*
X164996Y639974D01*
X164651D01*
G01X164996D02*
X165226Y640129D01*
X165418Y640388D01*
X165495Y640698D01*
X165418Y641008D01*
X165226Y641266D01*
X164881Y641421D01*
X164536Y641369D01*
X164191Y641163D01*
G01X167176Y638683D02*
X167445Y638424D01*
X167751Y638321D01*
X168058Y638424D01*
X168326Y638734D01*
X168518Y639199D01*
X168595Y639664D01*
Y640233D01*
X168518Y640698D01*
X168326Y641111D01*
X168096Y641318D01*
X167828Y641421D01*
X167521Y641318D01*
X167291Y641111D01*
X167138Y640801D01*
X167061Y640388D01*
X167138Y640026D01*
X167330Y639664D01*
X167560Y639458D01*
X167828Y639406D01*
X168135Y639509D01*
X168365Y639768D01*
X168595Y640233D01*
G01X170276Y638683D02*
X170545Y638424D01*
X170851Y638321D01*
X171158Y638424D01*
X171426Y638734D01*
X171618Y639199D01*
X171695Y639664D01*
Y640233D01*
X171618Y640698D01*
X171426Y641111D01*
X171196Y641318D01*
X170928Y641421D01*
X170621Y641318D01*
X170391Y641111D01*
X170238Y640801D01*
X170161Y640388D01*
X170238Y640026D01*
X170430Y639664D01*
X170660Y639458D01*
X170928Y639406D01*
X171235Y639509D01*
X171465Y639768D01*
X171695Y640233D01*
G01X155257Y633748D02*
X152157D01*
Y634707D01*
X152312Y635013D01*
X152519Y635205D01*
X152932Y635282D01*
X153345Y635205D01*
X153604Y634975D01*
X153759Y634707D01*
Y633748D01*
G01Y634707D02*
X155257Y635282D01*
G01X154792Y636772D02*
X155050Y637002D01*
X155205Y637270D01*
X155257Y637615D01*
X155154Y637960D01*
X154947Y638228D01*
X154585Y638420D01*
X154172Y638458D01*
X153759Y638382D01*
X153500Y638190D01*
X153294Y637922D01*
X153242Y637653D01*
X153294Y637385D01*
X153500Y637040D01*
X152157Y637155D01*
Y638190D01*
G01X154792Y639872D02*
X155050Y640102D01*
X155205Y640370D01*
X155257Y640715D01*
X155154Y641060D01*
X154947Y641328D01*
X154585Y641520D01*
X154172Y641558D01*
X153759Y641482D01*
X153500Y641290D01*
X153294Y641022D01*
X153242Y640753D01*
X153294Y640485D01*
X153500Y640140D01*
X152157Y640255D01*
Y641290D01*
G01X154895Y643163D02*
X155154Y643432D01*
X155257Y643738D01*
X155154Y644045D01*
X154844Y644313D01*
X154379Y644505D01*
X153914Y644582D01*
X153345D01*
X152880Y644505D01*
X152467Y644313D01*
X152260Y644083D01*
X152157Y643815D01*
X152260Y643508D01*
X152467Y643278D01*
X152777Y643125D01*
X153190Y643048D01*
X153552Y643125D01*
X153914Y643317D01*
X154120Y643547D01*
X154172Y643815D01*
X154069Y644122D01*
X153810Y644352D01*
X153345Y644582D01*
G01X156363Y635433D02*
Y641633D01*
G01D02*
X159563D01*
G01D02*
Y635433D01*
G01D02*
X156363D01*
G01X156504Y658723D02*
X153404D01*
Y659682D01*
X153559Y659988D01*
X153766Y660180D01*
X154179Y660257D01*
X154592Y660180D01*
X154851Y659950D01*
X155006Y659682D01*
Y658723D01*
G01Y659682D02*
X156504Y660257D01*
G01Y662590D02*
X153404D01*
X154024Y662130D01*
G01X156504D02*
Y663050D01*
G01X153404Y665690D02*
X153507Y665383D01*
X153766Y665153D01*
X154076Y665000D01*
X154489Y664885D01*
X154954Y664847D01*
X155419Y664885D01*
X155832Y665000D01*
X156142Y665153D01*
X156401Y665383D01*
X156504Y665690D01*
X156401Y665997D01*
X156142Y666227D01*
X155832Y666380D01*
X155419Y666495D01*
X154954Y666533D01*
X154489Y666495D01*
X154076Y666380D01*
X153766Y666227D01*
X153507Y665997D01*
X153404Y665690D01*
G01X156504Y668713D02*
X155832Y668790D01*
X155264Y668905D01*
X154747Y669058D01*
X154179Y669250D01*
X153404Y669557D01*
Y668023D01*
G01Y671890D02*
X153507Y671583D01*
X153766Y671353D01*
X154076Y671200D01*
X154489Y671085D01*
X154954Y671047D01*
X155419Y671085D01*
X155832Y671200D01*
X156142Y671353D01*
X156401Y671583D01*
X156504Y671890D01*
X156401Y672197D01*
X156142Y672427D01*
X155832Y672580D01*
X155419Y672695D01*
X154954Y672733D01*
X154489Y672695D01*
X154076Y672580D01*
X153766Y672427D01*
X153507Y672197D01*
X153404Y671890D01*
G01X153066Y652335D02*
Y653730D01*
X152299Y655435D01*
G01X153833D02*
X153066Y653730D01*
G01X156626Y652335D02*
Y655435D01*
X155208Y653213D01*
X157124D01*
G01X158263Y646740D02*
Y660126D01*
G01X184663Y646740D02*
X158263D01*
G01X166412Y664849D02*
X163212D01*
G01D02*
Y671049D01*
G01D02*
X166412D01*
G01X158263Y660126D02*
X184663D01*
G01X158924Y662001D02*
X161146D01*
X161611Y662154D01*
X161921Y662461D01*
X162024Y662844D01*
X161921Y663227D01*
X161611Y663534D01*
X161146Y663687D01*
X158924D01*
G01X162024Y665944D02*
X158924D01*
X159544Y665484D01*
G01X162024D02*
Y666404D01*
G01Y669044D02*
X158924D01*
X159544Y668584D01*
G01X162024D02*
Y669504D01*
G01Y672604D02*
X158924D01*
X161146Y671186D01*
Y673102D01*
G01X164794Y673493D02*
X165327D01*
Y672743D01*
X165167Y672493D01*
X164981Y672326D01*
X164714Y672243D01*
X164447Y672326D01*
X164261Y672493D01*
X164101Y672743D01*
X163994Y673035D01*
X163941Y673368D01*
Y673660D01*
X163994Y673910D01*
X164101Y674201D01*
X164261Y674451D01*
X164421Y674618D01*
X164634Y674743D01*
X164821D01*
X165034Y674660D01*
X165194Y674493D01*
G01X158323Y691239D02*
Y683839D01*
G01X149623Y691239D02*
Y683839D01*
G01X162434Y693442D02*
Y692609D01*
G01Y713475D02*
Y712542D01*
G01X152672Y722026D02*
X152832Y722276D01*
X153019Y722401D01*
X153232Y722443D01*
X153499Y722360D01*
X153686Y722151D01*
X153739Y721901D01*
X153712Y721651D01*
X153606Y721443D01*
X153072Y721026D01*
X152832Y720735D01*
X152672Y720318D01*
X152619Y719943D01*
X153739D01*
G01X157064Y716989D02*
Y742389D01*
G01X167664Y716989D02*
X157064D01*
G01X149517Y738242D02*
X149677Y737950D01*
X149891Y737784D01*
X150131Y737742D01*
X150344Y737784D01*
X150557Y737992D01*
X150691Y738242D01*
X150717Y738492D01*
X150664Y738784D01*
X150477Y738992D01*
X150291Y739075D01*
X150051D01*
G01X150291D02*
X150451Y739200D01*
X150584Y739409D01*
X150637Y739659D01*
X150584Y739909D01*
X150451Y740117D01*
X150211Y740242D01*
X149971Y740200D01*
X149731Y740034D01*
G01X156088Y736942D02*
Y724342D01*
G01X151950Y745243D02*
X148850D01*
Y746009D01*
X149005Y746316D01*
X149212Y746546D01*
X149522Y746738D01*
X149883Y746891D01*
X150400Y746929D01*
X150917Y746891D01*
X151278Y746738D01*
X151588Y746546D01*
X151795Y746316D01*
X151950Y746009D01*
Y745243D01*
G01X149367Y748458D02*
X149057Y748688D01*
X148902Y748956D01*
X148850Y749263D01*
X148953Y749646D01*
X149212Y749914D01*
X149522Y749991D01*
X149832Y749953D01*
X150090Y749799D01*
X150607Y749033D01*
X150968Y748688D01*
X151485Y748458D01*
X151950Y748381D01*
Y749991D01*
G01X148850Y752286D02*
X148953Y751979D01*
X149212Y751749D01*
X149522Y751596D01*
X149935Y751481D01*
X150400Y751443D01*
X150865Y751481D01*
X151278Y751596D01*
X151588Y751749D01*
X151847Y751979D01*
X151950Y752286D01*
X151847Y752593D01*
X151588Y752823D01*
X151278Y752976D01*
X150865Y753091D01*
X150400Y753129D01*
X149935Y753091D01*
X149522Y752976D01*
X149212Y752823D01*
X148953Y752593D01*
X148850Y752286D01*
G01X163245Y746268D02*
X160145D01*
Y747227D01*
X160300Y747533D01*
X160507Y747725D01*
X160920Y747802D01*
X161333Y747725D01*
X161592Y747495D01*
X161747Y747227D01*
Y746268D01*
G01Y747227D02*
X163245Y747802D01*
G01Y750135D02*
X160145D01*
X160765Y749675D01*
G01X163245D02*
Y750595D01*
G01X160145Y753235D02*
X160248Y752928D01*
X160507Y752698D01*
X160817Y752545D01*
X161230Y752430D01*
X161695Y752392D01*
X162160Y752430D01*
X162573Y752545D01*
X162883Y752698D01*
X163142Y752928D01*
X163245Y753235D01*
X163142Y753542D01*
X162883Y753772D01*
X162573Y753925D01*
X162160Y754040D01*
X161695Y754078D01*
X161230Y754040D01*
X160817Y753925D01*
X160507Y753772D01*
X160248Y753542D01*
X160145Y753235D01*
G01X163245Y756335D02*
X160145D01*
X160765Y755875D01*
G01X163245D02*
Y756795D01*
G01X162883Y758783D02*
X163142Y759052D01*
X163245Y759358D01*
X163142Y759665D01*
X162832Y759933D01*
X162367Y760125D01*
X161902Y760202D01*
X161333D01*
X160868Y760125D01*
X160455Y759933D01*
X160248Y759703D01*
X160145Y759435D01*
X160248Y759128D01*
X160455Y758898D01*
X160765Y758745D01*
X161178Y758668D01*
X161540Y758745D01*
X161902Y758937D01*
X162108Y759167D01*
X162160Y759435D01*
X162057Y759742D01*
X161798Y759972D01*
X161333Y760202D01*
G01X157064Y742389D02*
X167664D01*
G01X173735Y13388D02*
Y19588D01*
G01X176935D02*
Y13388D01*
G01D02*
X173735D01*
G01X169654Y13347D02*
Y19547D01*
G01X172854D02*
Y13347D01*
G01D02*
X169654D01*
G01X185282Y8445D02*
X177882D01*
G01D02*
Y25845D01*
G01X168648Y23117D02*
Y5717D01*
G01X179006Y46914D02*
Y29198D01*
G01D02*
X178100D01*
G01X167194D02*
Y46914D01*
G01X168100Y29198D02*
X167194D01*
G01X173735Y19588D02*
X176935D01*
G01X176835Y16488D02*
X173835D01*
G01X169654Y19547D02*
X172854D01*
G01X172754Y16447D02*
X169754D01*
G01X177882Y25845D02*
X185282D01*
G01X177882Y17145D02*
X185282D01*
G01X165533Y39000D02*
Y32800D01*
G01X178100Y46914D02*
X179006D01*
G01X167194D02*
X168100D01*
G01X168013Y54453D02*
X164913D01*
Y55373D01*
X165068Y55680D01*
X165430Y55910D01*
X165843Y55987D01*
X166256Y55910D01*
X166566Y55718D01*
X166721Y55373D01*
Y54453D01*
G01X165171Y59163D02*
X165016Y58933D01*
X164913Y58665D01*
Y58358D01*
X165068Y58013D01*
X165326Y57745D01*
X165636Y57553D01*
X166153Y57400D01*
X166618Y57362D01*
X167083Y57438D01*
X167393Y57553D01*
X167703Y57783D01*
X167910Y58052D01*
X168013Y58320D01*
Y58588D01*
X167910Y58857D01*
X167755Y59087D01*
X167548Y59278D01*
G01X168013Y61343D02*
X167341Y61420D01*
X166773Y61535D01*
X166256Y61688D01*
X165688Y61880D01*
X164913Y62187D01*
Y60653D01*
G01X166721Y63792D02*
X166360Y64060D01*
X166153Y64290D01*
X166050Y64597D01*
X166153Y64865D01*
X166360Y65057D01*
X166670Y65210D01*
X167031Y65248D01*
X167341Y65210D01*
X167651Y65057D01*
X167910Y64827D01*
X168013Y64558D01*
X167910Y64252D01*
X167600Y63983D01*
X167135Y63830D01*
X166618Y63792D01*
X165946Y63868D01*
X165585Y63983D01*
X165223Y64175D01*
X164965Y64443D01*
X164913Y64712D01*
X165016Y64980D01*
X165275Y65172D01*
G01X167712Y53268D02*
Y48668D01*
G01X179033Y129768D02*
X175933D01*
Y130727D01*
X176088Y131033D01*
X176295Y131225D01*
X176708Y131302D01*
X177121Y131225D01*
X177380Y130995D01*
X177535Y130727D01*
Y129768D01*
G01Y130727D02*
X179033Y131302D01*
G01X178568Y132792D02*
X178826Y133022D01*
X178981Y133290D01*
X179033Y133635D01*
X178930Y133980D01*
X178723Y134248D01*
X178361Y134440D01*
X177948Y134478D01*
X177535Y134402D01*
X177276Y134210D01*
X177070Y133942D01*
X177018Y133673D01*
X177070Y133405D01*
X177276Y133060D01*
X175933Y133175D01*
Y134210D01*
G01X178413Y135892D02*
X178775Y136122D01*
X178981Y136428D01*
X179033Y136773D01*
X178981Y137080D01*
X178723Y137387D01*
X178413Y137578D01*
X178103Y137617D01*
X177741Y137540D01*
X177483Y137272D01*
X177380Y137003D01*
Y136658D01*
G01Y137003D02*
X177225Y137233D01*
X176966Y137425D01*
X176656Y137502D01*
X176346Y137425D01*
X176088Y137233D01*
X175933Y136888D01*
X175985Y136543D01*
X176191Y136198D01*
G01X179033Y139758D02*
X178361Y139835D01*
X177793Y139950D01*
X177276Y140103D01*
X176708Y140295D01*
X175933Y140602D01*
Y139068D01*
G01X174813Y129768D02*
X171713D01*
Y130727D01*
X171868Y131033D01*
X172075Y131225D01*
X172488Y131302D01*
X172901Y131225D01*
X173160Y130995D01*
X173315Y130727D01*
Y129768D01*
G01Y130727D02*
X174813Y131302D01*
G01X174348Y132792D02*
X174606Y133022D01*
X174761Y133290D01*
X174813Y133635D01*
X174710Y133980D01*
X174503Y134248D01*
X174141Y134440D01*
X173728Y134478D01*
X173315Y134402D01*
X173056Y134210D01*
X172850Y133942D01*
X172798Y133673D01*
X172850Y133405D01*
X173056Y133060D01*
X171713Y133175D01*
Y134210D01*
G01X174193Y135892D02*
X174555Y136122D01*
X174761Y136428D01*
X174813Y136773D01*
X174761Y137080D01*
X174503Y137387D01*
X174193Y137578D01*
X173883Y137617D01*
X173521Y137540D01*
X173263Y137272D01*
X173160Y137003D01*
Y136658D01*
G01Y137003D02*
X173005Y137233D01*
X172746Y137425D01*
X172436Y137502D01*
X172126Y137425D01*
X171868Y137233D01*
X171713Y136888D01*
X171765Y136543D01*
X171971Y136198D01*
G01X173521Y139107D02*
X173160Y139375D01*
X172953Y139605D01*
X172850Y139912D01*
X172953Y140180D01*
X173160Y140372D01*
X173470Y140525D01*
X173831Y140563D01*
X174141Y140525D01*
X174451Y140372D01*
X174710Y140142D01*
X174813Y139873D01*
X174710Y139567D01*
X174400Y139298D01*
X173935Y139145D01*
X173418Y139107D01*
X172746Y139183D01*
X172385Y139298D01*
X172023Y139490D01*
X171765Y139758D01*
X171713Y140027D01*
X171816Y140295D01*
X172075Y140487D01*
G01X173710Y157195D02*
X173480Y157350D01*
X173212Y157453D01*
X172905D01*
X172560Y157298D01*
X172292Y157040D01*
X172100Y156730D01*
X171947Y156213D01*
X171909Y155748D01*
X171985Y155283D01*
X172100Y154973D01*
X172330Y154663D01*
X172599Y154456D01*
X172867Y154353D01*
X173135D01*
X173404Y154456D01*
X173634Y154611D01*
X173825Y154818D01*
G01X175239Y155645D02*
X175507Y156006D01*
X175737Y156213D01*
X176044Y156316D01*
X176312Y156213D01*
X176504Y156006D01*
X176657Y155696D01*
X176695Y155335D01*
X176657Y155025D01*
X176504Y154715D01*
X176274Y154456D01*
X176005Y154353D01*
X175699Y154456D01*
X175430Y154766D01*
X175277Y155231D01*
X175239Y155748D01*
X175315Y156420D01*
X175430Y156781D01*
X175622Y157143D01*
X175890Y157401D01*
X176159Y157453D01*
X176427Y157350D01*
X176619Y157091D01*
G01X179067Y154353D02*
Y157453D01*
X178607Y156833D01*
G01Y154353D02*
X179527D01*
G01X182167D02*
X182435Y154405D01*
X182742Y154560D01*
X182934Y154818D01*
X183010Y155180D01*
X182934Y155541D01*
X182704Y155851D01*
X182359Y156006D01*
X181975D01*
X181745Y156110D01*
X181554Y156368D01*
X181477Y156730D01*
X181592Y157091D01*
X181860Y157350D01*
X182167Y157453D01*
X182474Y157350D01*
X182742Y157091D01*
X182857Y156730D01*
X182780Y156368D01*
X182589Y156110D01*
X182359Y156006D01*
X181975D01*
X181630Y155851D01*
X181400Y155541D01*
X181324Y155180D01*
X181400Y154818D01*
X181592Y154560D01*
X181899Y154405D01*
X182167Y154353D01*
G01X175743Y142398D02*
X172643D01*
Y143357D01*
X172798Y143663D01*
X173005Y143855D01*
X173418Y143932D01*
X173831Y143855D01*
X174090Y143625D01*
X174245Y143357D01*
Y142398D01*
G01Y143357D02*
X175743Y143932D01*
G01X175278Y145422D02*
X175536Y145652D01*
X175691Y145920D01*
X175743Y146265D01*
X175640Y146610D01*
X175433Y146878D01*
X175071Y147070D01*
X174658Y147108D01*
X174245Y147032D01*
X173986Y146840D01*
X173780Y146572D01*
X173728Y146303D01*
X173780Y146035D01*
X173986Y145690D01*
X172643Y145805D01*
Y146840D01*
G01X175743Y149825D02*
X172643D01*
X174865Y148407D01*
Y150323D01*
G01X175743Y152465D02*
X172643D01*
X173263Y152005D01*
G01X175743D02*
Y152925D01*
G01X170642Y169109D02*
Y172209D01*
X171601D01*
X171907Y172054D01*
X172099Y171847D01*
X172176Y171434D01*
X172099Y171021D01*
X171869Y170762D01*
X171601Y170607D01*
X170642D01*
G01X171601D02*
X172176Y169109D01*
G01X174509D02*
Y172209D01*
X174049Y171589D01*
G01Y169109D02*
X174969D01*
G01X177609Y172209D02*
X177302Y172106D01*
X177072Y171847D01*
X176919Y171537D01*
X176804Y171124D01*
X176766Y170659D01*
X176804Y170194D01*
X176919Y169781D01*
X177072Y169471D01*
X177302Y169212D01*
X177609Y169109D01*
X177916Y169212D01*
X178146Y169471D01*
X178299Y169781D01*
X178414Y170194D01*
X178452Y170659D01*
X178414Y171124D01*
X178299Y171537D01*
X178146Y171847D01*
X177916Y172106D01*
X177609Y172209D01*
G01X180709D02*
X180402Y172106D01*
X180172Y171847D01*
X180019Y171537D01*
X179904Y171124D01*
X179866Y170659D01*
X179904Y170194D01*
X180019Y169781D01*
X180172Y169471D01*
X180402Y169212D01*
X180709Y169109D01*
X181016Y169212D01*
X181246Y169471D01*
X181399Y169781D01*
X181514Y170194D01*
X181552Y170659D01*
X181514Y171124D01*
X181399Y171537D01*
X181246Y171847D01*
X181016Y172106D01*
X180709Y172209D01*
G01X183081Y170401D02*
X183349Y170762D01*
X183579Y170969D01*
X183886Y171072D01*
X184154Y170969D01*
X184346Y170762D01*
X184499Y170452D01*
X184537Y170091D01*
X184499Y169781D01*
X184346Y169471D01*
X184116Y169212D01*
X183847Y169109D01*
X183541Y169212D01*
X183272Y169522D01*
X183119Y169987D01*
X183081Y170504D01*
X183157Y171176D01*
X183272Y171537D01*
X183464Y171899D01*
X183732Y172157D01*
X184001Y172209D01*
X184269Y172106D01*
X184461Y171847D01*
G01X179031Y159708D02*
X181253D01*
X181718Y159861D01*
X182028Y160168D01*
X182131Y160551D01*
X182028Y160934D01*
X181718Y161241D01*
X181253Y161394D01*
X179031D01*
G01X181769Y162999D02*
X182028Y163268D01*
X182131Y163574D01*
X182028Y163881D01*
X181718Y164149D01*
X181253Y164341D01*
X180788Y164418D01*
X180219D01*
X179754Y164341D01*
X179341Y164149D01*
X179134Y163919D01*
X179031Y163651D01*
X179134Y163344D01*
X179341Y163114D01*
X179651Y162961D01*
X180064Y162884D01*
X180426Y162961D01*
X180788Y163153D01*
X180994Y163383D01*
X181046Y163651D01*
X180943Y163958D01*
X180684Y164188D01*
X180219Y164418D01*
G01X179548Y166023D02*
X179238Y166253D01*
X179083Y166521D01*
X179031Y166828D01*
X179134Y167211D01*
X179393Y167479D01*
X179703Y167556D01*
X180013Y167518D01*
X180271Y167364D01*
X180788Y166598D01*
X181149Y166253D01*
X181666Y166023D01*
X182131Y165946D01*
Y167556D01*
G01X172155Y189425D02*
X171925Y189580D01*
X171657Y189683D01*
X171350D01*
X171005Y189528D01*
X170737Y189270D01*
X170545Y188960D01*
X170392Y188443D01*
X170354Y187978D01*
X170430Y187513D01*
X170545Y187203D01*
X170775Y186893D01*
X171044Y186686D01*
X171312Y186583D01*
X171580D01*
X171849Y186686D01*
X172079Y186841D01*
X172270Y187048D01*
G01X174335Y186583D02*
X174412Y187255D01*
X174527Y187823D01*
X174680Y188340D01*
X174872Y188908D01*
X175179Y189683D01*
X173645D01*
G01X177435Y186583D02*
X177512Y187255D01*
X177627Y187823D01*
X177780Y188340D01*
X177972Y188908D01*
X178279Y189683D01*
X176745D01*
G01X179769Y187048D02*
X179999Y186790D01*
X180267Y186635D01*
X180612Y186583D01*
X180957Y186686D01*
X181225Y186893D01*
X181417Y187255D01*
X181455Y187668D01*
X181379Y188081D01*
X181187Y188340D01*
X180919Y188546D01*
X180650Y188598D01*
X180382Y188546D01*
X180037Y188340D01*
X180152Y189683D01*
X181187D01*
G01X172257Y185403D02*
X172027Y185558D01*
X171759Y185661D01*
X171452D01*
X171107Y185506D01*
X170839Y185248D01*
X170647Y184938D01*
X170494Y184421D01*
X170456Y183956D01*
X170532Y183491D01*
X170647Y183181D01*
X170877Y182871D01*
X171146Y182664D01*
X171414Y182561D01*
X171682D01*
X171951Y182664D01*
X172181Y182819D01*
X172372Y183026D01*
G01X174437Y182561D02*
X174514Y183233D01*
X174629Y183801D01*
X174782Y184318D01*
X174974Y184886D01*
X175281Y185661D01*
X173747D01*
G01X177537Y182561D02*
X177614Y183233D01*
X177729Y183801D01*
X177882Y184318D01*
X178074Y184886D01*
X178381Y185661D01*
X176847D01*
G01X181174Y182561D02*
Y185661D01*
X179756Y183439D01*
X181672D01*
G01X172157Y181249D02*
X171927Y181404D01*
X171659Y181507D01*
X171352D01*
X171007Y181352D01*
X170739Y181094D01*
X170547Y180784D01*
X170394Y180267D01*
X170356Y179802D01*
X170432Y179337D01*
X170547Y179027D01*
X170777Y178717D01*
X171046Y178510D01*
X171314Y178407D01*
X171582D01*
X171851Y178510D01*
X172081Y178665D01*
X172272Y178872D01*
G01X174337Y178407D02*
X174414Y179079D01*
X174529Y179647D01*
X174682Y180164D01*
X174874Y180732D01*
X175181Y181507D01*
X173647D01*
G01X177437Y178407D02*
X177514Y179079D01*
X177629Y179647D01*
X177782Y180164D01*
X177974Y180732D01*
X178281Y181507D01*
X176747D01*
G01X179886Y180990D02*
X180116Y181300D01*
X180384Y181455D01*
X180691Y181507D01*
X181074Y181404D01*
X181342Y181145D01*
X181419Y180835D01*
X181381Y180525D01*
X181227Y180267D01*
X180461Y179750D01*
X180116Y179389D01*
X179886Y178872D01*
X179809Y178407D01*
X181419D01*
G01X172183Y177225D02*
X171953Y177380D01*
X171685Y177483D01*
X171378D01*
X171033Y177328D01*
X170765Y177070D01*
X170573Y176760D01*
X170420Y176243D01*
X170382Y175778D01*
X170458Y175313D01*
X170573Y175003D01*
X170803Y174693D01*
X171072Y174486D01*
X171340Y174383D01*
X171608D01*
X171877Y174486D01*
X172107Y174641D01*
X172298Y174848D01*
G01X174363Y174383D02*
X174440Y175055D01*
X174555Y175623D01*
X174708Y176140D01*
X174900Y176708D01*
X175207Y177483D01*
X173673D01*
G01X177463Y174383D02*
X177540Y175055D01*
X177655Y175623D01*
X177808Y176140D01*
X178000Y176708D01*
X178307Y177483D01*
X176773D01*
G01X179797Y175003D02*
X180027Y174641D01*
X180333Y174435D01*
X180678Y174383D01*
X180985Y174435D01*
X181292Y174693D01*
X181483Y175003D01*
X181522Y175313D01*
X181445Y175675D01*
X181177Y175933D01*
X180908Y176036D01*
X180563D01*
G01X180908D02*
X181138Y176191D01*
X181330Y176450D01*
X181407Y176760D01*
X181330Y177070D01*
X181138Y177328D01*
X180793Y177483D01*
X180448Y177431D01*
X180103Y177225D01*
G01X166700Y196270D02*
Y206010D01*
G01X174171Y194641D02*
X174016Y194411D01*
X173913Y194143D01*
Y193836D01*
X174068Y193491D01*
X174326Y193223D01*
X174636Y193031D01*
X175153Y192878D01*
X175618Y192840D01*
X176083Y192916D01*
X176393Y193031D01*
X176703Y193261D01*
X176910Y193530D01*
X177013Y193798D01*
Y194066D01*
X176910Y194335D01*
X176755Y194565D01*
X176548Y194756D01*
G01X175721Y196170D02*
X175360Y196438D01*
X175153Y196668D01*
X175050Y196975D01*
X175153Y197243D01*
X175360Y197435D01*
X175670Y197588D01*
X176031Y197626D01*
X176341Y197588D01*
X176651Y197435D01*
X176910Y197205D01*
X177013Y196936D01*
X176910Y196630D01*
X176600Y196361D01*
X176135Y196208D01*
X175618Y196170D01*
X174946Y196246D01*
X174585Y196361D01*
X174223Y196553D01*
X173965Y196821D01*
X173913Y197090D01*
X174016Y197358D01*
X174275Y197550D01*
G01X177013Y199998D02*
X173913D01*
X174533Y199538D01*
G01X177013D02*
Y200458D01*
G01Y203098D02*
X173913D01*
X174533Y202638D01*
G01X177013D02*
Y203558D01*
G01X169671Y194641D02*
X169516Y194411D01*
X169413Y194143D01*
Y193836D01*
X169568Y193491D01*
X169826Y193223D01*
X170136Y193031D01*
X170653Y192878D01*
X171118Y192840D01*
X171583Y192916D01*
X171893Y193031D01*
X172203Y193261D01*
X172410Y193530D01*
X172513Y193798D01*
Y194066D01*
X172410Y194335D01*
X172255Y194565D01*
X172048Y194756D01*
G01X171221Y196170D02*
X170860Y196438D01*
X170653Y196668D01*
X170550Y196975D01*
X170653Y197243D01*
X170860Y197435D01*
X171170Y197588D01*
X171531Y197626D01*
X171841Y197588D01*
X172151Y197435D01*
X172410Y197205D01*
X172513Y196936D01*
X172410Y196630D01*
X172100Y196361D01*
X171635Y196208D01*
X171118Y196170D01*
X170446Y196246D01*
X170085Y196361D01*
X169723Y196553D01*
X169465Y196821D01*
X169413Y197090D01*
X169516Y197358D01*
X169775Y197550D01*
G01X172513Y199998D02*
X169413D01*
X170033Y199538D01*
G01X172513D02*
Y200458D01*
G01Y203558D02*
X169413D01*
X171635Y202140D01*
Y204056D01*
G01X178671Y194608D02*
X178516Y194378D01*
X178413Y194110D01*
Y193803D01*
X178568Y193458D01*
X178826Y193190D01*
X179136Y192998D01*
X179653Y192845D01*
X180118Y192807D01*
X180583Y192883D01*
X180893Y192998D01*
X181203Y193228D01*
X181410Y193497D01*
X181513Y193765D01*
Y194033D01*
X181410Y194302D01*
X181255Y194532D01*
X181048Y194723D01*
G01X180221Y196137D02*
X179860Y196405D01*
X179653Y196635D01*
X179550Y196942D01*
X179653Y197210D01*
X179860Y197402D01*
X180170Y197555D01*
X180531Y197593D01*
X180841Y197555D01*
X181151Y197402D01*
X181410Y197172D01*
X181513Y196903D01*
X181410Y196597D01*
X181100Y196328D01*
X180635Y196175D01*
X180118Y196137D01*
X179446Y196213D01*
X179085Y196328D01*
X178723Y196520D01*
X178465Y196788D01*
X178413Y197057D01*
X178516Y197325D01*
X178775Y197517D01*
G01X178413Y199965D02*
X178516Y199658D01*
X178775Y199428D01*
X179085Y199275D01*
X179498Y199160D01*
X179963Y199122D01*
X180428Y199160D01*
X180841Y199275D01*
X181151Y199428D01*
X181410Y199658D01*
X181513Y199965D01*
X181410Y200272D01*
X181151Y200502D01*
X180841Y200655D01*
X180428Y200770D01*
X179963Y200808D01*
X179498Y200770D01*
X179085Y200655D01*
X178775Y200502D01*
X178516Y200272D01*
X178413Y199965D01*
G01X181513Y203065D02*
X181461Y203333D01*
X181306Y203640D01*
X181048Y203832D01*
X180686Y203908D01*
X180325Y203832D01*
X180015Y203602D01*
X179860Y203257D01*
Y202873D01*
X179756Y202643D01*
X179498Y202452D01*
X179136Y202375D01*
X178775Y202490D01*
X178516Y202758D01*
X178413Y203065D01*
X178516Y203372D01*
X178775Y203640D01*
X179136Y203755D01*
X179498Y203678D01*
X179756Y203487D01*
X179860Y203257D01*
Y202873D01*
X180015Y202528D01*
X180325Y202298D01*
X180686Y202222D01*
X181048Y202298D01*
X181306Y202490D01*
X181461Y202797D01*
X181513Y203065D01*
G01X166700Y206010D02*
X170290D01*
G01D02*
X197460D01*
G01X165542Y363339D02*
X165702Y363589D01*
X165889Y363714D01*
X166102Y363756D01*
X166369Y363673D01*
X166556Y363464D01*
X166609Y363214D01*
X166582Y362964D01*
X166476Y362756D01*
X165942Y362339D01*
X165702Y362048D01*
X165542Y361631D01*
X165489Y361256D01*
X166609D01*
G01X166962Y357256D02*
X167122Y356964D01*
X167336Y356798D01*
X167576Y356756D01*
X167789Y356798D01*
X168002Y357006D01*
X168136Y357256D01*
X168162Y357506D01*
X168109Y357798D01*
X167922Y358006D01*
X167736Y358089D01*
X167496D01*
G01X167736D02*
X167896Y358214D01*
X168029Y358423D01*
X168082Y358673D01*
X168029Y358923D01*
X167896Y359131D01*
X167656Y359256D01*
X167416Y359214D01*
X167176Y359048D01*
G01X169869Y361256D02*
Y363756D01*
X168882Y361964D01*
X170216D01*
G01X170462Y357131D02*
X170622Y356923D01*
X170809Y356798D01*
X171049Y356756D01*
X171289Y356839D01*
X171476Y357006D01*
X171609Y357298D01*
X171636Y357631D01*
X171582Y357964D01*
X171449Y358173D01*
X171262Y358339D01*
X171076Y358381D01*
X170889Y358339D01*
X170649Y358173D01*
X170729Y359256D01*
X171449D01*
G01X172542Y362298D02*
X172729Y362589D01*
X172889Y362756D01*
X173102Y362839D01*
X173289Y362756D01*
X173422Y362589D01*
X173529Y362339D01*
X173556Y362048D01*
X173529Y361798D01*
X173422Y361548D01*
X173262Y361339D01*
X173076Y361256D01*
X172862Y361339D01*
X172676Y361589D01*
X172569Y361964D01*
X172542Y362381D01*
X172596Y362923D01*
X172676Y363214D01*
X172809Y363506D01*
X172996Y363714D01*
X173182Y363756D01*
X173369Y363673D01*
X173502Y363464D01*
G01X175496Y356756D02*
X175549Y357298D01*
X175629Y357756D01*
X175736Y358173D01*
X175869Y358631D01*
X176082Y359256D01*
X175016D01*
G01X177049Y361256D02*
X177236Y361298D01*
X177449Y361423D01*
X177582Y361631D01*
X177636Y361923D01*
X177582Y362214D01*
X177422Y362464D01*
X177182Y362589D01*
X176916D01*
X176756Y362673D01*
X176622Y362881D01*
X176569Y363173D01*
X176649Y363464D01*
X176836Y363673D01*
X177049Y363756D01*
X177262Y363673D01*
X177449Y363464D01*
X177529Y363173D01*
X177476Y362881D01*
X177342Y362673D01*
X177182Y362589D01*
X176916D01*
X176676Y362464D01*
X176516Y362214D01*
X176462Y361923D01*
X176516Y361631D01*
X176649Y361423D01*
X176862Y361298D01*
X177049Y361256D01*
G01X179096Y357048D02*
X179282Y356839D01*
X179496Y356756D01*
X179709Y356839D01*
X179896Y357089D01*
X180029Y357464D01*
X180082Y357839D01*
Y358298D01*
X180029Y358673D01*
X179896Y359006D01*
X179736Y359173D01*
X179549Y359256D01*
X179336Y359173D01*
X179176Y359006D01*
X179069Y358756D01*
X179016Y358423D01*
X179069Y358131D01*
X179202Y357839D01*
X179362Y357673D01*
X179549Y357631D01*
X179762Y357714D01*
X179922Y357923D01*
X180082Y358298D01*
G01X180249Y361256D02*
Y363756D01*
X179929Y363256D01*
G01Y361256D02*
X180569D01*
G01X182449Y363756D02*
X182236Y363673D01*
X182076Y363464D01*
X181969Y363214D01*
X181889Y362881D01*
X181862Y362506D01*
X181889Y362131D01*
X181969Y361798D01*
X182076Y361548D01*
X182236Y361339D01*
X182449Y361256D01*
X182662Y361339D01*
X182822Y361548D01*
X182929Y361798D01*
X183009Y362131D01*
X183036Y362506D01*
X183009Y362881D01*
X182929Y363214D01*
X182822Y363464D01*
X182662Y363673D01*
X182449Y363756D01*
G01X178127Y387677D02*
X177972Y387447D01*
X177869Y387179D01*
Y386872D01*
X178024Y386527D01*
X178282Y386259D01*
X178592Y386067D01*
X179109Y385914D01*
X179574Y385876D01*
X180039Y385952D01*
X180349Y386067D01*
X180659Y386297D01*
X180866Y386566D01*
X180969Y386834D01*
Y387102D01*
X180866Y387371D01*
X180711Y387601D01*
X180504Y387792D01*
G01X180969Y389934D02*
X177869D01*
X178489Y389474D01*
G01X180969D02*
Y390394D01*
G01X180349Y392191D02*
X180711Y392421D01*
X180917Y392727D01*
X180969Y393072D01*
X180917Y393379D01*
X180659Y393686D01*
X180349Y393877D01*
X180039Y393916D01*
X179677Y393839D01*
X179419Y393571D01*
X179316Y393302D01*
Y392957D01*
G01Y393302D02*
X179161Y393532D01*
X178902Y393724D01*
X178592Y393801D01*
X178282Y393724D01*
X178024Y393532D01*
X177869Y393187D01*
X177921Y392842D01*
X178127Y392497D01*
G01X180607Y395482D02*
X180866Y395751D01*
X180969Y396057D01*
X180866Y396364D01*
X180556Y396632D01*
X180091Y396824D01*
X179626Y396901D01*
X179057D01*
X178592Y396824D01*
X178179Y396632D01*
X177972Y396402D01*
X177869Y396134D01*
X177972Y395827D01*
X178179Y395597D01*
X178489Y395444D01*
X178902Y395367D01*
X179264Y395444D01*
X179626Y395636D01*
X179832Y395866D01*
X179884Y396134D01*
X179781Y396441D01*
X179522Y396671D01*
X179057Y396901D01*
G01X170718Y394351D02*
X167618D01*
Y395310D01*
X167773Y395616D01*
X167980Y395808D01*
X168393Y395885D01*
X168806Y395808D01*
X169065Y395578D01*
X169220Y395310D01*
Y394351D01*
G01Y395310D02*
X170718Y395885D01*
G01Y398218D02*
X167618D01*
X168238Y397758D01*
G01X170718D02*
Y398678D01*
G01X170356Y400666D02*
X170615Y400935D01*
X170718Y401241D01*
X170615Y401548D01*
X170305Y401816D01*
X169840Y402008D01*
X169375Y402085D01*
X168806D01*
X168341Y402008D01*
X167928Y401816D01*
X167721Y401586D01*
X167618Y401318D01*
X167721Y401011D01*
X167928Y400781D01*
X168238Y400628D01*
X168651Y400551D01*
X169013Y400628D01*
X169375Y400820D01*
X169581Y401050D01*
X169633Y401318D01*
X169530Y401625D01*
X169271Y401855D01*
X168806Y402085D01*
G01X170718Y404418D02*
X170666Y404686D01*
X170511Y404993D01*
X170253Y405185D01*
X169891Y405261D01*
X169530Y405185D01*
X169220Y404955D01*
X169065Y404610D01*
Y404226D01*
X168961Y403996D01*
X168703Y403805D01*
X168341Y403728D01*
X167980Y403843D01*
X167721Y404111D01*
X167618Y404418D01*
X167721Y404725D01*
X167980Y404993D01*
X168341Y405108D01*
X168703Y405031D01*
X168961Y404840D01*
X169065Y404610D01*
Y404226D01*
X169220Y403881D01*
X169530Y403651D01*
X169891Y403575D01*
X170253Y403651D01*
X170511Y403843D01*
X170666Y404150D01*
X170718Y404418D01*
G01X180961Y400046D02*
X177761D01*
G01D02*
Y406246D01*
G01D02*
X180961D01*
G01X174841Y394271D02*
X171741D01*
Y395230D01*
X171896Y395536D01*
X172103Y395728D01*
X172516Y395805D01*
X172929Y395728D01*
X173188Y395498D01*
X173343Y395230D01*
Y394271D01*
G01Y395230D02*
X174841Y395805D01*
G01Y398138D02*
X171741D01*
X172361Y397678D01*
G01X174841D02*
Y398598D01*
G01X174479Y400586D02*
X174738Y400855D01*
X174841Y401161D01*
X174738Y401468D01*
X174428Y401736D01*
X173963Y401928D01*
X173498Y402005D01*
X172929D01*
X172464Y401928D01*
X172051Y401736D01*
X171844Y401506D01*
X171741Y401238D01*
X171844Y400931D01*
X172051Y400701D01*
X172361Y400548D01*
X172774Y400471D01*
X173136Y400548D01*
X173498Y400740D01*
X173704Y400970D01*
X173756Y401238D01*
X173653Y401545D01*
X173394Y401775D01*
X172929Y402005D01*
G01X174479Y403686D02*
X174738Y403955D01*
X174841Y404261D01*
X174738Y404568D01*
X174428Y404836D01*
X173963Y405028D01*
X173498Y405105D01*
X172929D01*
X172464Y405028D01*
X172051Y404836D01*
X171844Y404606D01*
X171741Y404338D01*
X171844Y404031D01*
X172051Y403801D01*
X172361Y403648D01*
X172774Y403571D01*
X173136Y403648D01*
X173498Y403840D01*
X173704Y404070D01*
X173756Y404338D01*
X173653Y404645D01*
X173394Y404875D01*
X172929Y405105D01*
G01X175042Y423369D02*
X175202Y423161D01*
X175389Y423036D01*
X175629Y422994D01*
X175869Y423077D01*
X176056Y423244D01*
X176189Y423536D01*
X176216Y423869D01*
X176162Y424202D01*
X176029Y424411D01*
X175842Y424577D01*
X175656Y424619D01*
X175469Y424577D01*
X175229Y424411D01*
X175309Y425494D01*
X176029D01*
G01X166261Y422621D02*
Y428821D01*
G01X169461D02*
Y422621D01*
G01D02*
X166261D01*
G01X170393Y416096D02*
Y422296D01*
G01X173593Y416096D02*
X170393D01*
G01X173593Y422296D02*
Y416096D01*
G01X170393Y422296D02*
X173593D01*
G01X177593Y416096D02*
X174393D01*
G01X177593Y422296D02*
Y416096D01*
G01X174393D02*
Y422296D01*
G01D02*
X177593D01*
G01X168852Y410417D02*
X165752D01*
Y411337D01*
X165907Y411644D01*
X166269Y411874D01*
X166682Y411951D01*
X167095Y411874D01*
X167405Y411682D01*
X167560Y411337D01*
Y410417D01*
G01X168232Y413517D02*
X168542Y413709D01*
X168749Y413939D01*
X168852Y414207D01*
X168749Y414514D01*
X168542Y414744D01*
X168232Y414974D01*
X167819Y415051D01*
X165752D01*
G01X166269Y416656D02*
X165959Y416886D01*
X165804Y417154D01*
X165752Y417461D01*
X165855Y417844D01*
X166114Y418112D01*
X166424Y418189D01*
X166734Y418151D01*
X166992Y417997D01*
X167509Y417231D01*
X167870Y416886D01*
X168387Y416656D01*
X168852Y416579D01*
Y418189D01*
G01X173342Y439904D02*
Y442404D01*
X173022Y441904D01*
G01Y439904D02*
X173662D01*
G01X175035Y440946D02*
X175222Y441237D01*
X175382Y441404D01*
X175595Y441487D01*
X175782Y441404D01*
X175915Y441237D01*
X176022Y440987D01*
X176049Y440696D01*
X176022Y440446D01*
X175915Y440196D01*
X175755Y439987D01*
X175569Y439904D01*
X175355Y439987D01*
X175169Y440237D01*
X175062Y440612D01*
X175035Y441029D01*
X175089Y441571D01*
X175169Y441862D01*
X175302Y442154D01*
X175489Y442362D01*
X175675Y442404D01*
X175862Y442321D01*
X175995Y442112D01*
G01X174345Y439185D02*
Y437084D01*
G01X176346Y439185D02*
X174345D01*
G01Y428684D02*
Y426783D01*
G01D02*
X176246D01*
G01X177593Y424937D02*
Y423737D01*
G01X169122Y434121D02*
Y430921D01*
G01X166022Y431021D02*
Y434021D01*
G01X166261Y428821D02*
X169461D01*
G01X166361Y425721D02*
X169361D01*
G01X168920Y438434D02*
Y435234D01*
G01X179539Y442237D02*
Y441037D01*
G01X166349Y442577D02*
Y439577D01*
G01X169449Y442677D02*
Y439477D01*
G01X178555Y450106D02*
X175455D01*
Y451026D01*
X175610Y451333D01*
X175972Y451563D01*
X176385Y451640D01*
X176798Y451563D01*
X177108Y451371D01*
X177263Y451026D01*
Y450106D01*
G01X175713Y454816D02*
X175558Y454586D01*
X175455Y454318D01*
Y454011D01*
X175610Y453666D01*
X175868Y453398D01*
X176178Y453206D01*
X176695Y453053D01*
X177160Y453015D01*
X177625Y453091D01*
X177935Y453206D01*
X178245Y453436D01*
X178452Y453705D01*
X178555Y453973D01*
Y454241D01*
X178452Y454510D01*
X178297Y454740D01*
X178090Y454931D01*
G01X178555Y457073D02*
X175455D01*
X176075Y456613D01*
G01X178555D02*
Y457533D01*
G01Y460633D02*
X175455D01*
X177677Y459215D01*
Y461131D01*
G01X171570Y443139D02*
Y446339D01*
G01X177770Y443139D02*
X171570D01*
G01X177770Y446339D02*
Y443139D01*
G01X171570Y446339D02*
X177770D01*
G01X174670Y443239D02*
Y446239D01*
G01X169449Y446634D02*
Y443434D01*
G01X175520Y470710D02*
X175290Y470865D01*
X175022Y470968D01*
X174715D01*
X174370Y470813D01*
X174102Y470555D01*
X173910Y470245D01*
X173757Y469728D01*
X173719Y469263D01*
X173795Y468798D01*
X173910Y468488D01*
X174140Y468178D01*
X174409Y467971D01*
X174677Y467868D01*
X174945D01*
X175214Y467971D01*
X175444Y468126D01*
X175635Y468333D01*
G01X177049Y470451D02*
X177279Y470761D01*
X177547Y470916D01*
X177854Y470968D01*
X178237Y470865D01*
X178505Y470606D01*
X178582Y470296D01*
X178544Y469986D01*
X178390Y469728D01*
X177624Y469211D01*
X177279Y468850D01*
X177049Y468333D01*
X176972Y467868D01*
X178582D01*
G01X181337D02*
Y470968D01*
X179919Y468746D01*
X181835D01*
G01X183900Y467868D02*
X183977Y468540D01*
X184092Y469108D01*
X184245Y469625D01*
X184437Y470193D01*
X184744Y470968D01*
X183210D01*
G01X173910Y463368D02*
Y466468D01*
X174869D01*
X175175Y466313D01*
X175367Y466106D01*
X175444Y465693D01*
X175367Y465280D01*
X175137Y465021D01*
X174869Y464866D01*
X173910D01*
G01X174869D02*
X175444Y463368D01*
G01X176934Y463988D02*
X177164Y463626D01*
X177470Y463420D01*
X177815Y463368D01*
X178122Y463420D01*
X178429Y463678D01*
X178620Y463988D01*
X178659Y464298D01*
X178582Y464660D01*
X178314Y464918D01*
X178045Y465021D01*
X177700D01*
G01X178045D02*
X178275Y465176D01*
X178467Y465435D01*
X178544Y465745D01*
X178467Y466055D01*
X178275Y466313D01*
X177930Y466468D01*
X177585Y466416D01*
X177240Y466210D01*
G01X180877Y463368D02*
Y466468D01*
X180417Y465848D01*
G01Y463368D02*
X181337D01*
G01X183977D02*
Y466468D01*
X183517Y465848D01*
G01Y463368D02*
X184437D01*
G01X178681Y480705D02*
X184381D01*
G01X177681Y482305D02*
X178681Y480705D01*
G01X176681D02*
X177681Y482305D01*
G01X170981Y480705D02*
X176681D01*
G01X170981D02*
Y489505D01*
G01X174229Y476290D02*
Y479290D01*
G01X171129Y476190D02*
Y479390D01*
G01X177329Y476190D02*
X171129D01*
G01X177329Y479390D02*
Y476190D01*
G01X171129Y479390D02*
X177329D01*
G01X175520Y474710D02*
X175290Y474865D01*
X175022Y474968D01*
X174715D01*
X174370Y474813D01*
X174102Y474555D01*
X173910Y474245D01*
X173757Y473728D01*
X173719Y473263D01*
X173795Y472798D01*
X173910Y472488D01*
X174140Y472178D01*
X174409Y471971D01*
X174677Y471868D01*
X174945D01*
X175214Y471971D01*
X175444Y472126D01*
X175635Y472333D01*
G01X177049Y474451D02*
X177279Y474761D01*
X177547Y474916D01*
X177854Y474968D01*
X178237Y474865D01*
X178505Y474606D01*
X178582Y474296D01*
X178544Y473986D01*
X178390Y473728D01*
X177624Y473211D01*
X177279Y472850D01*
X177049Y472333D01*
X176972Y471868D01*
X178582D01*
G01X181337D02*
Y474968D01*
X179919Y472746D01*
X181835D01*
G01X183249Y473160D02*
X183517Y473521D01*
X183747Y473728D01*
X184054Y473831D01*
X184322Y473728D01*
X184514Y473521D01*
X184667Y473211D01*
X184705Y472850D01*
X184667Y472540D01*
X184514Y472230D01*
X184284Y471971D01*
X184015Y471868D01*
X183709Y471971D01*
X183440Y472281D01*
X183287Y472746D01*
X183249Y473263D01*
X183325Y473935D01*
X183440Y474296D01*
X183632Y474658D01*
X183900Y474916D01*
X184169Y474968D01*
X184437Y474865D01*
X184629Y474606D01*
G01X168246Y483013D02*
X165046D01*
G01X168246Y489213D02*
Y483013D01*
G01X165046D02*
Y489213D01*
G01X170981Y489505D02*
X184381D01*
G01X165046Y489213D02*
X168246D01*
G01X172631Y560611D02*
X172899Y560972D01*
X173129Y561179D01*
X173436Y561282D01*
X173704Y561179D01*
X173896Y560972D01*
X174049Y560662D01*
X174087Y560301D01*
X174049Y559991D01*
X173896Y559681D01*
X173666Y559422D01*
X173397Y559319D01*
X173091Y559422D01*
X172822Y559732D01*
X172669Y560197D01*
X172631Y560714D01*
X172707Y561386D01*
X172822Y561747D01*
X173014Y562109D01*
X173282Y562367D01*
X173551Y562419D01*
X173819Y562316D01*
X174011Y562057D01*
G01X167519Y559319D02*
Y562419D01*
X166101Y560197D01*
X168017D01*
G01X169366Y564284D02*
X169596Y564026D01*
X169864Y563871D01*
X170209Y563819D01*
X170554Y563922D01*
X170822Y564129D01*
X171014Y564491D01*
X171052Y564904D01*
X170976Y565317D01*
X170784Y565576D01*
X170516Y565782D01*
X170247Y565834D01*
X169979Y565782D01*
X169634Y565576D01*
X169749Y566919D01*
X170784D01*
G01X176431Y563819D02*
X176508Y564491D01*
X176623Y565059D01*
X176776Y565576D01*
X176968Y566144D01*
X177275Y566919D01*
X175741D01*
G01X179658Y559319D02*
X179926Y559371D01*
X180233Y559526D01*
X180425Y559784D01*
X180501Y560146D01*
X180425Y560507D01*
X180195Y560817D01*
X179850Y560972D01*
X179466D01*
X179236Y561076D01*
X179045Y561334D01*
X178968Y561696D01*
X179083Y562057D01*
X179351Y562316D01*
X179658Y562419D01*
X179965Y562316D01*
X180233Y562057D01*
X180348Y561696D01*
X180271Y561334D01*
X180080Y561076D01*
X179850Y560972D01*
X179466D01*
X179121Y560817D01*
X178891Y560507D01*
X178815Y560146D01*
X178891Y559784D01*
X179083Y559526D01*
X179390Y559371D01*
X179658Y559319D01*
G01X164263Y577133D02*
Y570933D01*
G01X180863Y571033D02*
X177663D01*
G01D02*
Y577233D01*
G01D02*
X180863D01*
G01X172530Y577235D02*
Y571035D01*
G01D02*
X169330D01*
G01D02*
Y577235D01*
G01D02*
X172530D01*
G01X165063Y570933D02*
Y577133D01*
G01X168263D02*
Y570933D01*
G01D02*
X165063D01*
G01Y577133D02*
X168263D01*
G01X176863Y577233D02*
Y571033D01*
G01D02*
X173663D01*
G01D02*
Y577233D01*
G01D02*
X176863D01*
G01X170590Y581990D02*
X201020D01*
G01X170590Y585060D02*
Y581990D01*
G01X168573Y589433D02*
Y587433D01*
G01X178416Y589433D02*
Y585433D01*
G01X168573Y630433D02*
Y632433D01*
G01X176447Y630433D02*
Y634433D01*
G01X175408Y639201D02*
X175178Y639356D01*
X174910Y639459D01*
X174603D01*
X174258Y639304D01*
X173990Y639046D01*
X173798Y638736D01*
X173645Y638219D01*
X173607Y637754D01*
X173683Y637289D01*
X173798Y636979D01*
X174028Y636669D01*
X174297Y636462D01*
X174565Y636359D01*
X174833D01*
X175102Y636462D01*
X175332Y636617D01*
X175523Y636824D01*
G01X178125Y636359D02*
Y639459D01*
X176707Y637237D01*
X178623D01*
G01X180765Y639459D02*
X180458Y639356D01*
X180228Y639097D01*
X180075Y638787D01*
X179960Y638374D01*
X179922Y637909D01*
X179960Y637444D01*
X180075Y637031D01*
X180228Y636721D01*
X180458Y636462D01*
X180765Y636359D01*
X181072Y636462D01*
X181302Y636721D01*
X181455Y637031D01*
X181570Y637444D01*
X181608Y637909D01*
X181570Y638374D01*
X181455Y638787D01*
X181302Y639097D01*
X181072Y639356D01*
X180765Y639459D01*
G01X183865D02*
X183558Y639356D01*
X183328Y639097D01*
X183175Y638787D01*
X183060Y638374D01*
X183022Y637909D01*
X183060Y637444D01*
X183175Y637031D01*
X183328Y636721D01*
X183558Y636462D01*
X183865Y636359D01*
X184172Y636462D01*
X184402Y636721D01*
X184555Y637031D01*
X184670Y637444D01*
X184708Y637909D01*
X184670Y638374D01*
X184555Y638787D01*
X184402Y639097D01*
X184172Y639356D01*
X183865Y639459D01*
G01X178563Y642333D02*
X172363D01*
G01D02*
Y645533D01*
G01X178563D02*
Y642333D01*
G01X175463Y645433D02*
Y642433D01*
G01X164863Y642333D02*
Y645533D01*
G01X171063D02*
Y642333D01*
G01D02*
X164863D01*
G01X167963Y642433D02*
Y645433D01*
G01X172363Y645533D02*
X178563D01*
G01X164863D02*
X171063D01*
G01X167920Y675390D02*
Y692510D01*
G01X182520Y675390D02*
X167920D01*
G01X166412Y671049D02*
Y664849D01*
G01X165654Y661732D02*
X165867Y661524D01*
X166107Y661399D01*
X166321D01*
X166534Y661524D01*
X166694Y661732D01*
X166774Y662024D01*
X166721Y662316D01*
X166587Y662566D01*
X166347Y662732D01*
X166027Y662816D01*
X165841Y662982D01*
X165761Y663274D01*
X165814Y663566D01*
X165947Y663774D01*
X166134Y663899D01*
X166321D01*
X166507Y663816D01*
X166667Y663607D01*
G01X167519Y674316D02*
X182519D01*
G01X167519Y661316D02*
Y674316D01*
G01X182519Y661316D02*
X167519D01*
G01X166691Y678375D02*
X167224D01*
Y677625D01*
X167064Y677375D01*
X166878Y677208D01*
X166611Y677125D01*
X166344Y677208D01*
X166158Y677375D01*
X165998Y677625D01*
X165891Y677917D01*
X165838Y678250D01*
Y678542D01*
X165891Y678792D01*
X165998Y679083D01*
X166158Y679333D01*
X166318Y679500D01*
X166531Y679625D01*
X166718D01*
X166931Y679542D01*
X167091Y679375D01*
G01X168680Y676429D02*
Y691429D01*
G01X181680Y676429D02*
X168680D01*
G01X170030Y692510D02*
Y711740D01*
G01X167920Y692510D02*
X170030D01*
G01X174044Y707476D02*
Y704476D01*
G01X177144Y707576D02*
Y704376D01*
G01X170944D02*
Y707576D01*
G01X177144Y704376D02*
X170944D01*
G01X174044Y703476D02*
Y700476D01*
G01X177144Y703576D02*
Y700376D01*
G01X170944D02*
Y703576D01*
G01X177144Y700376D02*
X170944D01*
G01Y703576D02*
X177144D01*
G01X174044Y699476D02*
Y696476D01*
G01X177144Y699576D02*
Y696376D01*
G01X170944Y699576D02*
X177144D01*
G01X170944Y696376D02*
Y699576D01*
G01X177144Y696376D02*
X170944D01*
G01X173614Y695640D02*
X179814D01*
G01X173614Y692440D02*
Y695640D01*
G01X179814Y692440D02*
X173614D01*
G01X179814Y695640D02*
Y692440D01*
G01X171351Y692123D02*
Y694623D01*
X171885D01*
X172098Y694498D01*
X172258Y694331D01*
X172391Y694081D01*
X172498Y693790D01*
X172525Y693373D01*
X172498Y692956D01*
X172391Y692665D01*
X172258Y692415D01*
X172098Y692248D01*
X171885Y692123D01*
X171351D01*
G01X168680Y691429D02*
X181680D01*
G01X179051Y707135D02*
X179264Y706927D01*
X179504Y706802D01*
X179718D01*
X179931Y706927D01*
X180091Y707135D01*
X180171Y707427D01*
X180118Y707719D01*
X179984Y707969D01*
X179744Y708135D01*
X179424Y708219D01*
X179238Y708385D01*
X179158Y708677D01*
X179211Y708969D01*
X179344Y709177D01*
X179531Y709302D01*
X179718D01*
X179904Y709219D01*
X180064Y709010D01*
G01X178800Y711780D02*
X183090D01*
G01X170030Y711740D02*
X169940D01*
G01X174044Y711476D02*
Y708476D01*
G01X177144Y711576D02*
Y708376D01*
G01X170944Y711576D02*
X177144D01*
G01X170944Y708376D02*
Y711576D01*
G01X177144Y708376D02*
X170944D01*
G01Y707576D02*
X177144D01*
G01X167664Y742389D02*
Y716989D01*
G01X167143Y713468D02*
Y715968D01*
X167677D01*
X167890Y715843D01*
X168050Y715676D01*
X168183Y715426D01*
X168290Y715135D01*
X168317Y714718D01*
X168290Y714301D01*
X168183Y714010D01*
X168050Y713760D01*
X167890Y713593D01*
X167677Y713468D01*
X167143D01*
G01X169189Y712573D02*
Y727573D01*
G01X182189Y712573D02*
X169189D01*
G01X178503Y732021D02*
Y729021D01*
G01X175403Y732121D02*
X181603D01*
G01X175403Y728921D02*
Y732121D01*
G01X181603Y728921D02*
X175403D01*
G01X174055Y731250D02*
X170855D01*
G01X174055Y737450D02*
Y731250D01*
G01X170855Y737450D02*
X174055D01*
G01X170855Y731250D02*
Y737450D01*
G01X171963Y741689D02*
Y739467D01*
X172116Y739002D01*
X172423Y738692D01*
X172806Y738589D01*
X173189Y738692D01*
X173496Y739002D01*
X173649Y739467D01*
Y741689D01*
G01X175254Y738951D02*
X175523Y738692D01*
X175829Y738589D01*
X176136Y738692D01*
X176404Y739002D01*
X176596Y739467D01*
X176673Y739932D01*
Y740501D01*
X176596Y740966D01*
X176404Y741379D01*
X176174Y741586D01*
X175906Y741689D01*
X175599Y741586D01*
X175369Y741379D01*
X175216Y741069D01*
X175139Y740656D01*
X175216Y740294D01*
X175408Y739932D01*
X175638Y739726D01*
X175906Y739674D01*
X176213Y739777D01*
X176443Y740036D01*
X176673Y740501D01*
G01X178163Y739209D02*
X178393Y738847D01*
X178699Y738641D01*
X179044Y738589D01*
X179351Y738641D01*
X179658Y738899D01*
X179849Y739209D01*
X179888Y739519D01*
X179811Y739881D01*
X179543Y740139D01*
X179274Y740242D01*
X178929D01*
G01X179274D02*
X179504Y740397D01*
X179696Y740656D01*
X179773Y740966D01*
X179696Y741276D01*
X179504Y741534D01*
X179159Y741689D01*
X178814Y741637D01*
X178469Y741431D01*
G01X173563Y728979D02*
X174096D01*
Y728229D01*
X173936Y727979D01*
X173750Y727812D01*
X173483Y727729D01*
X173216Y727812D01*
X173030Y727979D01*
X172870Y728229D01*
X172763Y728521D01*
X172710Y728854D01*
Y729146D01*
X172763Y729396D01*
X172870Y729687D01*
X173030Y729937D01*
X173190Y730104D01*
X173403Y730229D01*
X173590D01*
X173803Y730146D01*
X173963Y729979D01*
G01X168585Y728986D02*
X168798Y728778D01*
X169038Y728653D01*
X169252D01*
X169465Y728778D01*
X169625Y728986D01*
X169705Y729278D01*
X169652Y729570D01*
X169518Y729820D01*
X169278Y729986D01*
X168958Y730070D01*
X168772Y730236D01*
X168692Y730528D01*
X168745Y730820D01*
X168878Y731028D01*
X169065Y731153D01*
X169252D01*
X169438Y731070D01*
X169598Y730861D01*
G01X169189Y727573D02*
X182189D01*
G01X177460Y744883D02*
X177305Y744653D01*
X177202Y744385D01*
Y744078D01*
X177357Y743733D01*
X177615Y743465D01*
X177925Y743273D01*
X178442Y743120D01*
X178907Y743082D01*
X179372Y743158D01*
X179682Y743273D01*
X179992Y743503D01*
X180199Y743772D01*
X180302Y744040D01*
Y744308D01*
X180199Y744577D01*
X180044Y744807D01*
X179837Y744998D01*
G01X179010Y746412D02*
X178649Y746680D01*
X178442Y746910D01*
X178339Y747217D01*
X178442Y747485D01*
X178649Y747677D01*
X178959Y747830D01*
X179320Y747868D01*
X179630Y747830D01*
X179940Y747677D01*
X180199Y747447D01*
X180302Y747178D01*
X180199Y746872D01*
X179889Y746603D01*
X179424Y746450D01*
X178907Y746412D01*
X178235Y746488D01*
X177874Y746603D01*
X177512Y746795D01*
X177254Y747063D01*
X177202Y747332D01*
X177305Y747600D01*
X177564Y747792D01*
G01X177202Y750240D02*
X177305Y749933D01*
X177564Y749703D01*
X177874Y749550D01*
X178287Y749435D01*
X178752Y749397D01*
X179217Y749435D01*
X179630Y749550D01*
X179940Y749703D01*
X180199Y749933D01*
X180302Y750240D01*
X180199Y750547D01*
X179940Y750777D01*
X179630Y750930D01*
X179217Y751045D01*
X178752Y751083D01*
X178287Y751045D01*
X177874Y750930D01*
X177564Y750777D01*
X177305Y750547D01*
X177202Y750240D01*
G01X180302Y753800D02*
X177202D01*
X179424Y752382D01*
Y754298D01*
G01X174805Y744555D02*
X171705D01*
Y745514D01*
X171860Y745820D01*
X172067Y746012D01*
X172480Y746089D01*
X172893Y746012D01*
X173152Y745782D01*
X173307Y745514D01*
Y744555D01*
G01Y745514D02*
X174805Y746089D01*
G01Y748422D02*
X171705D01*
X172325Y747962D01*
G01X174805D02*
Y748882D01*
G01X171705Y751522D02*
X171808Y751215D01*
X172067Y750985D01*
X172377Y750832D01*
X172790Y750717D01*
X173255Y750679D01*
X173720Y750717D01*
X174133Y750832D01*
X174443Y750985D01*
X174702Y751215D01*
X174805Y751522D01*
X174702Y751829D01*
X174443Y752059D01*
X174133Y752212D01*
X173720Y752327D01*
X173255Y752365D01*
X172790Y752327D01*
X172377Y752212D01*
X172067Y752059D01*
X171808Y751829D01*
X171705Y751522D01*
G01Y754622D02*
X171808Y754315D01*
X172067Y754085D01*
X172377Y753932D01*
X172790Y753817D01*
X173255Y753779D01*
X173720Y753817D01*
X174133Y753932D01*
X174443Y754085D01*
X174702Y754315D01*
X174805Y754622D01*
X174702Y754929D01*
X174443Y755159D01*
X174133Y755312D01*
X173720Y755427D01*
X173255Y755465D01*
X172790Y755427D01*
X172377Y755312D01*
X172067Y755159D01*
X171808Y754929D01*
X171705Y754622D01*
G01X174805Y757645D02*
X174133Y757722D01*
X173565Y757837D01*
X173048Y757990D01*
X172480Y758182D01*
X171705Y758489D01*
Y756955D01*
G01X195150Y1570D02*
Y27790D01*
G01X186311Y8635D02*
Y26035D01*
G01X193711D02*
Y8635D01*
G01D02*
X186311D01*
G01X185282Y25845D02*
Y8445D01*
G01X186311Y26035D02*
X193711D01*
G01X186311Y17335D02*
X193711D01*
G01X214579Y29974D02*
X181779D01*
G01D02*
Y56352D01*
G01X182273Y58206D02*
Y61306D01*
X183193D01*
X183500Y61151D01*
X183730Y60789D01*
X183807Y60376D01*
X183730Y59963D01*
X183538Y59653D01*
X183193Y59498D01*
X182273D01*
G01X185373Y61306D02*
Y58206D01*
X186907D01*
G01X189163D02*
X189240Y58878D01*
X189355Y59446D01*
X189508Y59963D01*
X189700Y60531D01*
X190007Y61306D01*
X188473D01*
G01X181779Y56352D02*
X214579D01*
G01X183673Y129768D02*
X180573D01*
Y130727D01*
X180728Y131033D01*
X180935Y131225D01*
X181348Y131302D01*
X181761Y131225D01*
X182020Y130995D01*
X182175Y130727D01*
Y129768D01*
G01Y130727D02*
X183673Y131302D01*
G01X183208Y132792D02*
X183466Y133022D01*
X183621Y133290D01*
X183673Y133635D01*
X183570Y133980D01*
X183363Y134248D01*
X183001Y134440D01*
X182588Y134478D01*
X182175Y134402D01*
X181916Y134210D01*
X181710Y133942D01*
X181658Y133673D01*
X181710Y133405D01*
X181916Y133060D01*
X180573Y133175D01*
Y134210D01*
G01X183673Y137195D02*
X180573D01*
X182795Y135777D01*
Y137693D01*
G01X180573Y139835D02*
X180676Y139528D01*
X180935Y139298D01*
X181245Y139145D01*
X181658Y139030D01*
X182123Y138992D01*
X182588Y139030D01*
X183001Y139145D01*
X183311Y139298D01*
X183570Y139528D01*
X183673Y139835D01*
X183570Y140142D01*
X183311Y140372D01*
X183001Y140525D01*
X182588Y140640D01*
X182123Y140678D01*
X181658Y140640D01*
X181245Y140525D01*
X180935Y140372D01*
X180676Y140142D01*
X180573Y139835D01*
G01X193573Y129768D02*
X190473D01*
Y130727D01*
X190628Y131033D01*
X190835Y131225D01*
X191248Y131302D01*
X191661Y131225D01*
X191920Y130995D01*
X192075Y130727D01*
Y129768D01*
G01Y130727D02*
X193573Y131302D01*
G01X193108Y132792D02*
X193366Y133022D01*
X193521Y133290D01*
X193573Y133635D01*
X193470Y133980D01*
X193263Y134248D01*
X192901Y134440D01*
X192488Y134478D01*
X192075Y134402D01*
X191816Y134210D01*
X191610Y133942D01*
X191558Y133673D01*
X191610Y133405D01*
X191816Y133060D01*
X190473Y133175D01*
Y134210D01*
G01X192953Y135892D02*
X193315Y136122D01*
X193521Y136428D01*
X193573Y136773D01*
X193521Y137080D01*
X193263Y137387D01*
X192953Y137578D01*
X192643Y137617D01*
X192281Y137540D01*
X192023Y137272D01*
X191920Y137003D01*
Y136658D01*
G01Y137003D02*
X191765Y137233D01*
X191506Y137425D01*
X191196Y137502D01*
X190886Y137425D01*
X190628Y137233D01*
X190473Y136888D01*
X190525Y136543D01*
X190731Y136198D01*
G01X193211Y139183D02*
X193470Y139452D01*
X193573Y139758D01*
X193470Y140065D01*
X193160Y140333D01*
X192695Y140525D01*
X192230Y140602D01*
X191661D01*
X191196Y140525D01*
X190783Y140333D01*
X190576Y140103D01*
X190473Y139835D01*
X190576Y139528D01*
X190783Y139298D01*
X191093Y139145D01*
X191506Y139068D01*
X191868Y139145D01*
X192230Y139337D01*
X192436Y139567D01*
X192488Y139835D01*
X192385Y140142D01*
X192126Y140372D01*
X191661Y140602D01*
G01X188423Y129768D02*
X185323D01*
Y130727D01*
X185478Y131033D01*
X185685Y131225D01*
X186098Y131302D01*
X186511Y131225D01*
X186770Y130995D01*
X186925Y130727D01*
Y129768D01*
G01Y130727D02*
X188423Y131302D01*
G01X187958Y132792D02*
X188216Y133022D01*
X188371Y133290D01*
X188423Y133635D01*
X188320Y133980D01*
X188113Y134248D01*
X187751Y134440D01*
X187338Y134478D01*
X186925Y134402D01*
X186666Y134210D01*
X186460Y133942D01*
X186408Y133673D01*
X186460Y133405D01*
X186666Y133060D01*
X185323Y133175D01*
Y134210D01*
G01X187803Y135892D02*
X188165Y136122D01*
X188371Y136428D01*
X188423Y136773D01*
X188371Y137080D01*
X188113Y137387D01*
X187803Y137578D01*
X187493Y137617D01*
X187131Y137540D01*
X186873Y137272D01*
X186770Y137003D01*
Y136658D01*
G01Y137003D02*
X186615Y137233D01*
X186356Y137425D01*
X186046Y137502D01*
X185736Y137425D01*
X185478Y137233D01*
X185323Y136888D01*
X185375Y136543D01*
X185581Y136198D01*
G01X188423Y139835D02*
X188371Y140103D01*
X188216Y140410D01*
X187958Y140602D01*
X187596Y140678D01*
X187235Y140602D01*
X186925Y140372D01*
X186770Y140027D01*
Y139643D01*
X186666Y139413D01*
X186408Y139222D01*
X186046Y139145D01*
X185685Y139260D01*
X185426Y139528D01*
X185323Y139835D01*
X185426Y140142D01*
X185685Y140410D01*
X186046Y140525D01*
X186408Y140448D01*
X186666Y140257D01*
X186770Y140027D01*
Y139643D01*
X186925Y139298D01*
X187235Y139068D01*
X187596Y138992D01*
X187958Y139068D01*
X188216Y139260D01*
X188371Y139567D01*
X188423Y139835D01*
G01X187324Y157195D02*
X187094Y157350D01*
X186826Y157453D01*
X186519D01*
X186174Y157298D01*
X185906Y157040D01*
X185714Y156730D01*
X185561Y156213D01*
X185523Y155748D01*
X185599Y155283D01*
X185714Y154973D01*
X185944Y154663D01*
X186213Y154456D01*
X186481Y154353D01*
X186749D01*
X187018Y154456D01*
X187248Y154611D01*
X187439Y154818D01*
G01X188853Y155645D02*
X189121Y156006D01*
X189351Y156213D01*
X189658Y156316D01*
X189926Y156213D01*
X190118Y156006D01*
X190271Y155696D01*
X190309Y155335D01*
X190271Y155025D01*
X190118Y154715D01*
X189888Y154456D01*
X189619Y154353D01*
X189313Y154456D01*
X189044Y154766D01*
X188891Y155231D01*
X188853Y155748D01*
X188929Y156420D01*
X189044Y156781D01*
X189236Y157143D01*
X189504Y157401D01*
X189773Y157453D01*
X190041Y157350D01*
X190233Y157091D01*
G01X191953Y156936D02*
X192183Y157246D01*
X192451Y157401D01*
X192758Y157453D01*
X193141Y157350D01*
X193409Y157091D01*
X193486Y156781D01*
X193448Y156471D01*
X193294Y156213D01*
X192528Y155696D01*
X192183Y155335D01*
X191953Y154818D01*
X191876Y154353D01*
X193486D01*
G01X195781Y157453D02*
X195474Y157350D01*
X195244Y157091D01*
X195091Y156781D01*
X194976Y156368D01*
X194938Y155903D01*
X194976Y155438D01*
X195091Y155025D01*
X195244Y154715D01*
X195474Y154456D01*
X195781Y154353D01*
X196088Y154456D01*
X196318Y154715D01*
X196471Y155025D01*
X196586Y155438D01*
X196624Y155903D01*
X196586Y156368D01*
X196471Y156781D01*
X196318Y157091D01*
X196088Y157350D01*
X195781Y157453D01*
G01X184293Y142398D02*
X181193D01*
Y143357D01*
X181348Y143663D01*
X181555Y143855D01*
X181968Y143932D01*
X182381Y143855D01*
X182640Y143625D01*
X182795Y143357D01*
Y142398D01*
G01Y143357D02*
X184293Y143932D01*
G01X183828Y145422D02*
X184086Y145652D01*
X184241Y145920D01*
X184293Y146265D01*
X184190Y146610D01*
X183983Y146878D01*
X183621Y147070D01*
X183208Y147108D01*
X182795Y147032D01*
X182536Y146840D01*
X182330Y146572D01*
X182278Y146303D01*
X182330Y146035D01*
X182536Y145690D01*
X181193Y145805D01*
Y146840D01*
G01X183001Y148637D02*
X182640Y148905D01*
X182433Y149135D01*
X182330Y149442D01*
X182433Y149710D01*
X182640Y149902D01*
X182950Y150055D01*
X183311Y150093D01*
X183621Y150055D01*
X183931Y149902D01*
X184190Y149672D01*
X184293Y149403D01*
X184190Y149097D01*
X183880Y148828D01*
X183415Y148675D01*
X182898Y148637D01*
X182226Y148713D01*
X181865Y148828D01*
X181503Y149020D01*
X181245Y149288D01*
X181193Y149557D01*
X181296Y149825D01*
X181555Y150017D01*
G01X181710Y151737D02*
X181400Y151967D01*
X181245Y152235D01*
X181193Y152542D01*
X181296Y152925D01*
X181555Y153193D01*
X181865Y153270D01*
X182175Y153232D01*
X182433Y153078D01*
X182950Y152312D01*
X183311Y151967D01*
X183828Y151737D01*
X184293Y151660D01*
Y153270D01*
G01X193293Y142398D02*
X190193D01*
Y143357D01*
X190348Y143663D01*
X190555Y143855D01*
X190968Y143932D01*
X191381Y143855D01*
X191640Y143625D01*
X191795Y143357D01*
Y142398D01*
G01Y143357D02*
X193293Y143932D01*
G01X192828Y145422D02*
X193086Y145652D01*
X193241Y145920D01*
X193293Y146265D01*
X193190Y146610D01*
X192983Y146878D01*
X192621Y147070D01*
X192208Y147108D01*
X191795Y147032D01*
X191536Y146840D01*
X191330Y146572D01*
X191278Y146303D01*
X191330Y146035D01*
X191536Y145690D01*
X190193Y145805D01*
Y146840D01*
G01X192001Y148637D02*
X191640Y148905D01*
X191433Y149135D01*
X191330Y149442D01*
X191433Y149710D01*
X191640Y149902D01*
X191950Y150055D01*
X192311Y150093D01*
X192621Y150055D01*
X192931Y149902D01*
X193190Y149672D01*
X193293Y149403D01*
X193190Y149097D01*
X192880Y148828D01*
X192415Y148675D01*
X191898Y148637D01*
X191226Y148713D01*
X190865Y148828D01*
X190503Y149020D01*
X190245Y149288D01*
X190193Y149557D01*
X190296Y149825D01*
X190555Y150017D01*
G01X192673Y151622D02*
X193035Y151852D01*
X193241Y152158D01*
X193293Y152503D01*
X193241Y152810D01*
X192983Y153117D01*
X192673Y153308D01*
X192363Y153347D01*
X192001Y153270D01*
X191743Y153002D01*
X191640Y152733D01*
Y152388D01*
G01Y152733D02*
X191485Y152963D01*
X191226Y153155D01*
X190916Y153232D01*
X190606Y153155D01*
X190348Y152963D01*
X190193Y152618D01*
X190245Y152273D01*
X190451Y151928D01*
G01X188793Y142398D02*
X185693D01*
Y143357D01*
X185848Y143663D01*
X186055Y143855D01*
X186468Y143932D01*
X186881Y143855D01*
X187140Y143625D01*
X187295Y143357D01*
Y142398D01*
G01Y143357D02*
X188793Y143932D01*
G01X188328Y145422D02*
X188586Y145652D01*
X188741Y145920D01*
X188793Y146265D01*
X188690Y146610D01*
X188483Y146878D01*
X188121Y147070D01*
X187708Y147108D01*
X187295Y147032D01*
X187036Y146840D01*
X186830Y146572D01*
X186778Y146303D01*
X186830Y146035D01*
X187036Y145690D01*
X185693Y145805D01*
Y146840D01*
G01X187501Y148637D02*
X187140Y148905D01*
X186933Y149135D01*
X186830Y149442D01*
X186933Y149710D01*
X187140Y149902D01*
X187450Y150055D01*
X187811Y150093D01*
X188121Y150055D01*
X188431Y149902D01*
X188690Y149672D01*
X188793Y149403D01*
X188690Y149097D01*
X188380Y148828D01*
X187915Y148675D01*
X187398Y148637D01*
X186726Y148713D01*
X186365Y148828D01*
X186003Y149020D01*
X185745Y149288D01*
X185693Y149557D01*
X185796Y149825D01*
X186055Y150017D01*
G01X188793Y152465D02*
X185693D01*
X186313Y152005D01*
G01X188793D02*
Y152925D01*
G01X186241Y169109D02*
Y172209D01*
X187200D01*
X187506Y172054D01*
X187698Y171847D01*
X187775Y171434D01*
X187698Y171021D01*
X187468Y170762D01*
X187200Y170607D01*
X186241D01*
G01X187200D02*
X187775Y169109D01*
G01X190108D02*
Y172209D01*
X189648Y171589D01*
G01Y169109D02*
X190568D01*
G01X193208Y172209D02*
X192901Y172106D01*
X192671Y171847D01*
X192518Y171537D01*
X192403Y171124D01*
X192365Y170659D01*
X192403Y170194D01*
X192518Y169781D01*
X192671Y169471D01*
X192901Y169212D01*
X193208Y169109D01*
X193515Y169212D01*
X193745Y169471D01*
X193898Y169781D01*
X194013Y170194D01*
X194051Y170659D01*
X194013Y171124D01*
X193898Y171537D01*
X193745Y171847D01*
X193515Y172106D01*
X193208Y172209D01*
G01X196308Y169109D02*
Y172209D01*
X195848Y171589D01*
G01Y169109D02*
X196768D01*
G01X198680Y171692D02*
X198910Y172002D01*
X199178Y172157D01*
X199485Y172209D01*
X199868Y172106D01*
X200136Y171847D01*
X200213Y171537D01*
X200175Y171227D01*
X200021Y170969D01*
X199255Y170452D01*
X198910Y170091D01*
X198680Y169574D01*
X198603Y169109D01*
X200213D01*
G01X183361Y159708D02*
X185583D01*
X186048Y159861D01*
X186358Y160168D01*
X186461Y160551D01*
X186358Y160934D01*
X186048Y161241D01*
X185583Y161394D01*
X183361D01*
G01X186461Y163651D02*
X186409Y163919D01*
X186254Y164226D01*
X185996Y164418D01*
X185634Y164494D01*
X185273Y164418D01*
X184963Y164188D01*
X184808Y163843D01*
Y163459D01*
X184704Y163229D01*
X184446Y163038D01*
X184084Y162961D01*
X183723Y163076D01*
X183464Y163344D01*
X183361Y163651D01*
X183464Y163958D01*
X183723Y164226D01*
X184084Y164341D01*
X184446Y164264D01*
X184704Y164073D01*
X184808Y163843D01*
Y163459D01*
X184963Y163114D01*
X185273Y162884D01*
X185634Y162808D01*
X185996Y162884D01*
X186254Y163076D01*
X186409Y163383D01*
X186461Y163651D01*
G01Y166674D02*
X185789Y166751D01*
X185221Y166866D01*
X184704Y167019D01*
X184136Y167211D01*
X183361Y167518D01*
Y165984D01*
G01X187771Y159708D02*
X189993D01*
X190458Y159861D01*
X190768Y160168D01*
X190871Y160551D01*
X190768Y160934D01*
X190458Y161241D01*
X189993Y161394D01*
X187771D01*
G01X190871Y163651D02*
X190819Y163919D01*
X190664Y164226D01*
X190406Y164418D01*
X190044Y164494D01*
X189683Y164418D01*
X189373Y164188D01*
X189218Y163843D01*
Y163459D01*
X189114Y163229D01*
X188856Y163038D01*
X188494Y162961D01*
X188133Y163076D01*
X187874Y163344D01*
X187771Y163651D01*
X187874Y163958D01*
X188133Y164226D01*
X188494Y164341D01*
X188856Y164264D01*
X189114Y164073D01*
X189218Y163843D01*
Y163459D01*
X189373Y163114D01*
X189683Y162884D01*
X190044Y162808D01*
X190406Y162884D01*
X190664Y163076D01*
X190819Y163383D01*
X190871Y163651D01*
G01X190406Y165908D02*
X190664Y166138D01*
X190819Y166406D01*
X190871Y166751D01*
X190768Y167096D01*
X190561Y167364D01*
X190199Y167556D01*
X189786Y167594D01*
X189373Y167518D01*
X189114Y167326D01*
X188908Y167058D01*
X188856Y166789D01*
X188908Y166521D01*
X189114Y166176D01*
X187771Y166291D01*
Y167326D01*
G01X192021Y159708D02*
X194243D01*
X194708Y159861D01*
X195018Y160168D01*
X195121Y160551D01*
X195018Y160934D01*
X194708Y161241D01*
X194243Y161394D01*
X192021D01*
G01X195121Y163651D02*
X195069Y163919D01*
X194914Y164226D01*
X194656Y164418D01*
X194294Y164494D01*
X193933Y164418D01*
X193623Y164188D01*
X193468Y163843D01*
Y163459D01*
X193364Y163229D01*
X193106Y163038D01*
X192744Y162961D01*
X192383Y163076D01*
X192124Y163344D01*
X192021Y163651D01*
X192124Y163958D01*
X192383Y164226D01*
X192744Y164341D01*
X193106Y164264D01*
X193364Y164073D01*
X193468Y163843D01*
Y163459D01*
X193623Y163114D01*
X193933Y162884D01*
X194294Y162808D01*
X194656Y162884D01*
X194914Y163076D01*
X195069Y163383D01*
X195121Y163651D01*
G01X194759Y166099D02*
X195018Y166368D01*
X195121Y166674D01*
X195018Y166981D01*
X194708Y167249D01*
X194243Y167441D01*
X193778Y167518D01*
X193209D01*
X192744Y167441D01*
X192331Y167249D01*
X192124Y167019D01*
X192021Y166751D01*
X192124Y166444D01*
X192331Y166214D01*
X192641Y166061D01*
X193054Y165984D01*
X193416Y166061D01*
X193778Y166253D01*
X193984Y166483D01*
X194036Y166751D01*
X193933Y167058D01*
X193674Y167288D01*
X193209Y167518D01*
G01X182589Y177718D02*
X184811D01*
X185276Y177871D01*
X185586Y178178D01*
X185689Y178561D01*
X185586Y178944D01*
X185276Y179251D01*
X184811Y179404D01*
X182589D01*
G01X185327Y181009D02*
X185586Y181278D01*
X185689Y181584D01*
X185586Y181891D01*
X185276Y182159D01*
X184811Y182351D01*
X184346Y182428D01*
X183777D01*
X183312Y182351D01*
X182899Y182159D01*
X182692Y181929D01*
X182589Y181661D01*
X182692Y181354D01*
X182899Y181124D01*
X183209Y180971D01*
X183622Y180894D01*
X183984Y180971D01*
X184346Y181163D01*
X184552Y181393D01*
X184604Y181661D01*
X184501Y181968D01*
X184242Y182198D01*
X183777Y182428D01*
G01X185327Y184109D02*
X185586Y184378D01*
X185689Y184684D01*
X185586Y184991D01*
X185276Y185259D01*
X184811Y185451D01*
X184346Y185528D01*
X183777D01*
X183312Y185451D01*
X182899Y185259D01*
X182692Y185029D01*
X182589Y184761D01*
X182692Y184454D01*
X182899Y184224D01*
X183209Y184071D01*
X183622Y183994D01*
X183984Y184071D01*
X184346Y184263D01*
X184552Y184493D01*
X184604Y184761D01*
X184501Y185068D01*
X184242Y185298D01*
X183777Y185528D01*
G01X186589Y177718D02*
X188811D01*
X189276Y177871D01*
X189586Y178178D01*
X189689Y178561D01*
X189586Y178944D01*
X189276Y179251D01*
X188811Y179404D01*
X186589D01*
G01X189327Y181009D02*
X189586Y181278D01*
X189689Y181584D01*
X189586Y181891D01*
X189276Y182159D01*
X188811Y182351D01*
X188346Y182428D01*
X187777D01*
X187312Y182351D01*
X186899Y182159D01*
X186692Y181929D01*
X186589Y181661D01*
X186692Y181354D01*
X186899Y181124D01*
X187209Y180971D01*
X187622Y180894D01*
X187984Y180971D01*
X188346Y181163D01*
X188552Y181393D01*
X188604Y181661D01*
X188501Y181968D01*
X188242Y182198D01*
X187777Y182428D01*
G01X188397Y184033D02*
X188036Y184301D01*
X187829Y184531D01*
X187726Y184838D01*
X187829Y185106D01*
X188036Y185298D01*
X188346Y185451D01*
X188707Y185489D01*
X189017Y185451D01*
X189327Y185298D01*
X189586Y185068D01*
X189689Y184799D01*
X189586Y184493D01*
X189276Y184224D01*
X188811Y184071D01*
X188294Y184033D01*
X187622Y184109D01*
X187261Y184224D01*
X186899Y184416D01*
X186641Y184684D01*
X186589Y184953D01*
X186692Y185221D01*
X186951Y185413D01*
G01X190589Y177718D02*
X192811D01*
X193276Y177871D01*
X193586Y178178D01*
X193689Y178561D01*
X193586Y178944D01*
X193276Y179251D01*
X192811Y179404D01*
X190589D01*
G01X193327Y181009D02*
X193586Y181278D01*
X193689Y181584D01*
X193586Y181891D01*
X193276Y182159D01*
X192811Y182351D01*
X192346Y182428D01*
X191777D01*
X191312Y182351D01*
X190899Y182159D01*
X190692Y181929D01*
X190589Y181661D01*
X190692Y181354D01*
X190899Y181124D01*
X191209Y180971D01*
X191622Y180894D01*
X191984Y180971D01*
X192346Y181163D01*
X192552Y181393D01*
X192604Y181661D01*
X192501Y181968D01*
X192242Y182198D01*
X191777Y182428D01*
G01X193689Y184761D02*
X193637Y185029D01*
X193482Y185336D01*
X193224Y185528D01*
X192862Y185604D01*
X192501Y185528D01*
X192191Y185298D01*
X192036Y184953D01*
Y184569D01*
X191932Y184339D01*
X191674Y184148D01*
X191312Y184071D01*
X190951Y184186D01*
X190692Y184454D01*
X190589Y184761D01*
X190692Y185068D01*
X190951Y185336D01*
X191312Y185451D01*
X191674Y185374D01*
X191932Y185183D01*
X192036Y184953D01*
Y184569D01*
X192191Y184224D01*
X192501Y183994D01*
X192862Y183918D01*
X193224Y183994D01*
X193482Y184186D01*
X193637Y184493D01*
X193689Y184761D01*
G01X194633Y177754D02*
X196855D01*
X197320Y177907D01*
X197630Y178214D01*
X197733Y178597D01*
X197630Y178980D01*
X197320Y179287D01*
X196855Y179440D01*
X194633D01*
G01X197371Y181045D02*
X197630Y181314D01*
X197733Y181620D01*
X197630Y181927D01*
X197320Y182195D01*
X196855Y182387D01*
X196390Y182464D01*
X195821D01*
X195356Y182387D01*
X194943Y182195D01*
X194736Y181965D01*
X194633Y181697D01*
X194736Y181390D01*
X194943Y181160D01*
X195253Y181007D01*
X195666Y180930D01*
X196028Y181007D01*
X196390Y181199D01*
X196596Y181429D01*
X196648Y181697D01*
X196545Y182004D01*
X196286Y182234D01*
X195821Y182464D01*
G01X197268Y183954D02*
X197526Y184184D01*
X197681Y184452D01*
X197733Y184797D01*
X197630Y185142D01*
X197423Y185410D01*
X197061Y185602D01*
X196648Y185640D01*
X196235Y185564D01*
X195976Y185372D01*
X195770Y185104D01*
X195718Y184835D01*
X195770Y184567D01*
X195976Y184222D01*
X194633Y184337D01*
Y185372D01*
G01X183171Y194641D02*
X183016Y194411D01*
X182913Y194143D01*
Y193836D01*
X183068Y193491D01*
X183326Y193223D01*
X183636Y193031D01*
X184153Y192878D01*
X184618Y192840D01*
X185083Y192916D01*
X185393Y193031D01*
X185703Y193261D01*
X185910Y193530D01*
X186013Y193798D01*
Y194066D01*
X185910Y194335D01*
X185755Y194565D01*
X185548Y194756D01*
G01X184721Y196170D02*
X184360Y196438D01*
X184153Y196668D01*
X184050Y196975D01*
X184153Y197243D01*
X184360Y197435D01*
X184670Y197588D01*
X185031Y197626D01*
X185341Y197588D01*
X185651Y197435D01*
X185910Y197205D01*
X186013Y196936D01*
X185910Y196630D01*
X185600Y196361D01*
X185135Y196208D01*
X184618Y196170D01*
X183946Y196246D01*
X183585Y196361D01*
X183223Y196553D01*
X182965Y196821D01*
X182913Y197090D01*
X183016Y197358D01*
X183275Y197550D01*
G01X182913Y199998D02*
X183016Y199691D01*
X183275Y199461D01*
X183585Y199308D01*
X183998Y199193D01*
X184463Y199155D01*
X184928Y199193D01*
X185341Y199308D01*
X185651Y199461D01*
X185910Y199691D01*
X186013Y199998D01*
X185910Y200305D01*
X185651Y200535D01*
X185341Y200688D01*
X184928Y200803D01*
X184463Y200841D01*
X183998Y200803D01*
X183585Y200688D01*
X183275Y200535D01*
X183016Y200305D01*
X182913Y199998D01*
G01X185548Y202255D02*
X185806Y202485D01*
X185961Y202753D01*
X186013Y203098D01*
X185910Y203443D01*
X185703Y203711D01*
X185341Y203903D01*
X184928Y203941D01*
X184515Y203865D01*
X184256Y203673D01*
X184050Y203405D01*
X183998Y203136D01*
X184050Y202868D01*
X184256Y202523D01*
X182913Y202638D01*
Y203673D01*
G01X192171Y194641D02*
X192016Y194411D01*
X191913Y194143D01*
Y193836D01*
X192068Y193491D01*
X192326Y193223D01*
X192636Y193031D01*
X193153Y192878D01*
X193618Y192840D01*
X194083Y192916D01*
X194393Y193031D01*
X194703Y193261D01*
X194910Y193530D01*
X195013Y193798D01*
Y194066D01*
X194910Y194335D01*
X194755Y194565D01*
X194548Y194756D01*
G01X193721Y196170D02*
X193360Y196438D01*
X193153Y196668D01*
X193050Y196975D01*
X193153Y197243D01*
X193360Y197435D01*
X193670Y197588D01*
X194031Y197626D01*
X194341Y197588D01*
X194651Y197435D01*
X194910Y197205D01*
X195013Y196936D01*
X194910Y196630D01*
X194600Y196361D01*
X194135Y196208D01*
X193618Y196170D01*
X192946Y196246D01*
X192585Y196361D01*
X192223Y196553D01*
X191965Y196821D01*
X191913Y197090D01*
X192016Y197358D01*
X192275Y197550D01*
G01X191913Y199998D02*
X192016Y199691D01*
X192275Y199461D01*
X192585Y199308D01*
X192998Y199193D01*
X193463Y199155D01*
X193928Y199193D01*
X194341Y199308D01*
X194651Y199461D01*
X194910Y199691D01*
X195013Y199998D01*
X194910Y200305D01*
X194651Y200535D01*
X194341Y200688D01*
X193928Y200803D01*
X193463Y200841D01*
X192998Y200803D01*
X192585Y200688D01*
X192275Y200535D01*
X192016Y200305D01*
X191913Y199998D01*
G01Y203098D02*
X192016Y202791D01*
X192275Y202561D01*
X192585Y202408D01*
X192998Y202293D01*
X193463Y202255D01*
X193928Y202293D01*
X194341Y202408D01*
X194651Y202561D01*
X194910Y202791D01*
X195013Y203098D01*
X194910Y203405D01*
X194651Y203635D01*
X194341Y203788D01*
X193928Y203903D01*
X193463Y203941D01*
X192998Y203903D01*
X192585Y203788D01*
X192275Y203635D01*
X192016Y203405D01*
X191913Y203098D01*
G01X187671Y194608D02*
X187516Y194378D01*
X187413Y194110D01*
Y193803D01*
X187568Y193458D01*
X187826Y193190D01*
X188136Y192998D01*
X188653Y192845D01*
X189118Y192807D01*
X189583Y192883D01*
X189893Y192998D01*
X190203Y193228D01*
X190410Y193497D01*
X190513Y193765D01*
Y194033D01*
X190410Y194302D01*
X190255Y194532D01*
X190048Y194723D01*
G01X189221Y196137D02*
X188860Y196405D01*
X188653Y196635D01*
X188550Y196942D01*
X188653Y197210D01*
X188860Y197402D01*
X189170Y197555D01*
X189531Y197593D01*
X189841Y197555D01*
X190151Y197402D01*
X190410Y197172D01*
X190513Y196903D01*
X190410Y196597D01*
X190100Y196328D01*
X189635Y196175D01*
X189118Y196137D01*
X188446Y196213D01*
X188085Y196328D01*
X187723Y196520D01*
X187465Y196788D01*
X187413Y197057D01*
X187516Y197325D01*
X187775Y197517D01*
G01X187413Y199965D02*
X187516Y199658D01*
X187775Y199428D01*
X188085Y199275D01*
X188498Y199160D01*
X188963Y199122D01*
X189428Y199160D01*
X189841Y199275D01*
X190151Y199428D01*
X190410Y199658D01*
X190513Y199965D01*
X190410Y200272D01*
X190151Y200502D01*
X189841Y200655D01*
X189428Y200770D01*
X188963Y200808D01*
X188498Y200770D01*
X188085Y200655D01*
X187775Y200502D01*
X187516Y200272D01*
X187413Y199965D01*
G01X187930Y202337D02*
X187620Y202567D01*
X187465Y202835D01*
X187413Y203142D01*
X187516Y203525D01*
X187775Y203793D01*
X188085Y203870D01*
X188395Y203832D01*
X188653Y203678D01*
X189170Y202912D01*
X189531Y202567D01*
X190048Y202337D01*
X190513Y202260D01*
Y203870D01*
G01X182749Y356756D02*
Y359256D01*
X182429Y358756D01*
G01Y356756D02*
X183069D01*
G01X184949D02*
Y359256D01*
X184629Y358756D01*
G01Y356756D02*
X185269D01*
G01X184749Y361256D02*
Y363756D01*
X184429Y363256D01*
G01Y361256D02*
X185069D01*
G01X186442Y363339D02*
X186602Y363589D01*
X186789Y363714D01*
X187002Y363756D01*
X187269Y363673D01*
X187456Y363464D01*
X187509Y363214D01*
X187482Y362964D01*
X187376Y362756D01*
X186842Y362339D01*
X186602Y362048D01*
X186442Y361631D01*
X186389Y361256D01*
X187509D01*
G01X188749D02*
Y363756D01*
X188429Y363256D01*
G01Y361256D02*
X189069D01*
G01X191269D02*
Y363756D01*
X190282Y361964D01*
X191616D01*
G01X187249Y356756D02*
Y359256D01*
X186929Y358756D01*
G01Y356756D02*
X187569D01*
G01X188862Y357256D02*
X189022Y356964D01*
X189236Y356798D01*
X189476Y356756D01*
X189689Y356798D01*
X189902Y357006D01*
X190036Y357256D01*
X190062Y357506D01*
X190009Y357798D01*
X189822Y358006D01*
X189636Y358089D01*
X189396D01*
G01X189636D02*
X189796Y358214D01*
X189929Y358423D01*
X189982Y358673D01*
X189929Y358923D01*
X189796Y359131D01*
X189556Y359256D01*
X189316Y359214D01*
X189076Y359048D01*
G01X192749Y361256D02*
Y363756D01*
X192429Y363256D01*
G01Y361256D02*
X193069D01*
G01X194442Y362298D02*
X194629Y362589D01*
X194789Y362756D01*
X195002Y362839D01*
X195189Y362756D01*
X195322Y362589D01*
X195429Y362339D01*
X195456Y362048D01*
X195429Y361798D01*
X195322Y361548D01*
X195162Y361339D01*
X194976Y361256D01*
X194762Y361339D01*
X194576Y361589D01*
X194469Y361964D01*
X194442Y362381D01*
X194496Y362923D01*
X194576Y363214D01*
X194709Y363506D01*
X194896Y363714D01*
X195082Y363756D01*
X195269Y363673D01*
X195402Y363464D01*
G01X195249Y356756D02*
Y359256D01*
X194929Y358756D01*
G01Y356756D02*
X195569D01*
G01X197396D02*
X197449Y357298D01*
X197529Y357756D01*
X197636Y358173D01*
X197769Y358631D01*
X197982Y359256D01*
X196916D01*
G01X191249Y356756D02*
Y359256D01*
X190929Y358756D01*
G01Y356756D02*
X191569D01*
G01X192862Y357131D02*
X193022Y356923D01*
X193209Y356798D01*
X193449Y356756D01*
X193689Y356839D01*
X193876Y357006D01*
X194009Y357298D01*
X194036Y357631D01*
X193982Y357964D01*
X193849Y358173D01*
X193662Y358339D01*
X193476Y358381D01*
X193289Y358339D01*
X193049Y358173D01*
X193129Y359256D01*
X193849D01*
G01X195681Y370949D02*
X195451Y371104D01*
X195183Y371207D01*
X194876D01*
X194531Y371052D01*
X194263Y370794D01*
X194071Y370484D01*
X193918Y369967D01*
X193880Y369502D01*
X193956Y369037D01*
X194071Y368727D01*
X194301Y368417D01*
X194570Y368210D01*
X194838Y368107D01*
X195106D01*
X195375Y368210D01*
X195605Y368365D01*
X195796Y368572D01*
G01X197938Y368107D02*
Y371207D01*
X197478Y370587D01*
G01Y368107D02*
X198398D01*
G01X200195Y368727D02*
X200425Y368365D01*
X200731Y368159D01*
X201076Y368107D01*
X201383Y368159D01*
X201690Y368417D01*
X201881Y368727D01*
X201920Y369037D01*
X201843Y369399D01*
X201575Y369657D01*
X201306Y369760D01*
X200961D01*
G01X201306D02*
X201536Y369915D01*
X201728Y370174D01*
X201805Y370484D01*
X201728Y370794D01*
X201536Y371052D01*
X201191Y371207D01*
X200846Y371155D01*
X200501Y370949D01*
G01X203410Y369399D02*
X203678Y369760D01*
X203908Y369967D01*
X204215Y370070D01*
X204483Y369967D01*
X204675Y369760D01*
X204828Y369450D01*
X204866Y369089D01*
X204828Y368779D01*
X204675Y368469D01*
X204445Y368210D01*
X204176Y368107D01*
X203870Y368210D01*
X203601Y368520D01*
X203448Y368985D01*
X203410Y369502D01*
X203486Y370174D01*
X203601Y370535D01*
X203793Y370897D01*
X204061Y371155D01*
X204330Y371207D01*
X204598Y371104D01*
X204790Y370845D01*
G01X186672Y384236D02*
Y382014D01*
X186825Y381549D01*
X187132Y381239D01*
X187515Y381136D01*
X187898Y381239D01*
X188205Y381549D01*
X188358Y382014D01*
Y384236D01*
G01X189963Y381498D02*
X190232Y381239D01*
X190538Y381136D01*
X190845Y381239D01*
X191113Y381549D01*
X191305Y382014D01*
X191382Y382479D01*
Y383048D01*
X191305Y383513D01*
X191113Y383926D01*
X190883Y384133D01*
X190615Y384236D01*
X190308Y384133D01*
X190078Y383926D01*
X189925Y383616D01*
X189848Y383203D01*
X189925Y382841D01*
X190117Y382479D01*
X190347Y382273D01*
X190615Y382221D01*
X190922Y382324D01*
X191152Y382583D01*
X191382Y383048D01*
G01X185720Y387747D02*
Y390247D01*
X185400Y389747D01*
G01Y387747D02*
X186040D01*
G01X187413Y389830D02*
X187573Y390080D01*
X187760Y390205D01*
X187973Y390247D01*
X188240Y390164D01*
X188427Y389955D01*
X188480Y389705D01*
X188453Y389455D01*
X188347Y389247D01*
X187813Y388830D01*
X187573Y388539D01*
X187413Y388122D01*
X187360Y387747D01*
X188480D01*
G01X192467Y381907D02*
Y384407D01*
X192147Y383907D01*
G01Y381907D02*
X192787D01*
G01X194080Y382407D02*
X194240Y382115D01*
X194454Y381949D01*
X194694Y381907D01*
X194907Y381949D01*
X195120Y382157D01*
X195254Y382407D01*
X195280Y382657D01*
X195227Y382949D01*
X195040Y383157D01*
X194854Y383240D01*
X194614D01*
G01X194854D02*
X195014Y383365D01*
X195147Y383574D01*
X195200Y383824D01*
X195147Y384074D01*
X195014Y384282D01*
X194774Y384407D01*
X194534Y384365D01*
X194294Y384199D01*
G01X189358Y388279D02*
Y385255D01*
G01D02*
X192395D01*
G01X181919Y395739D02*
X184919D01*
G01X185019Y398839D02*
Y392639D01*
G01D02*
X181819D01*
G01D02*
Y398839D01*
G01D02*
X185019D01*
G01X180961Y406246D02*
Y400046D01*
G01X184961D02*
X181761D01*
G01D02*
Y406246D01*
G01D02*
X184961D01*
G01D02*
Y400046D01*
G01X186323Y405427D02*
Y408527D01*
X187282D01*
X187588Y408372D01*
X187780Y408165D01*
X187857Y407752D01*
X187780Y407339D01*
X187550Y407080D01*
X187282Y406925D01*
X186323D01*
G01X187282D02*
X187857Y405427D01*
G01X190190D02*
Y408527D01*
X189730Y407907D01*
G01Y405427D02*
X190650D01*
G01X193290D02*
Y408527D01*
X192830Y407907D01*
G01Y405427D02*
X193750D01*
G01X196390Y408527D02*
X196083Y408424D01*
X195853Y408165D01*
X195700Y407855D01*
X195585Y407442D01*
X195547Y406977D01*
X195585Y406512D01*
X195700Y406099D01*
X195853Y405789D01*
X196083Y405530D01*
X196390Y405427D01*
X196697Y405530D01*
X196927Y405789D01*
X197080Y406099D01*
X197195Y406512D01*
X197233Y406977D01*
X197195Y407442D01*
X197080Y407855D01*
X196927Y408165D01*
X196697Y408424D01*
X196390Y408527D01*
G01X198647Y406047D02*
X198877Y405685D01*
X199183Y405479D01*
X199528Y405427D01*
X199835Y405479D01*
X200142Y405737D01*
X200333Y406047D01*
X200372Y406357D01*
X200295Y406719D01*
X200027Y406977D01*
X199758Y407080D01*
X199413D01*
G01X199758D02*
X199988Y407235D01*
X200180Y407494D01*
X200257Y407804D01*
X200180Y408114D01*
X199988Y408372D01*
X199643Y408527D01*
X199298Y408475D01*
X198953Y408269D01*
G01X187492Y396853D02*
X187678Y396644D01*
X187892Y396561D01*
X188105Y396644D01*
X188292Y396894D01*
X188425Y397269D01*
X188478Y397644D01*
Y398103D01*
X188425Y398478D01*
X188292Y398811D01*
X188132Y398978D01*
X187945Y399061D01*
X187732Y398978D01*
X187572Y398811D01*
X187465Y398561D01*
X187412Y398228D01*
X187465Y397936D01*
X187598Y397644D01*
X187758Y397478D01*
X187945Y397436D01*
X188158Y397519D01*
X188318Y397728D01*
X188478Y398103D01*
G01X191137Y402219D02*
X191324Y402261D01*
X191537Y402386D01*
X191670Y402594D01*
X191724Y402886D01*
X191670Y403177D01*
X191510Y403427D01*
X191270Y403552D01*
X191004D01*
X190844Y403636D01*
X190710Y403844D01*
X190657Y404136D01*
X190737Y404427D01*
X190924Y404636D01*
X191137Y404719D01*
X191350Y404636D01*
X191537Y404427D01*
X191617Y404136D01*
X191564Y403844D01*
X191430Y403636D01*
X191270Y403552D01*
X191004D01*
X190764Y403427D01*
X190604Y403177D01*
X190550Y402886D01*
X190604Y402594D01*
X190737Y402386D01*
X190950Y402261D01*
X191137Y402219D01*
G01X188449Y394585D02*
X184949D01*
G01X192414Y401396D02*
X189358D01*
G01D02*
Y398372D01*
G01X194937Y414590D02*
Y440968D01*
G01X227737Y414590D02*
X194937D01*
G01X191888Y422629D02*
X188788D01*
Y423549D01*
X188943Y423856D01*
X189305Y424086D01*
X189718Y424163D01*
X190131Y424086D01*
X190441Y423894D01*
X190596Y423549D01*
Y422629D01*
G01X188788Y425653D02*
X191010D01*
X191475Y425806D01*
X191785Y426113D01*
X191888Y426496D01*
X191785Y426879D01*
X191475Y427186D01*
X191010Y427339D01*
X188788D01*
G01X189305Y428868D02*
X188995Y429098D01*
X188840Y429366D01*
X188788Y429673D01*
X188891Y430056D01*
X189150Y430324D01*
X189460Y430401D01*
X189770Y430363D01*
X190028Y430209D01*
X190545Y429443D01*
X190906Y429098D01*
X191423Y428868D01*
X191888Y428791D01*
Y430401D01*
G01X186831Y423792D02*
X187017Y423583D01*
X187231Y423500D01*
X187444Y423583D01*
X187631Y423833D01*
X187764Y424208D01*
X187817Y424583D01*
Y425042D01*
X187764Y425417D01*
X187631Y425750D01*
X187471Y425917D01*
X187284Y426000D01*
X187071Y425917D01*
X186911Y425750D01*
X186804Y425500D01*
X186751Y425167D01*
X186804Y424875D01*
X186937Y424583D01*
X187097Y424417D01*
X187284Y424375D01*
X187497Y424458D01*
X187657Y424667D01*
X187817Y425042D01*
G01X186271Y409303D02*
Y412403D01*
X187191D01*
X187498Y412248D01*
X187728Y411886D01*
X187805Y411473D01*
X187728Y411060D01*
X187536Y410750D01*
X187191Y410595D01*
X186271D01*
G01X190981Y412145D02*
X190751Y412300D01*
X190483Y412403D01*
X190176D01*
X189831Y412248D01*
X189563Y411990D01*
X189371Y411680D01*
X189218Y411163D01*
X189180Y410698D01*
X189256Y410233D01*
X189371Y409923D01*
X189601Y409613D01*
X189870Y409406D01*
X190138Y409303D01*
X190406D01*
X190675Y409406D01*
X190905Y409561D01*
X191096Y409768D01*
G01X192510Y411886D02*
X192740Y412196D01*
X193008Y412351D01*
X193315Y412403D01*
X193698Y412300D01*
X193966Y412041D01*
X194043Y411731D01*
X194005Y411421D01*
X193851Y411163D01*
X193085Y410646D01*
X192740Y410285D01*
X192510Y409768D01*
X192433Y409303D01*
X194043D01*
G01X195610Y410595D02*
X195878Y410956D01*
X196108Y411163D01*
X196415Y411266D01*
X196683Y411163D01*
X196875Y410956D01*
X197028Y410646D01*
X197066Y410285D01*
X197028Y409975D01*
X196875Y409665D01*
X196645Y409406D01*
X196376Y409303D01*
X196070Y409406D01*
X195801Y409716D01*
X195648Y410181D01*
X195610Y410698D01*
X195686Y411370D01*
X195801Y411731D01*
X195993Y412093D01*
X196261Y412351D01*
X196530Y412403D01*
X196798Y412300D01*
X196990Y412041D01*
G01X186686Y420425D02*
Y417425D01*
G01X189786Y420525D02*
Y417325D01*
G01D02*
X183586D01*
G01D02*
Y420525D01*
G01D02*
X189786D01*
G01X183592Y413285D02*
Y416485D01*
G01X189792Y413285D02*
X183592D01*
G01X189792Y416485D02*
Y413285D01*
G01X183592Y416485D02*
X189792D01*
G01X187710Y439026D02*
Y441526D01*
X187390Y441026D01*
G01Y439026D02*
X188030D01*
G01X189403Y441109D02*
X189563Y441359D01*
X189750Y441484D01*
X189963Y441526D01*
X190230Y441443D01*
X190417Y441234D01*
X190470Y440984D01*
X190443Y440734D01*
X190337Y440526D01*
X189803Y440109D01*
X189563Y439818D01*
X189403Y439401D01*
X189350Y439026D01*
X190470D01*
G01X186747Y437184D02*
Y439185D01*
G01D02*
X184646D01*
G01Y426783D02*
X186747D01*
G01D02*
Y428484D01*
G01X188639Y431999D02*
X190639D01*
G01X193403Y432040D02*
X190203D01*
G01X193403Y438240D02*
Y432040D01*
G01X190203Y438240D02*
X193403D01*
G01X190203Y432040D02*
Y438240D01*
G01X193303Y435140D02*
X190303D01*
G01X194937Y440968D02*
X227737D01*
G01X182918Y455399D02*
Y458499D01*
X183838D01*
X184145Y458344D01*
X184375Y457982D01*
X184452Y457569D01*
X184375Y457156D01*
X184183Y456846D01*
X183838Y456691D01*
X182918D01*
G01X187628Y458241D02*
X187398Y458396D01*
X187130Y458499D01*
X186823D01*
X186478Y458344D01*
X186210Y458086D01*
X186018Y457776D01*
X185865Y457259D01*
X185827Y456794D01*
X185903Y456329D01*
X186018Y456019D01*
X186248Y455709D01*
X186517Y455502D01*
X186785Y455399D01*
X187053D01*
X187322Y455502D01*
X187552Y455657D01*
X187743Y455864D01*
G01X189885Y455399D02*
Y458499D01*
X189425Y457879D01*
G01Y455399D02*
X190345D01*
G01X192257Y457982D02*
X192487Y458292D01*
X192755Y458447D01*
X193062Y458499D01*
X193445Y458396D01*
X193713Y458137D01*
X193790Y457827D01*
X193752Y457517D01*
X193598Y457259D01*
X192832Y456742D01*
X192487Y456381D01*
X192257Y455864D01*
X192180Y455399D01*
X193790D01*
G01X190698Y442792D02*
X184498D01*
G01D02*
Y445992D01*
G01D02*
X190698D01*
G01D02*
Y442792D01*
G01X187598Y445892D02*
Y442892D01*
G01X192503Y441785D02*
Y444885D01*
X193423D01*
X193730Y444730D01*
X193960Y444368D01*
X194037Y443955D01*
X193960Y443542D01*
X193768Y443232D01*
X193423Y443077D01*
X192503D01*
G01X197213Y444627D02*
X196983Y444782D01*
X196715Y444885D01*
X196408D01*
X196063Y444730D01*
X195795Y444472D01*
X195603Y444162D01*
X195450Y443645D01*
X195412Y443180D01*
X195488Y442715D01*
X195603Y442405D01*
X195833Y442095D01*
X196102Y441888D01*
X196370Y441785D01*
X196638D01*
X196907Y441888D01*
X197137Y442043D01*
X197328Y442250D01*
G01X199470Y441785D02*
Y444885D01*
X199010Y444265D01*
G01Y441785D02*
X199930D01*
G01X201727Y442250D02*
X201957Y441992D01*
X202225Y441837D01*
X202570Y441785D01*
X202915Y441888D01*
X203183Y442095D01*
X203375Y442457D01*
X203413Y442870D01*
X203337Y443283D01*
X203145Y443542D01*
X202877Y443748D01*
X202608Y443800D01*
X202340Y443748D01*
X201995Y443542D01*
X202110Y444885D01*
X203145D01*
G01X190009Y446791D02*
Y454191D01*
G01X198709Y446791D02*
X181309D01*
G01D02*
Y454191D01*
G01D02*
X198709D01*
G01X182981Y459590D02*
Y462690D01*
X183901D01*
X184208Y462535D01*
X184438Y462173D01*
X184515Y461760D01*
X184438Y461347D01*
X184246Y461037D01*
X183901Y460882D01*
X182981D01*
G01X187691Y462432D02*
X187461Y462587D01*
X187193Y462690D01*
X186886D01*
X186541Y462535D01*
X186273Y462277D01*
X186081Y461967D01*
X185928Y461450D01*
X185890Y460985D01*
X185966Y460520D01*
X186081Y460210D01*
X186311Y459900D01*
X186580Y459693D01*
X186848Y459590D01*
X187116D01*
X187385Y459693D01*
X187615Y459848D01*
X187806Y460055D01*
G01X189948Y459590D02*
Y462690D01*
X189488Y462070D01*
G01Y459590D02*
X190408D01*
G01X193048D02*
Y462690D01*
X192588Y462070D01*
G01Y459590D02*
X193508D01*
G01X197885Y468928D02*
X194785D01*
Y469887D01*
X194940Y470193D01*
X195147Y470385D01*
X195560Y470462D01*
X195973Y470385D01*
X196232Y470155D01*
X196387Y469887D01*
Y468928D01*
G01Y469887D02*
X197885Y470462D01*
G01X197265Y471952D02*
X197627Y472182D01*
X197833Y472488D01*
X197885Y472833D01*
X197833Y473140D01*
X197575Y473447D01*
X197265Y473638D01*
X196955Y473677D01*
X196593Y473600D01*
X196335Y473332D01*
X196232Y473063D01*
Y472718D01*
G01Y473063D02*
X196077Y473293D01*
X195818Y473485D01*
X195508Y473562D01*
X195198Y473485D01*
X194940Y473293D01*
X194785Y472948D01*
X194837Y472603D01*
X195043Y472258D01*
G01X197885Y475895D02*
X194785D01*
X195405Y475435D01*
G01X197885D02*
Y476355D01*
G01X195302Y478267D02*
X194992Y478497D01*
X194837Y478765D01*
X194785Y479072D01*
X194888Y479455D01*
X195147Y479723D01*
X195457Y479800D01*
X195767Y479762D01*
X196025Y479608D01*
X196542Y478842D01*
X196903Y478497D01*
X197420Y478267D01*
X197885Y478190D01*
Y479800D01*
G01X191463Y464780D02*
X191411Y464473D01*
X191205Y464205D01*
X190895Y463975D01*
X190533Y463822D01*
X190120Y463745D01*
X189706D01*
X189293Y463822D01*
X188931Y463975D01*
X188621Y464205D01*
X188415Y464473D01*
X188363Y464780D01*
X188415Y465087D01*
X188621Y465355D01*
X188931Y465585D01*
X189293Y465738D01*
X189706Y465815D01*
X190120D01*
X190533Y465738D01*
X190895Y465585D01*
X191205Y465355D01*
X191411Y465087D01*
X191463Y464780D01*
G01X191050Y467075D02*
X191308Y467382D01*
X191463Y467727D01*
Y468033D01*
X191308Y468340D01*
X191050Y468570D01*
X190688Y468685D01*
X190326Y468608D01*
X190016Y468417D01*
X189810Y468072D01*
X189706Y467612D01*
X189500Y467343D01*
X189138Y467228D01*
X188776Y467305D01*
X188518Y467497D01*
X188363Y467765D01*
Y468033D01*
X188466Y468302D01*
X188725Y468532D01*
G01X188621Y471823D02*
X188466Y471593D01*
X188363Y471325D01*
Y471018D01*
X188518Y470673D01*
X188776Y470405D01*
X189086Y470213D01*
X189603Y470060D01*
X190068Y470022D01*
X190533Y470098D01*
X190843Y470213D01*
X191153Y470443D01*
X191360Y470712D01*
X191463Y470980D01*
Y471248D01*
X191360Y471517D01*
X191205Y471747D01*
X190998Y471938D01*
G01X190843Y473237D02*
X191205Y473467D01*
X191411Y473773D01*
X191463Y474118D01*
X191411Y474425D01*
X191153Y474732D01*
X190843Y474923D01*
X190533Y474962D01*
X190171Y474885D01*
X189913Y474617D01*
X189810Y474348D01*
Y474003D01*
G01Y474348D02*
X189655Y474578D01*
X189396Y474770D01*
X189086Y474847D01*
X188776Y474770D01*
X188518Y474578D01*
X188363Y474233D01*
X188415Y473888D01*
X188621Y473543D01*
G01X187237Y486437D02*
Y484215D01*
X187390Y483750D01*
X187697Y483440D01*
X188080Y483337D01*
X188463Y483440D01*
X188770Y483750D01*
X188923Y484215D01*
Y486437D01*
G01X191180Y483337D02*
Y486437D01*
X190720Y485817D01*
G01Y483337D02*
X191640D01*
G01X193552Y484629D02*
X193820Y484990D01*
X194050Y485197D01*
X194357Y485300D01*
X194625Y485197D01*
X194817Y484990D01*
X194970Y484680D01*
X195008Y484319D01*
X194970Y484009D01*
X194817Y483699D01*
X194587Y483440D01*
X194318Y483337D01*
X194012Y483440D01*
X193743Y483750D01*
X193590Y484215D01*
X193552Y484732D01*
X193628Y485404D01*
X193743Y485765D01*
X193935Y486127D01*
X194203Y486385D01*
X194472Y486437D01*
X194740Y486334D01*
X194932Y486075D01*
G01X184381Y489505D02*
Y480705D01*
G01X185423Y478927D02*
Y475827D01*
X186957D01*
G01X189290D02*
Y478927D01*
X188830Y478307D01*
G01Y475827D02*
X189750D01*
G01X191547Y476447D02*
X191777Y476085D01*
X192083Y475879D01*
X192428Y475827D01*
X192735Y475879D01*
X193042Y476137D01*
X193233Y476447D01*
X193272Y476757D01*
X193195Y477119D01*
X192927Y477377D01*
X192658Y477480D01*
X192313D01*
G01X192658D02*
X192888Y477635D01*
X193080Y477894D01*
X193157Y478204D01*
X193080Y478514D01*
X192888Y478772D01*
X192543Y478927D01*
X192198Y478875D01*
X191853Y478669D01*
G01X184382Y557731D02*
Y504975D01*
G01X182155Y564181D02*
X182424Y563922D01*
X182730Y563819D01*
X183037Y563922D01*
X183305Y564232D01*
X183497Y564697D01*
X183574Y565162D01*
Y565731D01*
X183497Y566196D01*
X183305Y566609D01*
X183075Y566816D01*
X182807Y566919D01*
X182500Y566816D01*
X182270Y566609D01*
X182117Y566299D01*
X182040Y565886D01*
X182117Y565524D01*
X182309Y565162D01*
X182539Y564956D01*
X182807Y564904D01*
X183114Y565007D01*
X183344Y565266D01*
X183574Y565731D01*
G01X180863Y577233D02*
Y571033D01*
G01X192436Y586757D02*
X189936D01*
X190436Y586437D01*
G01X192436D02*
Y587077D01*
G01X191394Y588450D02*
X191103Y588637D01*
X190936Y588797D01*
X190853Y589010D01*
X190936Y589197D01*
X191103Y589330D01*
X191353Y589437D01*
X191644Y589464D01*
X191894Y589437D01*
X192144Y589330D01*
X192353Y589170D01*
X192436Y588984D01*
X192353Y588770D01*
X192103Y588584D01*
X191728Y588477D01*
X191311Y588450D01*
X190769Y588504D01*
X190478Y588584D01*
X190186Y588717D01*
X189978Y588904D01*
X189936Y589090D01*
X190019Y589277D01*
X190228Y589410D01*
G01X188258Y589433D02*
Y587433D01*
G01X193180Y594133D02*
Y592316D01*
G01D02*
X193080Y592216D01*
G01D02*
X191263D01*
G01X196251Y626360D02*
X196543Y626520D01*
X196709Y626734D01*
X196751Y626974D01*
X196709Y627187D01*
X196501Y627400D01*
X196251Y627534D01*
X196001Y627560D01*
X195709Y627507D01*
X195501Y627320D01*
X195418Y627134D01*
Y626894D01*
G01Y627134D02*
X195293Y627294D01*
X195084Y627427D01*
X194834Y627480D01*
X194584Y627427D01*
X194376Y627294D01*
X194251Y627054D01*
X194293Y626814D01*
X194459Y626574D01*
G01X194668Y628640D02*
X194418Y628800D01*
X194293Y628987D01*
X194251Y629200D01*
X194334Y629467D01*
X194543Y629654D01*
X194793Y629707D01*
X195043Y629680D01*
X195251Y629574D01*
X195668Y629040D01*
X195959Y628800D01*
X196376Y628640D01*
X196751Y628587D01*
Y629707D01*
G01X191363Y627650D02*
X193180D01*
G01D02*
Y625733D01*
G01X184750Y641300D02*
Y645730D01*
G01X207840Y641300D02*
X184750D01*
G01X190470Y630578D02*
X190762Y630738D01*
X190928Y630952D01*
X190970Y631192D01*
X190928Y631405D01*
X190720Y631618D01*
X190470Y631752D01*
X190220Y631778D01*
X189928Y631725D01*
X189720Y631538D01*
X189637Y631352D01*
Y631112D01*
G01Y631352D02*
X189512Y631512D01*
X189303Y631645D01*
X189053Y631698D01*
X188803Y631645D01*
X188595Y631512D01*
X188470Y631272D01*
X188512Y631032D01*
X188678Y630792D01*
G01X190470Y632778D02*
X190762Y632938D01*
X190928Y633152D01*
X190970Y633392D01*
X190928Y633605D01*
X190720Y633818D01*
X190470Y633952D01*
X190220Y633978D01*
X189928Y633925D01*
X189720Y633738D01*
X189637Y633552D01*
Y633312D01*
G01Y633552D02*
X189512Y633712D01*
X189303Y633845D01*
X189053Y633898D01*
X188803Y633845D01*
X188595Y633712D01*
X188470Y633472D01*
X188512Y633232D01*
X188678Y632992D01*
G01X186290Y630433D02*
Y632433D01*
G01X194810Y642175D02*
Y648375D01*
G01X198010Y642175D02*
X194810D01*
G01X190310D02*
Y648375D01*
G01X193510D02*
Y642175D01*
G01D02*
X190310D01*
G01X185810D02*
Y648375D01*
G01X189010D02*
Y642175D01*
G01D02*
X185810D01*
G01X185520Y659480D02*
Y674130D01*
G01X194810Y652175D02*
Y658375D01*
G01D02*
X198010D01*
G01Y652175D02*
X194810D01*
G01X185810D02*
Y658375D01*
G01D02*
X189010D01*
G01D02*
Y652175D01*
G01D02*
X185810D01*
G01X194810Y648375D02*
X198010D01*
G01X190310D02*
X193510D01*
G01X185810D02*
X189010D01*
G01X184663Y660126D02*
Y646740D01*
G01X188707Y665440D02*
X188960Y665690D01*
X189150Y666106D01*
X189277Y666690D01*
X189150Y667190D01*
X188897Y667523D01*
X188453Y667773D01*
X186743D01*
Y662773D01*
X188833D01*
X189277Y663106D01*
X189530Y663606D01*
X189657Y664190D01*
X189530Y664773D01*
X189150Y665273D01*
X188707Y665440D01*
X186743D01*
G01X191690Y669140D02*
Y661270D01*
G01D02*
X185690D01*
G01X185520Y669140D02*
X191690D01*
G01X185520Y674130D02*
X184960D01*
G01X189638Y670926D02*
Y674126D01*
G01X195838Y670926D02*
X189638D01*
G01Y674126D02*
X195838D01*
G01X192738Y671026D02*
Y674026D01*
G01X187078Y672160D02*
Y674660D01*
X186091Y672868D01*
X187425D01*
G01X183631Y675179D02*
Y691179D01*
G01X195835Y675179D02*
X183631D01*
G01X183753Y666757D02*
Y669257D01*
X184287D01*
X184500Y669132D01*
X184660Y668965D01*
X184793Y668715D01*
X184900Y668424D01*
X184927Y668007D01*
X184900Y667590D01*
X184793Y667299D01*
X184660Y667049D01*
X184500Y666882D01*
X184287Y666757D01*
X183753D01*
G01X182519Y674316D02*
Y661316D01*
G01X180587Y692596D02*
X180747Y692304D01*
X180961Y692138D01*
X181201Y692096D01*
X181414Y692138D01*
X181627Y692346D01*
X181761Y692596D01*
X181787Y692846D01*
X181734Y693138D01*
X181547Y693346D01*
X181361Y693429D01*
X181121D01*
G01X181361D02*
X181521Y693554D01*
X181654Y693763D01*
X181707Y694013D01*
X181654Y694263D01*
X181521Y694471D01*
X181281Y694596D01*
X181041Y694554D01*
X180801Y694388D01*
G01X183631Y691179D02*
X195835D01*
G01X181827Y678012D02*
X182040Y677804D01*
X182280Y677679D01*
X182494D01*
X182707Y677804D01*
X182867Y678012D01*
X182947Y678304D01*
X182894Y678596D01*
X182760Y678846D01*
X182520Y679012D01*
X182200Y679096D01*
X182014Y679262D01*
X181934Y679554D01*
X181987Y679846D01*
X182120Y680054D01*
X182307Y680179D01*
X182494D01*
X182680Y680096D01*
X182840Y679887D01*
G01X181680Y691429D02*
Y676429D01*
G01X182787Y692287D02*
Y695487D01*
G01X188987Y692287D02*
X182787D01*
G01X188987Y695487D02*
Y692287D01*
G01X182787Y695487D02*
X188987D01*
G01X191789Y693471D02*
Y695971D01*
X192323D01*
X192536Y695846D01*
X192696Y695679D01*
X192829Y695429D01*
X192936Y695138D01*
X192963Y694721D01*
X192936Y694304D01*
X192829Y694013D01*
X192696Y693763D01*
X192536Y693596D01*
X192323Y693471D01*
X191789D01*
G01X180940Y696456D02*
Y711456D01*
G01X193940Y696456D02*
X180940D01*
G01X193940Y711456D02*
Y696456D01*
G01X194940D02*
Y711456D01*
G01X207940Y696456D02*
X194940D01*
G01X183090Y711780D02*
Y712550D01*
G01D02*
Y721940D01*
G01D02*
X211900D01*
G01X191440Y717506D02*
X188440D01*
G01X191540Y714406D02*
X188340D01*
G01Y720606D02*
X191540D01*
G01X188340Y714406D02*
Y720606D01*
G01X191540D02*
Y714406D01*
G01X186940Y717506D02*
X183940D01*
G01X187040Y714406D02*
X183840D01*
G01X187040Y720606D02*
Y714406D01*
G01X183840Y720606D02*
X187040D01*
G01X183840Y714406D02*
Y720606D01*
G01X195940Y717473D02*
X192940D01*
G01X196040Y714373D02*
X192840D01*
G01Y720573D02*
X196040D01*
G01X192840Y714373D02*
Y720573D01*
G01X182189Y727573D02*
Y712573D01*
G01X191688Y713283D02*
Y713816D01*
X192438D01*
X192688Y713656D01*
X192855Y713470D01*
X192938Y713203D01*
X192855Y712936D01*
X192688Y712750D01*
X192438Y712590D01*
X192146Y712483D01*
X191813Y712430D01*
X191521D01*
X191271Y712483D01*
X190980Y712590D01*
X190730Y712750D01*
X190563Y712910D01*
X190438Y713123D01*
Y713310D01*
X190521Y713523D01*
X190688Y713683D01*
G01X180940Y711456D02*
X193940D01*
G01X194940D02*
X207940D01*
G01X181603Y732121D02*
Y728921D01*
G01X196040Y737556D02*
X192840D01*
G01D02*
Y743756D01*
G01X196040Y726056D02*
X192840D01*
G01Y732256D02*
X196040D01*
G01X192840Y726056D02*
Y732256D01*
G01X191540Y726056D02*
X188340D01*
G01Y732256D02*
X191540D01*
G01X188340Y726056D02*
Y732256D01*
G01X191540D02*
Y726056D01*
G01X187040D02*
X183840D01*
G01X187040Y732256D02*
Y726056D01*
G01X183840Y732256D02*
X187040D01*
G01X183840Y726056D02*
Y732256D01*
G01X191540Y737556D02*
X188340D01*
G01D02*
Y743756D01*
G01X191540D02*
Y737556D01*
G01X187040D02*
X183840D01*
G01X187040Y743756D02*
Y737556D01*
G01X183840D02*
Y743756D01*
G01X192840D02*
X196040D01*
G01X196053Y745311D02*
X192953D01*
Y746270D01*
X193108Y746576D01*
X193315Y746768D01*
X193728Y746845D01*
X194141Y746768D01*
X194400Y746538D01*
X194555Y746270D01*
Y745311D01*
G01Y746270D02*
X196053Y746845D01*
G01Y749178D02*
X196001Y749446D01*
X195846Y749753D01*
X195588Y749945D01*
X195226Y750021D01*
X194865Y749945D01*
X194555Y749715D01*
X194400Y749370D01*
Y748986D01*
X194296Y748756D01*
X194038Y748565D01*
X193676Y748488D01*
X193315Y748603D01*
X193056Y748871D01*
X192953Y749178D01*
X193056Y749485D01*
X193315Y749753D01*
X193676Y749868D01*
X194038Y749791D01*
X194296Y749600D01*
X194400Y749370D01*
Y748986D01*
X194555Y748641D01*
X194865Y748411D01*
X195226Y748335D01*
X195588Y748411D01*
X195846Y748603D01*
X196001Y748910D01*
X196053Y749178D01*
G01X195433Y751435D02*
X195795Y751665D01*
X196001Y751971D01*
X196053Y752316D01*
X196001Y752623D01*
X195743Y752930D01*
X195433Y753121D01*
X195123Y753160D01*
X194761Y753083D01*
X194503Y752815D01*
X194400Y752546D01*
Y752201D01*
G01Y752546D02*
X194245Y752776D01*
X193986Y752968D01*
X193676Y753045D01*
X193366Y752968D01*
X193108Y752776D01*
X192953Y752431D01*
X193005Y752086D01*
X193211Y751741D01*
G01X195691Y754726D02*
X195950Y754995D01*
X196053Y755301D01*
X195950Y755608D01*
X195640Y755876D01*
X195175Y756068D01*
X194710Y756145D01*
X194141D01*
X193676Y756068D01*
X193263Y755876D01*
X193056Y755646D01*
X192953Y755378D01*
X193056Y755071D01*
X193263Y754841D01*
X193573Y754688D01*
X193986Y754611D01*
X194348Y754688D01*
X194710Y754880D01*
X194916Y755110D01*
X194968Y755378D01*
X194865Y755685D01*
X194606Y755915D01*
X194141Y756145D01*
G01X191553Y745311D02*
X188453D01*
Y746270D01*
X188608Y746576D01*
X188815Y746768D01*
X189228Y746845D01*
X189641Y746768D01*
X189900Y746538D01*
X190055Y746270D01*
Y745311D01*
G01Y746270D02*
X191553Y746845D01*
G01Y749178D02*
X191501Y749446D01*
X191346Y749753D01*
X191088Y749945D01*
X190726Y750021D01*
X190365Y749945D01*
X190055Y749715D01*
X189900Y749370D01*
Y748986D01*
X189796Y748756D01*
X189538Y748565D01*
X189176Y748488D01*
X188815Y748603D01*
X188556Y748871D01*
X188453Y749178D01*
X188556Y749485D01*
X188815Y749753D01*
X189176Y749868D01*
X189538Y749791D01*
X189796Y749600D01*
X189900Y749370D01*
Y748986D01*
X190055Y748641D01*
X190365Y748411D01*
X190726Y748335D01*
X191088Y748411D01*
X191346Y748603D01*
X191501Y748910D01*
X191553Y749178D01*
G01Y752738D02*
X188453D01*
X190675Y751320D01*
Y753236D01*
G01X188970Y754650D02*
X188660Y754880D01*
X188505Y755148D01*
X188453Y755455D01*
X188556Y755838D01*
X188815Y756106D01*
X189125Y756183D01*
X189435Y756145D01*
X189693Y755991D01*
X190210Y755225D01*
X190571Y754880D01*
X191088Y754650D01*
X191553Y754573D01*
Y756183D01*
G01X187053Y745311D02*
X183953D01*
Y746270D01*
X184108Y746576D01*
X184315Y746768D01*
X184728Y746845D01*
X185141Y746768D01*
X185400Y746538D01*
X185555Y746270D01*
Y745311D01*
G01Y746270D02*
X187053Y746845D01*
G01Y749178D02*
X187001Y749446D01*
X186846Y749753D01*
X186588Y749945D01*
X186226Y750021D01*
X185865Y749945D01*
X185555Y749715D01*
X185400Y749370D01*
Y748986D01*
X185296Y748756D01*
X185038Y748565D01*
X184676Y748488D01*
X184315Y748603D01*
X184056Y748871D01*
X183953Y749178D01*
X184056Y749485D01*
X184315Y749753D01*
X184676Y749868D01*
X185038Y749791D01*
X185296Y749600D01*
X185400Y749370D01*
Y748986D01*
X185555Y748641D01*
X185865Y748411D01*
X186226Y748335D01*
X186588Y748411D01*
X186846Y748603D01*
X187001Y748910D01*
X187053Y749178D01*
G01Y752738D02*
X183953D01*
X186175Y751320D01*
Y753236D01*
G01X185761Y754650D02*
X185400Y754918D01*
X185193Y755148D01*
X185090Y755455D01*
X185193Y755723D01*
X185400Y755915D01*
X185710Y756068D01*
X186071Y756106D01*
X186381Y756068D01*
X186691Y755915D01*
X186950Y755685D01*
X187053Y755416D01*
X186950Y755110D01*
X186640Y754841D01*
X186175Y754688D01*
X185658Y754650D01*
X184986Y754726D01*
X184625Y754841D01*
X184263Y755033D01*
X184005Y755301D01*
X183953Y755570D01*
X184056Y755838D01*
X184315Y756030D01*
G01X188340Y743756D02*
X191540D01*
G01X183840D02*
X187040D01*
G01X196643Y758948D02*
X193543D01*
Y759907D01*
X193698Y760213D01*
X193905Y760405D01*
X194318Y760482D01*
X194731Y760405D01*
X194990Y760175D01*
X195145Y759907D01*
Y758948D01*
G01Y759907D02*
X196643Y760482D01*
G01Y762815D02*
X196591Y763083D01*
X196436Y763390D01*
X196178Y763582D01*
X195816Y763658D01*
X195455Y763582D01*
X195145Y763352D01*
X194990Y763007D01*
Y762623D01*
X194886Y762393D01*
X194628Y762202D01*
X194266Y762125D01*
X193905Y762240D01*
X193646Y762508D01*
X193543Y762815D01*
X193646Y763122D01*
X193905Y763390D01*
X194266Y763505D01*
X194628Y763428D01*
X194886Y763237D01*
X194990Y763007D01*
Y762623D01*
X195145Y762278D01*
X195455Y762048D01*
X195816Y761972D01*
X196178Y762048D01*
X196436Y762240D01*
X196591Y762547D01*
X196643Y762815D01*
G01X196178Y765072D02*
X196436Y765302D01*
X196591Y765570D01*
X196643Y765915D01*
X196540Y766260D01*
X196333Y766528D01*
X195971Y766720D01*
X195558Y766758D01*
X195145Y766682D01*
X194886Y766490D01*
X194680Y766222D01*
X194628Y765953D01*
X194680Y765685D01*
X194886Y765340D01*
X193543Y765455D01*
Y766490D01*
G01Y769015D02*
X193646Y768708D01*
X193905Y768478D01*
X194215Y768325D01*
X194628Y768210D01*
X195093Y768172D01*
X195558Y768210D01*
X195971Y768325D01*
X196281Y768478D01*
X196540Y768708D01*
X196643Y769015D01*
X196540Y769322D01*
X196281Y769552D01*
X195971Y769705D01*
X195558Y769820D01*
X195093Y769858D01*
X194628Y769820D01*
X194215Y769705D01*
X193905Y769552D01*
X193646Y769322D01*
X193543Y769015D01*
G01X192143Y758948D02*
X189043D01*
Y759907D01*
X189198Y760213D01*
X189405Y760405D01*
X189818Y760482D01*
X190231Y760405D01*
X190490Y760175D01*
X190645Y759907D01*
Y758948D01*
G01Y759907D02*
X192143Y760482D01*
G01Y762815D02*
X192091Y763083D01*
X191936Y763390D01*
X191678Y763582D01*
X191316Y763658D01*
X190955Y763582D01*
X190645Y763352D01*
X190490Y763007D01*
Y762623D01*
X190386Y762393D01*
X190128Y762202D01*
X189766Y762125D01*
X189405Y762240D01*
X189146Y762508D01*
X189043Y762815D01*
X189146Y763122D01*
X189405Y763390D01*
X189766Y763505D01*
X190128Y763428D01*
X190386Y763237D01*
X190490Y763007D01*
Y762623D01*
X190645Y762278D01*
X190955Y762048D01*
X191316Y761972D01*
X191678Y762048D01*
X191936Y762240D01*
X192091Y762547D01*
X192143Y762815D01*
G01X191678Y765072D02*
X191936Y765302D01*
X192091Y765570D01*
X192143Y765915D01*
X192040Y766260D01*
X191833Y766528D01*
X191471Y766720D01*
X191058Y766758D01*
X190645Y766682D01*
X190386Y766490D01*
X190180Y766222D01*
X190128Y765953D01*
X190180Y765685D01*
X190386Y765340D01*
X189043Y765455D01*
Y766490D01*
G01X192143Y769015D02*
X189043D01*
X189663Y768555D01*
G01X192143D02*
Y769475D01*
G01X187643Y758948D02*
X184543D01*
Y759907D01*
X184698Y760213D01*
X184905Y760405D01*
X185318Y760482D01*
X185731Y760405D01*
X185990Y760175D01*
X186145Y759907D01*
Y758948D01*
G01Y759907D02*
X187643Y760482D01*
G01Y762815D02*
X187591Y763083D01*
X187436Y763390D01*
X187178Y763582D01*
X186816Y763658D01*
X186455Y763582D01*
X186145Y763352D01*
X185990Y763007D01*
Y762623D01*
X185886Y762393D01*
X185628Y762202D01*
X185266Y762125D01*
X184905Y762240D01*
X184646Y762508D01*
X184543Y762815D01*
X184646Y763122D01*
X184905Y763390D01*
X185266Y763505D01*
X185628Y763428D01*
X185886Y763237D01*
X185990Y763007D01*
Y762623D01*
X186145Y762278D01*
X186455Y762048D01*
X186816Y761972D01*
X187178Y762048D01*
X187436Y762240D01*
X187591Y762547D01*
X187643Y762815D01*
G01X187178Y765072D02*
X187436Y765302D01*
X187591Y765570D01*
X187643Y765915D01*
X187540Y766260D01*
X187333Y766528D01*
X186971Y766720D01*
X186558Y766758D01*
X186145Y766682D01*
X185886Y766490D01*
X185680Y766222D01*
X185628Y765953D01*
X185680Y765685D01*
X185886Y765340D01*
X184543Y765455D01*
Y766490D01*
G01X185060Y768287D02*
X184750Y768517D01*
X184595Y768785D01*
X184543Y769092D01*
X184646Y769475D01*
X184905Y769743D01*
X185215Y769820D01*
X185525Y769782D01*
X185783Y769628D01*
X186300Y768862D01*
X186661Y768517D01*
X187178Y768287D01*
X187643Y768210D01*
Y769820D01*
G01X203540Y25816D02*
Y8416D01*
G01D02*
X196140D01*
G01D02*
Y25816D01*
G01X208224Y15943D02*
X205124D01*
Y16863D01*
X205279Y17170D01*
X205641Y17400D01*
X206054Y17477D01*
X206467Y17400D01*
X206777Y17208D01*
X206932Y16863D01*
Y15943D01*
G01X208224Y19043D02*
X205124D01*
Y20002D01*
X205279Y20308D01*
X205486Y20500D01*
X205899Y20577D01*
X206312Y20500D01*
X206571Y20270D01*
X206726Y20002D01*
Y19043D01*
G01Y20002D02*
X208224Y20577D01*
G01X207604Y22067D02*
X207966Y22297D01*
X208172Y22603D01*
X208224Y22948D01*
X208172Y23255D01*
X207914Y23562D01*
X207604Y23753D01*
X207294Y23792D01*
X206932Y23715D01*
X206674Y23447D01*
X206571Y23178D01*
Y22833D01*
G01Y23178D02*
X206416Y23408D01*
X206157Y23600D01*
X205847Y23677D01*
X205537Y23600D01*
X205279Y23408D01*
X205124Y23063D01*
X205176Y22718D01*
X205382Y22373D01*
G01X205641Y25282D02*
X205331Y25512D01*
X205176Y25780D01*
X205124Y26087D01*
X205227Y26470D01*
X205486Y26738D01*
X205796Y26815D01*
X206106Y26777D01*
X206364Y26623D01*
X206881Y25857D01*
X207242Y25512D01*
X207759Y25282D01*
X208224Y25205D01*
Y26815D01*
G01X196140Y25816D02*
X203540D01*
G01X202120Y58961D02*
X199020D01*
Y59881D01*
X199175Y60188D01*
X199537Y60418D01*
X199950Y60495D01*
X200363Y60418D01*
X200673Y60226D01*
X200828Y59881D01*
Y58961D01*
G01X199278Y63671D02*
X199123Y63441D01*
X199020Y63173D01*
Y62866D01*
X199175Y62521D01*
X199433Y62253D01*
X199743Y62061D01*
X200260Y61908D01*
X200725Y61870D01*
X201190Y61946D01*
X201500Y62061D01*
X201810Y62291D01*
X202017Y62560D01*
X202120Y62828D01*
Y63096D01*
X202017Y63365D01*
X201862Y63595D01*
X201655Y63786D01*
G01X202120Y65928D02*
X202068Y66196D01*
X201913Y66503D01*
X201655Y66695D01*
X201293Y66771D01*
X200932Y66695D01*
X200622Y66465D01*
X200467Y66120D01*
Y65736D01*
X200363Y65506D01*
X200105Y65315D01*
X199743Y65238D01*
X199382Y65353D01*
X199123Y65621D01*
X199020Y65928D01*
X199123Y66235D01*
X199382Y66503D01*
X199743Y66618D01*
X200105Y66541D01*
X200363Y66350D01*
X200467Y66120D01*
Y65736D01*
X200622Y65391D01*
X200932Y65161D01*
X201293Y65085D01*
X201655Y65161D01*
X201913Y65353D01*
X202068Y65660D01*
X202120Y65928D01*
G01X201500Y68185D02*
X201862Y68415D01*
X202068Y68721D01*
X202120Y69066D01*
X202068Y69373D01*
X201810Y69680D01*
X201500Y69871D01*
X201190Y69910D01*
X200828Y69833D01*
X200570Y69565D01*
X200467Y69296D01*
Y68951D01*
G01Y69296D02*
X200312Y69526D01*
X200053Y69718D01*
X199743Y69795D01*
X199433Y69718D01*
X199175Y69526D01*
X199020Y69181D01*
X199072Y68836D01*
X199278Y68491D01*
G01X206360Y58961D02*
X203260D01*
Y59881D01*
X203415Y60188D01*
X203777Y60418D01*
X204190Y60495D01*
X204603Y60418D01*
X204913Y60226D01*
X205068Y59881D01*
Y58961D01*
G01X203518Y63671D02*
X203363Y63441D01*
X203260Y63173D01*
Y62866D01*
X203415Y62521D01*
X203673Y62253D01*
X203983Y62061D01*
X204500Y61908D01*
X204965Y61870D01*
X205430Y61946D01*
X205740Y62061D01*
X206050Y62291D01*
X206257Y62560D01*
X206360Y62828D01*
Y63096D01*
X206257Y63365D01*
X206102Y63595D01*
X205895Y63786D01*
G01X206360Y65928D02*
X206308Y66196D01*
X206153Y66503D01*
X205895Y66695D01*
X205533Y66771D01*
X205172Y66695D01*
X204862Y66465D01*
X204707Y66120D01*
Y65736D01*
X204603Y65506D01*
X204345Y65315D01*
X203983Y65238D01*
X203622Y65353D01*
X203363Y65621D01*
X203260Y65928D01*
X203363Y66235D01*
X203622Y66503D01*
X203983Y66618D01*
X204345Y66541D01*
X204603Y66350D01*
X204707Y66120D01*
Y65736D01*
X204862Y65391D01*
X205172Y65161D01*
X205533Y65085D01*
X205895Y65161D01*
X206153Y65353D01*
X206308Y65660D01*
X206360Y65928D01*
G01Y69488D02*
X203260D01*
X205482Y68070D01*
Y69986D01*
G01X210517Y58961D02*
X207417D01*
Y59881D01*
X207572Y60188D01*
X207934Y60418D01*
X208347Y60495D01*
X208760Y60418D01*
X209070Y60226D01*
X209225Y59881D01*
Y58961D01*
G01X207675Y63671D02*
X207520Y63441D01*
X207417Y63173D01*
Y62866D01*
X207572Y62521D01*
X207830Y62253D01*
X208140Y62061D01*
X208657Y61908D01*
X209122Y61870D01*
X209587Y61946D01*
X209897Y62061D01*
X210207Y62291D01*
X210414Y62560D01*
X210517Y62828D01*
Y63096D01*
X210414Y63365D01*
X210259Y63595D01*
X210052Y63786D01*
G01X210517Y65928D02*
X210465Y66196D01*
X210310Y66503D01*
X210052Y66695D01*
X209690Y66771D01*
X209329Y66695D01*
X209019Y66465D01*
X208864Y66120D01*
Y65736D01*
X208760Y65506D01*
X208502Y65315D01*
X208140Y65238D01*
X207779Y65353D01*
X207520Y65621D01*
X207417Y65928D01*
X207520Y66235D01*
X207779Y66503D01*
X208140Y66618D01*
X208502Y66541D01*
X208760Y66350D01*
X208864Y66120D01*
Y65736D01*
X209019Y65391D01*
X209329Y65161D01*
X209690Y65085D01*
X210052Y65161D01*
X210310Y65353D01*
X210465Y65660D01*
X210517Y65928D01*
G01X207934Y68300D02*
X207624Y68530D01*
X207469Y68798D01*
X207417Y69105D01*
X207520Y69488D01*
X207779Y69756D01*
X208089Y69833D01*
X208399Y69795D01*
X208657Y69641D01*
X209174Y68875D01*
X209535Y68530D01*
X210052Y68300D01*
X210517Y68223D01*
Y69833D01*
G01X199548Y72174D02*
X199740Y71864D01*
X199970Y71657D01*
X200238Y71554D01*
X200545Y71657D01*
X200775Y71864D01*
X201005Y72174D01*
X201082Y72587D01*
Y74654D01*
G01X202687Y74137D02*
X202917Y74447D01*
X203185Y74602D01*
X203492Y74654D01*
X203875Y74551D01*
X204143Y74292D01*
X204220Y73982D01*
X204182Y73672D01*
X204028Y73414D01*
X203262Y72897D01*
X202917Y72536D01*
X202687Y72019D01*
X202610Y71554D01*
X204220D01*
G01X199324Y157195D02*
X199094Y157350D01*
X198826Y157453D01*
X198519D01*
X198174Y157298D01*
X197906Y157040D01*
X197714Y156730D01*
X197561Y156213D01*
X197523Y155748D01*
X197599Y155283D01*
X197714Y154973D01*
X197944Y154663D01*
X198213Y154456D01*
X198481Y154353D01*
X198749D01*
X199018Y154456D01*
X199248Y154611D01*
X199439Y154818D01*
G01X200853Y155645D02*
X201121Y156006D01*
X201351Y156213D01*
X201658Y156316D01*
X201926Y156213D01*
X202118Y156006D01*
X202271Y155696D01*
X202309Y155335D01*
X202271Y155025D01*
X202118Y154715D01*
X201888Y154456D01*
X201619Y154353D01*
X201313Y154456D01*
X201044Y154766D01*
X200891Y155231D01*
X200853Y155748D01*
X200929Y156420D01*
X201044Y156781D01*
X201236Y157143D01*
X201504Y157401D01*
X201773Y157453D01*
X202041Y157350D01*
X202233Y157091D01*
G01X204681Y154353D02*
Y157453D01*
X204221Y156833D01*
G01Y154353D02*
X205141D01*
G01X207053Y155645D02*
X207321Y156006D01*
X207551Y156213D01*
X207858Y156316D01*
X208126Y156213D01*
X208318Y156006D01*
X208471Y155696D01*
X208509Y155335D01*
X208471Y155025D01*
X208318Y154715D01*
X208088Y154456D01*
X207819Y154353D01*
X207513Y154456D01*
X207244Y154766D01*
X207091Y155231D01*
X207053Y155748D01*
X207129Y156420D01*
X207244Y156781D01*
X207436Y157143D01*
X207704Y157401D01*
X207973Y157453D01*
X208241Y157350D01*
X208433Y157091D01*
G01X211324Y157195D02*
X211094Y157350D01*
X210826Y157453D01*
X210519D01*
X210174Y157298D01*
X209906Y157040D01*
X209714Y156730D01*
X209561Y156213D01*
X209523Y155748D01*
X209599Y155283D01*
X209714Y154973D01*
X209944Y154663D01*
X210213Y154456D01*
X210481Y154353D01*
X210749D01*
X211018Y154456D01*
X211248Y154611D01*
X211439Y154818D01*
G01X212853Y155645D02*
X213121Y156006D01*
X213351Y156213D01*
X213658Y156316D01*
X213926Y156213D01*
X214118Y156006D01*
X214271Y155696D01*
X214309Y155335D01*
X214271Y155025D01*
X214118Y154715D01*
X213888Y154456D01*
X213619Y154353D01*
X213313Y154456D01*
X213044Y154766D01*
X212891Y155231D01*
X212853Y155748D01*
X212929Y156420D01*
X213044Y156781D01*
X213236Y157143D01*
X213504Y157401D01*
X213773Y157453D01*
X214041Y157350D01*
X214233Y157091D01*
G01X216681Y154353D02*
Y157453D01*
X216221Y156833D01*
G01Y154353D02*
X217141D01*
G01X219129Y154715D02*
X219398Y154456D01*
X219704Y154353D01*
X220011Y154456D01*
X220279Y154766D01*
X220471Y155231D01*
X220548Y155696D01*
Y156265D01*
X220471Y156730D01*
X220279Y157143D01*
X220049Y157350D01*
X219781Y157453D01*
X219474Y157350D01*
X219244Y157143D01*
X219091Y156833D01*
X219014Y156420D01*
X219091Y156058D01*
X219283Y155696D01*
X219513Y155490D01*
X219781Y155438D01*
X220088Y155541D01*
X220318Y155800D01*
X220548Y156265D01*
G01X201811Y169109D02*
Y172209D01*
X202770D01*
X203076Y172054D01*
X203268Y171847D01*
X203345Y171434D01*
X203268Y171021D01*
X203038Y170762D01*
X202770Y170607D01*
X201811D01*
G01X202770D02*
X203345Y169109D01*
G01X205678D02*
Y172209D01*
X205218Y171589D01*
G01Y169109D02*
X206138D01*
G01X208778Y172209D02*
X208471Y172106D01*
X208241Y171847D01*
X208088Y171537D01*
X207973Y171124D01*
X207935Y170659D01*
X207973Y170194D01*
X208088Y169781D01*
X208241Y169471D01*
X208471Y169212D01*
X208778Y169109D01*
X209085Y169212D01*
X209315Y169471D01*
X209468Y169781D01*
X209583Y170194D01*
X209621Y170659D01*
X209583Y171124D01*
X209468Y171537D01*
X209315Y171847D01*
X209085Y172106D01*
X208778Y172209D01*
G01X211878Y169109D02*
Y172209D01*
X211418Y171589D01*
G01Y169109D02*
X212338D01*
G01X215438D02*
Y172209D01*
X214020Y169987D01*
X215936D01*
G01X196261Y159708D02*
X198483D01*
X198948Y159861D01*
X199258Y160168D01*
X199361Y160551D01*
X199258Y160934D01*
X198948Y161241D01*
X198483Y161394D01*
X196261D01*
G01X199361Y163651D02*
X199309Y163919D01*
X199154Y164226D01*
X198896Y164418D01*
X198534Y164494D01*
X198173Y164418D01*
X197863Y164188D01*
X197708Y163843D01*
Y163459D01*
X197604Y163229D01*
X197346Y163038D01*
X196984Y162961D01*
X196623Y163076D01*
X196364Y163344D01*
X196261Y163651D01*
X196364Y163958D01*
X196623Y164226D01*
X196984Y164341D01*
X197346Y164264D01*
X197604Y164073D01*
X197708Y163843D01*
Y163459D01*
X197863Y163114D01*
X198173Y162884D01*
X198534Y162808D01*
X198896Y162884D01*
X199154Y163076D01*
X199309Y163383D01*
X199361Y163651D01*
G01X198069Y166023D02*
X197708Y166291D01*
X197501Y166521D01*
X197398Y166828D01*
X197501Y167096D01*
X197708Y167288D01*
X198018Y167441D01*
X198379Y167479D01*
X198689Y167441D01*
X198999Y167288D01*
X199258Y167058D01*
X199361Y166789D01*
X199258Y166483D01*
X198948Y166214D01*
X198483Y166061D01*
X197966Y166023D01*
X197294Y166099D01*
X196933Y166214D01*
X196571Y166406D01*
X196313Y166674D01*
X196261Y166943D01*
X196364Y167211D01*
X196623Y167403D01*
G01X200483Y159708D02*
X202705D01*
X203170Y159861D01*
X203480Y160168D01*
X203583Y160551D01*
X203480Y160934D01*
X203170Y161241D01*
X202705Y161394D01*
X200483D01*
G01X203583Y163651D02*
X203531Y163919D01*
X203376Y164226D01*
X203118Y164418D01*
X202756Y164494D01*
X202395Y164418D01*
X202085Y164188D01*
X201930Y163843D01*
Y163459D01*
X201826Y163229D01*
X201568Y163038D01*
X201206Y162961D01*
X200845Y163076D01*
X200586Y163344D01*
X200483Y163651D01*
X200586Y163958D01*
X200845Y164226D01*
X201206Y164341D01*
X201568Y164264D01*
X201826Y164073D01*
X201930Y163843D01*
Y163459D01*
X202085Y163114D01*
X202395Y162884D01*
X202756Y162808D01*
X203118Y162884D01*
X203376Y163076D01*
X203531Y163383D01*
X203583Y163651D01*
G01Y166751D02*
X203531Y167019D01*
X203376Y167326D01*
X203118Y167518D01*
X202756Y167594D01*
X202395Y167518D01*
X202085Y167288D01*
X201930Y166943D01*
Y166559D01*
X201826Y166329D01*
X201568Y166138D01*
X201206Y166061D01*
X200845Y166176D01*
X200586Y166444D01*
X200483Y166751D01*
X200586Y167058D01*
X200845Y167326D01*
X201206Y167441D01*
X201568Y167364D01*
X201826Y167173D01*
X201930Y166943D01*
Y166559D01*
X202085Y166214D01*
X202395Y165984D01*
X202756Y165908D01*
X203118Y165984D01*
X203376Y166176D01*
X203531Y166483D01*
X203583Y166751D01*
G01X204701Y159708D02*
X206923D01*
X207388Y159861D01*
X207698Y160168D01*
X207801Y160551D01*
X207698Y160934D01*
X207388Y161241D01*
X206923Y161394D01*
X204701D01*
G01X207801Y163651D02*
X207749Y163919D01*
X207594Y164226D01*
X207336Y164418D01*
X206974Y164494D01*
X206613Y164418D01*
X206303Y164188D01*
X206148Y163843D01*
Y163459D01*
X206044Y163229D01*
X205786Y163038D01*
X205424Y162961D01*
X205063Y163076D01*
X204804Y163344D01*
X204701Y163651D01*
X204804Y163958D01*
X205063Y164226D01*
X205424Y164341D01*
X205786Y164264D01*
X206044Y164073D01*
X206148Y163843D01*
Y163459D01*
X206303Y163114D01*
X206613Y162884D01*
X206974Y162808D01*
X207336Y162884D01*
X207594Y163076D01*
X207749Y163383D01*
X207801Y163651D01*
G01Y167211D02*
X204701D01*
X206923Y165793D01*
Y167709D01*
G01X198633Y177754D02*
X200855D01*
X201320Y177907D01*
X201630Y178214D01*
X201733Y178597D01*
X201630Y178980D01*
X201320Y179287D01*
X200855Y179440D01*
X198633D01*
G01X201371Y181045D02*
X201630Y181314D01*
X201733Y181620D01*
X201630Y181927D01*
X201320Y182195D01*
X200855Y182387D01*
X200390Y182464D01*
X199821D01*
X199356Y182387D01*
X198943Y182195D01*
X198736Y181965D01*
X198633Y181697D01*
X198736Y181390D01*
X198943Y181160D01*
X199253Y181007D01*
X199666Y180930D01*
X200028Y181007D01*
X200390Y181199D01*
X200596Y181429D01*
X200648Y181697D01*
X200545Y182004D01*
X200286Y182234D01*
X199821Y182464D01*
G01X201733Y184720D02*
X201061Y184797D01*
X200493Y184912D01*
X199976Y185065D01*
X199408Y185257D01*
X198633Y185564D01*
Y184030D01*
G01X202633Y177754D02*
X204855D01*
X205320Y177907D01*
X205630Y178214D01*
X205733Y178597D01*
X205630Y178980D01*
X205320Y179287D01*
X204855Y179440D01*
X202633D01*
G01X205371Y181045D02*
X205630Y181314D01*
X205733Y181620D01*
X205630Y181927D01*
X205320Y182195D01*
X204855Y182387D01*
X204390Y182464D01*
X203821D01*
X203356Y182387D01*
X202943Y182195D01*
X202736Y181965D01*
X202633Y181697D01*
X202736Y181390D01*
X202943Y181160D01*
X203253Y181007D01*
X203666Y180930D01*
X204028Y181007D01*
X204390Y181199D01*
X204596Y181429D01*
X204648Y181697D01*
X204545Y182004D01*
X204286Y182234D01*
X203821Y182464D01*
G01X205733Y185257D02*
X202633D01*
X204855Y183839D01*
Y185755D01*
G01X197460Y190630D02*
X218480D01*
G01X197460Y206010D02*
Y190630D01*
G01X214304Y211738D02*
X213924Y211988D01*
X213481Y212155D01*
X212974D01*
X212404Y211905D01*
X211961Y211488D01*
X211644Y210988D01*
X211391Y210155D01*
X211328Y209405D01*
X211454Y208655D01*
X211644Y208155D01*
X212024Y207655D01*
X212468Y207322D01*
X212911Y207155D01*
X213354D01*
X213798Y207322D01*
X214178Y207572D01*
X214494Y207905D01*
G01X216744Y207155D02*
Y212155D01*
X218264D01*
X218771Y211905D01*
X219151Y211322D01*
X219278Y210655D01*
X219151Y209988D01*
X218834Y209488D01*
X218264Y209238D01*
X216744D01*
G01X221718Y212155D02*
Y208572D01*
X221971Y207822D01*
X222478Y207322D01*
X223111Y207155D01*
X223744Y207322D01*
X224251Y207822D01*
X224504Y208572D01*
Y212155D01*
G01X208955Y215255D02*
X228095D01*
Y204587D01*
X208485D01*
Y215255D01*
X208955D01*
G01X196749Y361256D02*
Y363756D01*
X196429Y363256D01*
G01Y361256D02*
X197069D01*
G01X198949D02*
X199136Y361298D01*
X199349Y361423D01*
X199482Y361631D01*
X199536Y361923D01*
X199482Y362214D01*
X199322Y362464D01*
X199082Y362589D01*
X198816D01*
X198656Y362673D01*
X198522Y362881D01*
X198469Y363173D01*
X198549Y363464D01*
X198736Y363673D01*
X198949Y363756D01*
X199162Y363673D01*
X199349Y363464D01*
X199429Y363173D01*
X199376Y362881D01*
X199242Y362673D01*
X199082Y362589D01*
X198816D01*
X198576Y362464D01*
X198416Y362214D01*
X198362Y361923D01*
X198416Y361631D01*
X198549Y361423D01*
X198762Y361298D01*
X198949Y361256D01*
G01X198749Y356756D02*
Y359256D01*
X198429Y358756D01*
G01Y356756D02*
X199069D01*
G01X200496Y357048D02*
X200682Y356839D01*
X200896Y356756D01*
X201109Y356839D01*
X201296Y357089D01*
X201429Y357464D01*
X201482Y357839D01*
Y358298D01*
X201429Y358673D01*
X201296Y359006D01*
X201136Y359173D01*
X200949Y359256D01*
X200736Y359173D01*
X200576Y359006D01*
X200469Y358756D01*
X200416Y358423D01*
X200469Y358131D01*
X200602Y357839D01*
X200762Y357673D01*
X200949Y357631D01*
X201162Y357714D01*
X201322Y357923D01*
X201482Y358298D01*
G01X200242Y363339D02*
X200402Y363589D01*
X200589Y363714D01*
X200802Y363756D01*
X201069Y363673D01*
X201256Y363464D01*
X201309Y363214D01*
X201282Y362964D01*
X201176Y362756D01*
X200642Y362339D01*
X200402Y362048D01*
X200242Y361631D01*
X200189Y361256D01*
X201309D01*
G01X202949Y363756D02*
X202736Y363673D01*
X202576Y363464D01*
X202469Y363214D01*
X202389Y362881D01*
X202362Y362506D01*
X202389Y362131D01*
X202469Y361798D01*
X202576Y361548D01*
X202736Y361339D01*
X202949Y361256D01*
X203162Y361339D01*
X203322Y361548D01*
X203429Y361798D01*
X203509Y362131D01*
X203536Y362506D01*
X203509Y362881D01*
X203429Y363214D01*
X203322Y363464D01*
X203162Y363673D01*
X202949Y363756D01*
G01X202242Y358839D02*
X202402Y359089D01*
X202589Y359214D01*
X202802Y359256D01*
X203069Y359173D01*
X203256Y358964D01*
X203309Y358714D01*
X203282Y358464D01*
X203176Y358256D01*
X202642Y357839D01*
X202402Y357548D01*
X202242Y357131D01*
X202189Y356756D01*
X203309D01*
G01X204949D02*
Y359256D01*
X204629Y358756D01*
G01Y356756D02*
X205269D01*
G01X204242Y363339D02*
X204402Y363589D01*
X204589Y363714D01*
X204802Y363756D01*
X205069Y363673D01*
X205256Y363464D01*
X205309Y363214D01*
X205282Y362964D01*
X205176Y362756D01*
X204642Y362339D01*
X204402Y362048D01*
X204242Y361631D01*
X204189Y361256D01*
X205309D01*
G01X206442Y363339D02*
X206602Y363589D01*
X206789Y363714D01*
X207002Y363756D01*
X207269Y363673D01*
X207456Y363464D01*
X207509Y363214D01*
X207482Y362964D01*
X207376Y362756D01*
X206842Y362339D01*
X206602Y362048D01*
X206442Y361631D01*
X206389Y361256D01*
X207509D01*
G01X206242Y358839D02*
X206402Y359089D01*
X206589Y359214D01*
X206802Y359256D01*
X207069Y359173D01*
X207256Y358964D01*
X207309Y358714D01*
X207282Y358464D01*
X207176Y358256D01*
X206642Y357839D01*
X206402Y357548D01*
X206242Y357131D01*
X206189Y356756D01*
X207309D01*
G01X208362Y357256D02*
X208522Y356964D01*
X208736Y356798D01*
X208976Y356756D01*
X209189Y356798D01*
X209402Y357006D01*
X209536Y357256D01*
X209562Y357506D01*
X209509Y357798D01*
X209322Y358006D01*
X209136Y358089D01*
X208896D01*
G01X209136D02*
X209296Y358214D01*
X209429Y358423D01*
X209482Y358673D01*
X209429Y358923D01*
X209296Y359131D01*
X209056Y359256D01*
X208816Y359214D01*
X208576Y359048D01*
G01X208242Y363339D02*
X208402Y363589D01*
X208589Y363714D01*
X208802Y363756D01*
X209069Y363673D01*
X209256Y363464D01*
X209309Y363214D01*
X209282Y362964D01*
X209176Y362756D01*
X208642Y362339D01*
X208402Y362048D01*
X208242Y361631D01*
X208189Y361256D01*
X209309D01*
G01X211269D02*
Y363756D01*
X210282Y361964D01*
X211616D01*
G01X210242Y358839D02*
X210402Y359089D01*
X210589Y359214D01*
X210802Y359256D01*
X211069Y359173D01*
X211256Y358964D01*
X211309Y358714D01*
X211282Y358464D01*
X211176Y358256D01*
X210642Y357839D01*
X210402Y357548D01*
X210242Y357131D01*
X210189Y356756D01*
X211309D01*
G01X212362Y357131D02*
X212522Y356923D01*
X212709Y356798D01*
X212949Y356756D01*
X213189Y356839D01*
X213376Y357006D01*
X213509Y357298D01*
X213536Y357631D01*
X213482Y357964D01*
X213349Y358173D01*
X213162Y358339D01*
X212976Y358381D01*
X212789Y358339D01*
X212549Y358173D01*
X212629Y359256D01*
X213349D01*
G01X200420Y375201D02*
Y372201D01*
G01X203520Y372101D02*
X197320D01*
G01D02*
Y375301D01*
G01D02*
X203520D01*
G01D02*
Y372101D01*
G01X206300Y376440D02*
X240250D01*
G01X206300Y384310D02*
Y376440D01*
G01X208510Y384940D02*
X240220D01*
G01X210160Y390178D02*
X213160D01*
G01X213260Y387078D02*
X210060D01*
G01D02*
Y393278D01*
G01X210329Y383848D02*
Y377648D01*
G01X207129D02*
Y383848D01*
G01D02*
X210329D01*
G01Y377648D02*
X207129D01*
G01X211129D02*
Y383848D01*
G01D02*
X214329D01*
G01Y377648D02*
X211129D01*
G01X200556Y381871D02*
Y384371D01*
X200236Y383871D01*
G01Y381871D02*
X200876D01*
G01X202249Y382913D02*
X202436Y383204D01*
X202596Y383371D01*
X202809Y383454D01*
X202996Y383371D01*
X203129Y383204D01*
X203236Y382954D01*
X203263Y382663D01*
X203236Y382413D01*
X203129Y382163D01*
X202969Y381954D01*
X202783Y381871D01*
X202569Y381954D01*
X202383Y382204D01*
X202276Y382579D01*
X202249Y382996D01*
X202303Y383538D01*
X202383Y383829D01*
X202516Y384121D01*
X202703Y384329D01*
X202889Y384371D01*
X203076Y384288D01*
X203209Y384079D01*
G01X206680Y385631D02*
Y388131D01*
X206360Y387631D01*
G01Y385631D02*
X207000D01*
G01X198730Y384170D02*
Y382170D01*
G01X202456Y385255D02*
X205500D01*
G01D02*
Y388269D01*
G01X210200Y397114D02*
X213200D01*
G01X213300Y394014D02*
X210100D01*
G01D02*
Y400214D01*
G01D02*
X213300D01*
G01X210060Y393278D02*
X213260D01*
G01X202737Y402739D02*
X202897Y402531D01*
X203084Y402406D01*
X203324Y402364D01*
X203564Y402447D01*
X203751Y402614D01*
X203884Y402906D01*
X203911Y403239D01*
X203857Y403572D01*
X203724Y403781D01*
X203537Y403947D01*
X203351Y403989D01*
X203164Y403947D01*
X202924Y403781D01*
X203004Y404864D01*
X203724D01*
G01X207380Y395509D02*
Y398009D01*
X206393Y396217D01*
X207727D01*
G01X201294Y402389D02*
Y404389D01*
G01X205500Y398347D02*
Y401396D01*
G01D02*
X202437D01*
G01X207259Y442946D02*
Y446046D01*
X208179D01*
X208486Y445891D01*
X208716Y445529D01*
X208793Y445116D01*
X208716Y444703D01*
X208524Y444393D01*
X208179Y444238D01*
X207259D01*
G01X210359Y446046D02*
Y442946D01*
X211893D01*
G01X213498Y445529D02*
X213728Y445839D01*
X213996Y445994D01*
X214303Y446046D01*
X214686Y445943D01*
X214954Y445684D01*
X215031Y445374D01*
X214993Y445064D01*
X214839Y444806D01*
X214073Y444289D01*
X213728Y443928D01*
X213498Y443411D01*
X213421Y442946D01*
X215031D01*
G01X198709Y454191D02*
Y446791D01*
G01X202009Y471453D02*
Y468453D01*
G01X205109Y471553D02*
Y468353D01*
G01X198909D02*
Y471553D01*
G01X205109Y468353D02*
X198909D01*
G01X200409Y460953D02*
Y467153D01*
G01X203609Y460953D02*
X200409D01*
G01X203609Y467153D02*
Y460953D01*
G01X200409Y467153D02*
X203609D01*
G01X204238Y457123D02*
Y459623D01*
X203918Y459123D01*
G01Y457123D02*
X204558D01*
G01X204909Y464991D02*
Y467491D01*
X203922Y465699D01*
X205256D01*
G01X206009Y459753D02*
Y472353D01*
G01X221409Y459753D02*
X206009D01*
G01X207709Y466053D02*
X206213Y465653D01*
G01Y466453D02*
X207709Y466053D01*
G01X201381Y483309D02*
X205896D01*
X206841Y483622D01*
X207471Y484249D01*
X207681Y485032D01*
X207471Y485815D01*
X206841Y486442D01*
X205896Y486755D01*
X201381D01*
G01X207681Y491332D02*
X201381D01*
X202641Y490392D01*
G01X207681D02*
Y492272D01*
G01Y498572D02*
X201381D01*
X205896Y495674D01*
Y499590D01*
G01X236938Y481534D02*
X209417D01*
G01D02*
Y541123D01*
G01X202009Y472753D02*
Y475753D01*
G01X198909Y472653D02*
Y475853D01*
G01X205109Y472653D02*
X198909D01*
G01X205109Y475853D02*
Y472653D01*
G01X198909Y475853D02*
X205109D01*
G01X198909Y471553D02*
X205109D01*
G01X206009Y473653D02*
Y478653D01*
G01D02*
X216209D01*
G01Y473653D02*
X206009D01*
G01X210609Y473853D02*
Y478453D01*
G01X206009Y472353D02*
X221409D01*
G01X196193Y512123D02*
Y493164D01*
G01Y537123D02*
Y518623D01*
G01Y569542D02*
Y540123D01*
G01X209417Y543623D02*
Y559123D01*
G01X197443Y546337D02*
Y549437D01*
X198402D01*
X198708Y549282D01*
X198900Y549075D01*
X198977Y548662D01*
X198900Y548249D01*
X198670Y547990D01*
X198402Y547835D01*
X197443D01*
G01X198402D02*
X198977Y546337D01*
G01X200467Y546802D02*
X200697Y546544D01*
X200965Y546389D01*
X201310Y546337D01*
X201655Y546440D01*
X201923Y546647D01*
X202115Y547009D01*
X202153Y547422D01*
X202077Y547835D01*
X201885Y548094D01*
X201617Y548300D01*
X201348Y548352D01*
X201080Y548300D01*
X200735Y548094D01*
X200850Y549437D01*
X201885D01*
G01X204870Y546337D02*
Y549437D01*
X203452Y547215D01*
X205368D01*
G01X206667Y546802D02*
X206897Y546544D01*
X207165Y546389D01*
X207510Y546337D01*
X207855Y546440D01*
X208123Y546647D01*
X208315Y547009D01*
X208353Y547422D01*
X208277Y547835D01*
X208085Y548094D01*
X207817Y548300D01*
X207548Y548352D01*
X207280Y548300D01*
X206935Y548094D01*
X207050Y549437D01*
X208085D01*
G01X209417Y564123D02*
Y580352D01*
G01X197586Y562736D02*
Y565836D01*
X198545D01*
X198851Y565681D01*
X199043Y565474D01*
X199120Y565061D01*
X199043Y564648D01*
X198813Y564389D01*
X198545Y564234D01*
X197586D01*
G01X198545D02*
X199120Y562736D01*
G01X200610Y563201D02*
X200840Y562943D01*
X201108Y562788D01*
X201453Y562736D01*
X201798Y562839D01*
X202066Y563046D01*
X202258Y563408D01*
X202296Y563821D01*
X202220Y564234D01*
X202028Y564493D01*
X201760Y564699D01*
X201491Y564751D01*
X201223Y564699D01*
X200878Y564493D01*
X200993Y565836D01*
X202028D01*
G01X205013Y562736D02*
Y565836D01*
X203595Y563614D01*
X205511D01*
G01X206810Y563356D02*
X207040Y562994D01*
X207346Y562788D01*
X207691Y562736D01*
X207998Y562788D01*
X208305Y563046D01*
X208496Y563356D01*
X208535Y563666D01*
X208458Y564028D01*
X208190Y564286D01*
X207921Y564389D01*
X207576D01*
G01X207921D02*
X208151Y564544D01*
X208343Y564803D01*
X208420Y565113D01*
X208343Y565423D01*
X208151Y565681D01*
X207806Y565836D01*
X207461Y565784D01*
X207116Y565578D01*
G01X197586Y554691D02*
Y557791D01*
X198545D01*
X198851Y557636D01*
X199043Y557429D01*
X199120Y557016D01*
X199043Y556603D01*
X198813Y556344D01*
X198545Y556189D01*
X197586D01*
G01X198545D02*
X199120Y554691D01*
G01X200610Y555156D02*
X200840Y554898D01*
X201108Y554743D01*
X201453Y554691D01*
X201798Y554794D01*
X202066Y555001D01*
X202258Y555363D01*
X202296Y555776D01*
X202220Y556189D01*
X202028Y556448D01*
X201760Y556654D01*
X201491Y556706D01*
X201223Y556654D01*
X200878Y556448D01*
X200993Y557791D01*
X202028D01*
G01X205013Y554691D02*
Y557791D01*
X203595Y555569D01*
X205511D01*
G01X207001Y555053D02*
X207270Y554794D01*
X207576Y554691D01*
X207883Y554794D01*
X208151Y555104D01*
X208343Y555569D01*
X208420Y556034D01*
Y556603D01*
X208343Y557068D01*
X208151Y557481D01*
X207921Y557688D01*
X207653Y557791D01*
X207346Y557688D01*
X207116Y557481D01*
X206963Y557171D01*
X206886Y556758D01*
X206963Y556396D01*
X207155Y556034D01*
X207385Y555828D01*
X207653Y555776D01*
X207960Y555879D01*
X208190Y556138D01*
X208420Y556603D01*
G01X197586Y558665D02*
Y561765D01*
X198545D01*
X198851Y561610D01*
X199043Y561403D01*
X199120Y560990D01*
X199043Y560577D01*
X198813Y560318D01*
X198545Y560163D01*
X197586D01*
G01X198545D02*
X199120Y558665D01*
G01X200610Y559130D02*
X200840Y558872D01*
X201108Y558717D01*
X201453Y558665D01*
X201798Y558768D01*
X202066Y558975D01*
X202258Y559337D01*
X202296Y559750D01*
X202220Y560163D01*
X202028Y560422D01*
X201760Y560628D01*
X201491Y560680D01*
X201223Y560628D01*
X200878Y560422D01*
X200993Y561765D01*
X202028D01*
G01X205013Y558665D02*
Y561765D01*
X203595Y559543D01*
X205511D01*
G01X206925Y561248D02*
X207155Y561558D01*
X207423Y561713D01*
X207730Y561765D01*
X208113Y561662D01*
X208381Y561403D01*
X208458Y561093D01*
X208420Y560783D01*
X208266Y560525D01*
X207500Y560008D01*
X207155Y559647D01*
X206925Y559130D01*
X206848Y558665D01*
X208458D01*
G01X209417Y580352D02*
X308235D01*
G01X197586Y566766D02*
Y569866D01*
X198545D01*
X198851Y569711D01*
X199043Y569504D01*
X199120Y569091D01*
X199043Y568678D01*
X198813Y568419D01*
X198545Y568264D01*
X197586D01*
G01X198545D02*
X199120Y566766D01*
G01X200610Y567231D02*
X200840Y566973D01*
X201108Y566818D01*
X201453Y566766D01*
X201798Y566869D01*
X202066Y567076D01*
X202258Y567438D01*
X202296Y567851D01*
X202220Y568264D01*
X202028Y568523D01*
X201760Y568729D01*
X201491Y568781D01*
X201223Y568729D01*
X200878Y568523D01*
X200993Y569866D01*
X202028D01*
G01X203825Y568058D02*
X204093Y568419D01*
X204323Y568626D01*
X204630Y568729D01*
X204898Y568626D01*
X205090Y568419D01*
X205243Y568109D01*
X205281Y567748D01*
X205243Y567438D01*
X205090Y567128D01*
X204860Y566869D01*
X204591Y566766D01*
X204285Y566869D01*
X204016Y567179D01*
X203863Y567644D01*
X203825Y568161D01*
X203901Y568833D01*
X204016Y569194D01*
X204208Y569556D01*
X204476Y569814D01*
X204745Y569866D01*
X205013Y569763D01*
X205205Y569504D01*
G01X207653Y569866D02*
X207346Y569763D01*
X207116Y569504D01*
X206963Y569194D01*
X206848Y568781D01*
X206810Y568316D01*
X206848Y567851D01*
X206963Y567438D01*
X207116Y567128D01*
X207346Y566869D01*
X207653Y566766D01*
X207960Y566869D01*
X208190Y567128D01*
X208343Y567438D01*
X208458Y567851D01*
X208496Y568316D01*
X208458Y568781D01*
X208343Y569194D01*
X208190Y569504D01*
X207960Y569763D01*
X207653Y569866D01*
G01X208703Y575293D02*
X202503D01*
G01X208703Y578493D02*
Y575293D01*
G01X202503D02*
Y578493D01*
G01D02*
X208703D01*
G01Y571293D02*
X202503D01*
G01D02*
Y574493D01*
G01D02*
X208703D01*
G01D02*
Y571293D01*
G01Y582492D02*
Y579294D01*
G01D02*
X202503D01*
G01D02*
Y582492D01*
G01X201020Y593110D02*
X229620D01*
G01X201020Y581990D02*
Y593110D01*
G01X198514Y594193D02*
X196014D01*
X196514Y593873D01*
G01X198514D02*
Y594513D01*
G01Y596340D02*
X197972Y596393D01*
X197514Y596473D01*
X197097Y596580D01*
X196639Y596713D01*
X196014Y596926D01*
Y595860D01*
G01X210853Y595357D02*
Y598557D01*
G01X217053Y595357D02*
X210853D01*
G01X208703Y583293D02*
X202503D01*
G01D02*
Y586493D01*
G01D02*
X208703D01*
G01D02*
Y583293D01*
G01X202503Y587293D02*
Y590493D01*
G01D02*
X208703D01*
G01D02*
Y587293D01*
G01D02*
X202503D01*
G01Y582492D02*
X208703D01*
G01X211183Y586907D02*
Y590007D01*
X212142D01*
X212448Y589852D01*
X212640Y589645D01*
X212717Y589232D01*
X212640Y588819D01*
X212410Y588560D01*
X212142Y588405D01*
X211183D01*
G01X212142D02*
X212717Y586907D01*
G01X214207Y587527D02*
X214437Y587165D01*
X214743Y586959D01*
X215088Y586907D01*
X215395Y586959D01*
X215702Y587217D01*
X215893Y587527D01*
X215932Y587837D01*
X215855Y588199D01*
X215587Y588457D01*
X215318Y588560D01*
X214973D01*
G01X215318D02*
X215548Y588715D01*
X215740Y588974D01*
X215817Y589284D01*
X215740Y589594D01*
X215548Y589852D01*
X215203Y590007D01*
X214858Y589955D01*
X214513Y589749D01*
G01X218150Y586907D02*
Y590007D01*
X217690Y589387D01*
G01Y586907D02*
X218610D01*
G01X220407Y587372D02*
X220637Y587114D01*
X220905Y586959D01*
X221250Y586907D01*
X221595Y587010D01*
X221863Y587217D01*
X222055Y587579D01*
X222093Y587992D01*
X222017Y588405D01*
X221825Y588664D01*
X221557Y588870D01*
X221288Y588922D01*
X221020Y588870D01*
X220675Y588664D01*
X220790Y590007D01*
X221825D01*
G01X195963Y610917D02*
X197963D01*
G01X195963Y601075D02*
X199963D01*
G01X206978Y610347D02*
X206748Y610502D01*
X206480Y610605D01*
X206173D01*
X205828Y610450D01*
X205560Y610192D01*
X205368Y609882D01*
X205215Y609365D01*
X205177Y608900D01*
X205253Y608435D01*
X205368Y608125D01*
X205598Y607815D01*
X205867Y607608D01*
X206135Y607505D01*
X206403D01*
X206672Y607608D01*
X206902Y607763D01*
X207093Y607970D01*
G01X208392Y608125D02*
X208622Y607763D01*
X208928Y607557D01*
X209273Y607505D01*
X209580Y607557D01*
X209887Y607815D01*
X210078Y608125D01*
X210117Y608435D01*
X210040Y608797D01*
X209772Y609055D01*
X209503Y609158D01*
X209158D01*
G01X209503D02*
X209733Y609313D01*
X209925Y609572D01*
X210002Y609882D01*
X209925Y610192D01*
X209733Y610450D01*
X209388Y610605D01*
X209043Y610553D01*
X208698Y610347D01*
G01X211683Y607867D02*
X211952Y607608D01*
X212258Y607505D01*
X212565Y607608D01*
X212833Y607918D01*
X213025Y608383D01*
X213102Y608848D01*
Y609417D01*
X213025Y609882D01*
X212833Y610295D01*
X212603Y610502D01*
X212335Y610605D01*
X212028Y610502D01*
X211798Y610295D01*
X211645Y609985D01*
X211568Y609572D01*
X211645Y609210D01*
X211837Y608848D01*
X212067Y608642D01*
X212335Y608590D01*
X212642Y608693D01*
X212872Y608952D01*
X213102Y609417D01*
G01X215435Y607505D02*
Y610605D01*
X214975Y609985D01*
G01Y607505D02*
X215895D01*
G01X210853Y599357D02*
Y602557D01*
G01D02*
X217053D01*
G01Y599357D02*
X210853D01*
G01X206898Y606307D02*
X206668Y606462D01*
X206400Y606565D01*
X206093D01*
X205748Y606410D01*
X205480Y606152D01*
X205288Y605842D01*
X205135Y605325D01*
X205097Y604860D01*
X205173Y604395D01*
X205288Y604085D01*
X205518Y603775D01*
X205787Y603568D01*
X206055Y603465D01*
X206323D01*
X206592Y603568D01*
X206822Y603723D01*
X207013Y603930D01*
G01X208312Y604085D02*
X208542Y603723D01*
X208848Y603517D01*
X209193Y603465D01*
X209500Y603517D01*
X209807Y603775D01*
X209998Y604085D01*
X210037Y604395D01*
X209960Y604757D01*
X209692Y605015D01*
X209423Y605118D01*
X209078D01*
G01X209423D02*
X209653Y605273D01*
X209845Y605532D01*
X209922Y605842D01*
X209845Y606152D01*
X209653Y606410D01*
X209308Y606565D01*
X208963Y606513D01*
X208618Y606307D01*
G01X211603Y603827D02*
X211872Y603568D01*
X212178Y603465D01*
X212485Y603568D01*
X212753Y603878D01*
X212945Y604343D01*
X213022Y604808D01*
Y605377D01*
X212945Y605842D01*
X212753Y606255D01*
X212523Y606462D01*
X212255Y606565D01*
X211948Y606462D01*
X211718Y606255D01*
X211565Y605945D01*
X211488Y605532D01*
X211565Y605170D01*
X211757Y604808D01*
X211987Y604602D01*
X212255Y604550D01*
X212562Y604653D01*
X212792Y604912D01*
X213022Y605377D01*
G01X214627Y606048D02*
X214857Y606358D01*
X215125Y606513D01*
X215432Y606565D01*
X215815Y606462D01*
X216083Y606203D01*
X216160Y605893D01*
X216122Y605583D01*
X215968Y605325D01*
X215202Y604808D01*
X214857Y604447D01*
X214627Y603930D01*
X214550Y603465D01*
X216160D01*
G01X210853Y598557D02*
X217053D01*
G01X195963Y620760D02*
X199963D01*
G01X207774Y623577D02*
X213974D01*
G01Y620377D02*
X207774D01*
G01D02*
Y623577D01*
G01Y627577D02*
X213974D01*
G01Y624377D02*
X207774D01*
G01D02*
Y627577D01*
G01X207840Y669340D02*
Y641300D01*
G01X213974Y628377D02*
X207774D01*
G01D02*
Y631577D01*
G01D02*
X213974D01*
G01X210874Y631477D02*
Y628477D01*
G01X213974Y636377D02*
X207774D01*
G01X210874Y639477D02*
Y636477D01*
G01X207774Y636377D02*
Y639577D01*
G01D02*
X213974D01*
G01X210874Y635477D02*
Y632477D01*
G01X213974Y632377D02*
X207774D01*
G01D02*
Y635577D01*
G01D02*
X213974D01*
G01X198010Y648375D02*
Y642175D01*
G01X203810D02*
Y648375D01*
G01X207010D02*
Y642175D01*
G01D02*
X203810D01*
G01X199310D02*
Y648375D01*
G01X202510D02*
Y642175D01*
G01D02*
X199310D01*
G01X208991Y641607D02*
Y644707D01*
X209950D01*
X210256Y644552D01*
X210448Y644345D01*
X210525Y643932D01*
X210448Y643519D01*
X210218Y643260D01*
X209950Y643105D01*
X208991D01*
G01X209950D02*
X210525Y641607D01*
G01X212015Y642072D02*
X212245Y641814D01*
X212513Y641659D01*
X212858Y641607D01*
X213203Y641710D01*
X213471Y641917D01*
X213663Y642279D01*
X213701Y642692D01*
X213625Y643105D01*
X213433Y643364D01*
X213165Y643570D01*
X212896Y643622D01*
X212628Y643570D01*
X212283Y643364D01*
X212398Y644707D01*
X213433D01*
G01X215306Y641969D02*
X215575Y641710D01*
X215881Y641607D01*
X216188Y641710D01*
X216456Y642020D01*
X216648Y642485D01*
X216725Y642950D01*
Y643519D01*
X216648Y643984D01*
X216456Y644397D01*
X216226Y644604D01*
X215958Y644707D01*
X215651Y644604D01*
X215421Y644397D01*
X215268Y644087D01*
X215191Y643674D01*
X215268Y643312D01*
X215460Y642950D01*
X215690Y642744D01*
X215958Y642692D01*
X216265Y642795D01*
X216495Y643054D01*
X216725Y643519D01*
G01X218330Y642899D02*
X218598Y643260D01*
X218828Y643467D01*
X219135Y643570D01*
X219403Y643467D01*
X219595Y643260D01*
X219748Y642950D01*
X219786Y642589D01*
X219748Y642279D01*
X219595Y641969D01*
X219365Y641710D01*
X219096Y641607D01*
X218790Y641710D01*
X218521Y642020D01*
X218368Y642485D01*
X218330Y643002D01*
X218406Y643674D01*
X218521Y644035D01*
X218713Y644397D01*
X218981Y644655D01*
X219250Y644707D01*
X219518Y644604D01*
X219710Y644345D01*
G01X210601Y652968D02*
X210371Y653123D01*
X210103Y653226D01*
X209796D01*
X209451Y653071D01*
X209183Y652813D01*
X208991Y652503D01*
X208838Y651986D01*
X208800Y651521D01*
X208876Y651056D01*
X208991Y650746D01*
X209221Y650436D01*
X209490Y650229D01*
X209758Y650126D01*
X210026D01*
X210295Y650229D01*
X210525Y650384D01*
X210716Y650591D01*
G01X212015D02*
X212245Y650333D01*
X212513Y650178D01*
X212858Y650126D01*
X213203Y650229D01*
X213471Y650436D01*
X213663Y650798D01*
X213701Y651211D01*
X213625Y651624D01*
X213433Y651883D01*
X213165Y652089D01*
X212896Y652141D01*
X212628Y652089D01*
X212283Y651883D01*
X212398Y653226D01*
X213433D01*
G01X215958Y650126D02*
Y653226D01*
X215498Y652606D01*
G01Y650126D02*
X216418D01*
G01X218981D02*
X219058Y650798D01*
X219173Y651366D01*
X219326Y651883D01*
X219518Y652451D01*
X219825Y653226D01*
X218291D01*
G01X210601Y661722D02*
X210371Y661877D01*
X210103Y661980D01*
X209796D01*
X209451Y661825D01*
X209183Y661567D01*
X208991Y661257D01*
X208838Y660740D01*
X208800Y660275D01*
X208876Y659810D01*
X208991Y659500D01*
X209221Y659190D01*
X209490Y658983D01*
X209758Y658880D01*
X210026D01*
X210295Y658983D01*
X210525Y659138D01*
X210716Y659345D01*
G01X212015D02*
X212245Y659087D01*
X212513Y658932D01*
X212858Y658880D01*
X213203Y658983D01*
X213471Y659190D01*
X213663Y659552D01*
X213701Y659965D01*
X213625Y660378D01*
X213433Y660637D01*
X213165Y660843D01*
X212896Y660895D01*
X212628Y660843D01*
X212283Y660637D01*
X212398Y661980D01*
X213433D01*
G01X215958Y658880D02*
Y661980D01*
X215498Y661360D01*
G01Y658880D02*
X216418D01*
G01X218406Y659242D02*
X218675Y658983D01*
X218981Y658880D01*
X219288Y658983D01*
X219556Y659293D01*
X219748Y659758D01*
X219825Y660223D01*
Y660792D01*
X219748Y661257D01*
X219556Y661670D01*
X219326Y661877D01*
X219058Y661980D01*
X218751Y661877D01*
X218521Y661670D01*
X218368Y661360D01*
X218291Y660947D01*
X218368Y660585D01*
X218560Y660223D01*
X218790Y660017D01*
X219058Y659965D01*
X219365Y660068D01*
X219595Y660327D01*
X219825Y660792D01*
G01X210601Y657332D02*
X210371Y657487D01*
X210103Y657590D01*
X209796D01*
X209451Y657435D01*
X209183Y657177D01*
X208991Y656867D01*
X208838Y656350D01*
X208800Y655885D01*
X208876Y655420D01*
X208991Y655110D01*
X209221Y654800D01*
X209490Y654593D01*
X209758Y654490D01*
X210026D01*
X210295Y654593D01*
X210525Y654748D01*
X210716Y654955D01*
G01X212015D02*
X212245Y654697D01*
X212513Y654542D01*
X212858Y654490D01*
X213203Y654593D01*
X213471Y654800D01*
X213663Y655162D01*
X213701Y655575D01*
X213625Y655988D01*
X213433Y656247D01*
X213165Y656453D01*
X212896Y656505D01*
X212628Y656453D01*
X212283Y656247D01*
X212398Y657590D01*
X213433D01*
G01X215958Y654490D02*
Y657590D01*
X215498Y656970D01*
G01Y654490D02*
X216418D01*
G01X219058D02*
X219326Y654542D01*
X219633Y654697D01*
X219825Y654955D01*
X219901Y655317D01*
X219825Y655678D01*
X219595Y655988D01*
X219250Y656143D01*
X218866D01*
X218636Y656247D01*
X218445Y656505D01*
X218368Y656867D01*
X218483Y657228D01*
X218751Y657487D01*
X219058Y657590D01*
X219365Y657487D01*
X219633Y657228D01*
X219748Y656867D01*
X219671Y656505D01*
X219480Y656247D01*
X219250Y656143D01*
X218866D01*
X218521Y655988D01*
X218291Y655678D01*
X218215Y655317D01*
X218291Y654955D01*
X218483Y654697D01*
X218790Y654542D01*
X219058Y654490D01*
G01X198010Y658375D02*
Y652175D01*
G01X203810D02*
Y658375D01*
G01D02*
X207010D01*
G01D02*
Y652175D01*
G01D02*
X203810D01*
G01X199310D02*
Y658375D01*
G01D02*
X202510D01*
G01D02*
Y652175D01*
G01D02*
X199310D01*
G01X203810Y648375D02*
X207010D01*
G01X199310D02*
X202510D01*
G01X208991Y645807D02*
Y648907D01*
X209950D01*
X210256Y648752D01*
X210448Y648545D01*
X210525Y648132D01*
X210448Y647719D01*
X210218Y647460D01*
X209950Y647305D01*
X208991D01*
G01X209950D02*
X210525Y645807D01*
G01X212015Y646272D02*
X212245Y646014D01*
X212513Y645859D01*
X212858Y645807D01*
X213203Y645910D01*
X213471Y646117D01*
X213663Y646479D01*
X213701Y646892D01*
X213625Y647305D01*
X213433Y647564D01*
X213165Y647770D01*
X212896Y647822D01*
X212628Y647770D01*
X212283Y647564D01*
X212398Y648907D01*
X213433D01*
G01X215115Y646272D02*
X215345Y646014D01*
X215613Y645859D01*
X215958Y645807D01*
X216303Y645910D01*
X216571Y646117D01*
X216763Y646479D01*
X216801Y646892D01*
X216725Y647305D01*
X216533Y647564D01*
X216265Y647770D01*
X215996Y647822D01*
X215728Y647770D01*
X215383Y647564D01*
X215498Y648907D01*
X216533D01*
G01X219058Y645807D02*
X219326Y645859D01*
X219633Y646014D01*
X219825Y646272D01*
X219901Y646634D01*
X219825Y646995D01*
X219595Y647305D01*
X219250Y647460D01*
X218866D01*
X218636Y647564D01*
X218445Y647822D01*
X218368Y648184D01*
X218483Y648545D01*
X218751Y648804D01*
X219058Y648907D01*
X219365Y648804D01*
X219633Y648545D01*
X219748Y648184D01*
X219671Y647822D01*
X219480Y647564D01*
X219250Y647460D01*
X218866D01*
X218521Y647305D01*
X218291Y646995D01*
X218215Y646634D01*
X218291Y646272D01*
X218483Y646014D01*
X218790Y645859D01*
X219058Y645807D01*
G01X266430Y669340D02*
X207840D01*
G01X195838Y674126D02*
Y670926D01*
G01X207307Y673272D02*
Y670272D01*
G01X210407Y673372D02*
Y670172D01*
G01X204207Y673372D02*
X210407D01*
G01Y670172D02*
X204207D01*
G01D02*
Y673372D01*
G01X197360Y672219D02*
X197520Y672011D01*
X197707Y671886D01*
X197947Y671844D01*
X198187Y671927D01*
X198374Y672094D01*
X198507Y672386D01*
X198534Y672719D01*
X198480Y673052D01*
X198347Y673261D01*
X198160Y673427D01*
X197974Y673469D01*
X197787Y673427D01*
X197547Y673261D01*
X197627Y674344D01*
X198347D01*
G01X195835Y691179D02*
Y675179D01*
G01X200951Y671844D02*
Y674344D01*
X199964Y672552D01*
X201298D01*
G01X211161Y672337D02*
X211321Y672129D01*
X211508Y672004D01*
X211748Y671962D01*
X211988Y672045D01*
X212175Y672212D01*
X212308Y672504D01*
X212335Y672837D01*
X212281Y673170D01*
X212148Y673379D01*
X211961Y673545D01*
X211775Y673587D01*
X211588Y673545D01*
X211348Y673379D01*
X211428Y674462D01*
X212148D01*
G01X197631Y675179D02*
Y691179D01*
G01X209835Y675179D02*
X197631D01*
G01X209835Y691179D02*
Y675179D01*
G01X211003D02*
Y691179D01*
G01X223207Y675179D02*
X211003D01*
G01X205093Y691866D02*
Y694366D01*
X204773Y693866D01*
G01Y691866D02*
X205413D01*
G01X197631Y691179D02*
X209835D01*
G01X211003D02*
X223207D01*
G01X196586Y692129D02*
Y694629D01*
X196266Y694129D01*
G01Y692129D02*
X196906D01*
G01X199151Y693123D02*
X199311Y692831D01*
X199525Y692665D01*
X199765Y692623D01*
X199978Y692665D01*
X200191Y692873D01*
X200325Y693123D01*
X200351Y693373D01*
X200298Y693665D01*
X200111Y693873D01*
X199925Y693956D01*
X199685D01*
G01X199925D02*
X200085Y694081D01*
X200218Y694290D01*
X200271Y694540D01*
X200218Y694790D01*
X200085Y694998D01*
X199845Y695123D01*
X199605Y695081D01*
X199365Y694915D01*
G01X202272Y693145D02*
Y695645D01*
X202806D01*
X203019Y695520D01*
X203179Y695353D01*
X203312Y695103D01*
X203419Y694812D01*
X203446Y694395D01*
X203419Y693978D01*
X203312Y693687D01*
X203179Y693437D01*
X203019Y693270D01*
X202806Y693145D01*
X202272D01*
G01X207940Y711456D02*
Y696456D01*
G01X208940D02*
Y711456D01*
G01X221940Y696456D02*
X208940D01*
G01X196040Y720573D02*
Y714373D01*
G01X200440Y717506D02*
X197440D01*
G01X200540Y714406D02*
X197340D01*
G01X200540Y720606D02*
Y714406D01*
G01X197340Y720606D02*
X200540D01*
G01X197340Y714406D02*
Y720606D01*
G01X209440Y717506D02*
X206440D01*
G01X209540Y714406D02*
X206340D01*
G01Y720606D02*
X209540D01*
G01X206340Y714406D02*
Y720606D01*
G01X209540D02*
Y714406D01*
G01X204940Y717473D02*
X201940D01*
G01X205040Y714373D02*
X201840D01*
G01X205040Y720573D02*
Y714373D01*
G01X201840Y720573D02*
X205040D01*
G01X201840Y714373D02*
Y720573D01*
G01X199605Y712563D02*
X199813Y712776D01*
X199938Y713016D01*
Y713230D01*
X199813Y713443D01*
X199605Y713603D01*
X199313Y713683D01*
X199021Y713630D01*
X198771Y713496D01*
X198605Y713256D01*
X198521Y712936D01*
X198355Y712750D01*
X198063Y712670D01*
X197771Y712723D01*
X197563Y712856D01*
X197438Y713043D01*
Y713230D01*
X197521Y713416D01*
X197730Y713576D01*
G01X207688Y712783D02*
Y713316D01*
X208438D01*
X208688Y713156D01*
X208855Y712970D01*
X208938Y712703D01*
X208855Y712436D01*
X208688Y712250D01*
X208438Y712090D01*
X208146Y711983D01*
X207813Y711930D01*
X207521D01*
X207271Y711983D01*
X206980Y712090D01*
X206730Y712250D01*
X206563Y712410D01*
X206438Y712623D01*
Y712810D01*
X206521Y713023D01*
X206688Y713183D01*
G01X208940Y711456D02*
X221940D01*
G01X214040Y737556D02*
X210840D01*
G01D02*
Y743756D01*
G01X196040D02*
Y737556D01*
G01Y732256D02*
Y726056D01*
G01X209540Y737556D02*
X206340D01*
G01D02*
Y743756D01*
G01X209540D02*
Y737556D01*
G01X205040D02*
X201840D01*
G01X205040Y743756D02*
Y737556D01*
G01X201840D02*
Y743756D01*
G01X200540Y737556D02*
X197340D01*
G01X200540Y743756D02*
Y737556D01*
G01X197340D02*
Y743756D01*
G01X209540Y726056D02*
X206340D01*
G01Y732256D02*
X209540D01*
G01X206340Y726056D02*
Y732256D01*
G01X209540D02*
Y726056D01*
G01X205040D02*
X201840D01*
G01X205040Y732256D02*
Y726056D01*
G01X201840Y732256D02*
X205040D01*
G01X201840Y726056D02*
Y732256D01*
G01X200540Y726056D02*
X197340D01*
G01X200540Y732256D02*
Y726056D01*
G01X197340Y732256D02*
X200540D01*
G01X197340Y726056D02*
Y732256D01*
G01X210841D02*
X214039D01*
G01X210841Y726056D02*
Y732256D01*
G01X214039Y726056D02*
X210841D01*
G01X210840Y743756D02*
X214040D01*
G01X213940Y740656D02*
X210940D01*
G01X206340Y743756D02*
X209540D01*
G01X201840D02*
X205040D01*
G01X197340D02*
X200540D01*
G01X209553Y745311D02*
X206453D01*
Y746270D01*
X206608Y746576D01*
X206815Y746768D01*
X207228Y746845D01*
X207641Y746768D01*
X207900Y746538D01*
X208055Y746270D01*
Y745311D01*
G01Y746270D02*
X209553Y746845D01*
G01Y749178D02*
X209501Y749446D01*
X209346Y749753D01*
X209088Y749945D01*
X208726Y750021D01*
X208365Y749945D01*
X208055Y749715D01*
X207900Y749370D01*
Y748986D01*
X207796Y748756D01*
X207538Y748565D01*
X207176Y748488D01*
X206815Y748603D01*
X206556Y748871D01*
X206453Y749178D01*
X206556Y749485D01*
X206815Y749753D01*
X207176Y749868D01*
X207538Y749791D01*
X207796Y749600D01*
X207900Y749370D01*
Y748986D01*
X208055Y748641D01*
X208365Y748411D01*
X208726Y748335D01*
X209088Y748411D01*
X209346Y748603D01*
X209501Y748910D01*
X209553Y749178D01*
G01X208933Y751435D02*
X209295Y751665D01*
X209501Y751971D01*
X209553Y752316D01*
X209501Y752623D01*
X209243Y752930D01*
X208933Y753121D01*
X208623Y753160D01*
X208261Y753083D01*
X208003Y752815D01*
X207900Y752546D01*
Y752201D01*
G01Y752546D02*
X207745Y752776D01*
X207486Y752968D01*
X207176Y753045D01*
X206866Y752968D01*
X206608Y752776D01*
X206453Y752431D01*
X206505Y752086D01*
X206711Y751741D01*
G01X209553Y755378D02*
X206453D01*
X207073Y754918D01*
G01X209553D02*
Y755838D01*
G01X205053Y745311D02*
X201953D01*
Y746270D01*
X202108Y746576D01*
X202315Y746768D01*
X202728Y746845D01*
X203141Y746768D01*
X203400Y746538D01*
X203555Y746270D01*
Y745311D01*
G01Y746270D02*
X205053Y746845D01*
G01Y749178D02*
X205001Y749446D01*
X204846Y749753D01*
X204588Y749945D01*
X204226Y750021D01*
X203865Y749945D01*
X203555Y749715D01*
X203400Y749370D01*
Y748986D01*
X203296Y748756D01*
X203038Y748565D01*
X202676Y748488D01*
X202315Y748603D01*
X202056Y748871D01*
X201953Y749178D01*
X202056Y749485D01*
X202315Y749753D01*
X202676Y749868D01*
X203038Y749791D01*
X203296Y749600D01*
X203400Y749370D01*
Y748986D01*
X203555Y748641D01*
X203865Y748411D01*
X204226Y748335D01*
X204588Y748411D01*
X204846Y748603D01*
X205001Y748910D01*
X205053Y749178D01*
G01X204433Y751435D02*
X204795Y751665D01*
X205001Y751971D01*
X205053Y752316D01*
X205001Y752623D01*
X204743Y752930D01*
X204433Y753121D01*
X204123Y753160D01*
X203761Y753083D01*
X203503Y752815D01*
X203400Y752546D01*
Y752201D01*
G01Y752546D02*
X203245Y752776D01*
X202986Y752968D01*
X202676Y753045D01*
X202366Y752968D01*
X202108Y752776D01*
X201953Y752431D01*
X202005Y752086D01*
X202211Y751741D01*
G01X204433Y754535D02*
X204795Y754765D01*
X205001Y755071D01*
X205053Y755416D01*
X205001Y755723D01*
X204743Y756030D01*
X204433Y756221D01*
X204123Y756260D01*
X203761Y756183D01*
X203503Y755915D01*
X203400Y755646D01*
Y755301D01*
G01Y755646D02*
X203245Y755876D01*
X202986Y756068D01*
X202676Y756145D01*
X202366Y756068D01*
X202108Y755876D01*
X201953Y755531D01*
X202005Y755186D01*
X202211Y754841D01*
G01X200553Y745311D02*
X197453D01*
Y746270D01*
X197608Y746576D01*
X197815Y746768D01*
X198228Y746845D01*
X198641Y746768D01*
X198900Y746538D01*
X199055Y746270D01*
Y745311D01*
G01Y746270D02*
X200553Y746845D01*
G01Y749178D02*
X200501Y749446D01*
X200346Y749753D01*
X200088Y749945D01*
X199726Y750021D01*
X199365Y749945D01*
X199055Y749715D01*
X198900Y749370D01*
Y748986D01*
X198796Y748756D01*
X198538Y748565D01*
X198176Y748488D01*
X197815Y748603D01*
X197556Y748871D01*
X197453Y749178D01*
X197556Y749485D01*
X197815Y749753D01*
X198176Y749868D01*
X198538Y749791D01*
X198796Y749600D01*
X198900Y749370D01*
Y748986D01*
X199055Y748641D01*
X199365Y748411D01*
X199726Y748335D01*
X200088Y748411D01*
X200346Y748603D01*
X200501Y748910D01*
X200553Y749178D01*
G01X199933Y751435D02*
X200295Y751665D01*
X200501Y751971D01*
X200553Y752316D01*
X200501Y752623D01*
X200243Y752930D01*
X199933Y753121D01*
X199623Y753160D01*
X199261Y753083D01*
X199003Y752815D01*
X198900Y752546D01*
Y752201D01*
G01Y752546D02*
X198745Y752776D01*
X198486Y752968D01*
X198176Y753045D01*
X197866Y752968D01*
X197608Y752776D01*
X197453Y752431D01*
X197505Y752086D01*
X197711Y751741D01*
G01X199261Y754650D02*
X198900Y754918D01*
X198693Y755148D01*
X198590Y755455D01*
X198693Y755723D01*
X198900Y755915D01*
X199210Y756068D01*
X199571Y756106D01*
X199881Y756068D01*
X200191Y755915D01*
X200450Y755685D01*
X200553Y755416D01*
X200450Y755110D01*
X200140Y754841D01*
X199675Y754688D01*
X199158Y754650D01*
X198486Y754726D01*
X198125Y754841D01*
X197763Y755033D01*
X197505Y755301D01*
X197453Y755570D01*
X197556Y755838D01*
X197815Y756030D01*
G01X213699Y745311D02*
X210599D01*
Y746270D01*
X210754Y746576D01*
X210961Y746768D01*
X211374Y746845D01*
X211787Y746768D01*
X212046Y746538D01*
X212201Y746270D01*
Y745311D01*
G01Y746270D02*
X213699Y746845D01*
G01Y749178D02*
X213647Y749446D01*
X213492Y749753D01*
X213234Y749945D01*
X212872Y750021D01*
X212511Y749945D01*
X212201Y749715D01*
X212046Y749370D01*
Y748986D01*
X211942Y748756D01*
X211684Y748565D01*
X211322Y748488D01*
X210961Y748603D01*
X210702Y748871D01*
X210599Y749178D01*
X210702Y749485D01*
X210961Y749753D01*
X211322Y749868D01*
X211684Y749791D01*
X211942Y749600D01*
X212046Y749370D01*
Y748986D01*
X212201Y748641D01*
X212511Y748411D01*
X212872Y748335D01*
X213234Y748411D01*
X213492Y748603D01*
X213647Y748910D01*
X213699Y749178D01*
G01Y752278D02*
X210599D01*
X211219Y751818D01*
G01X213699D02*
Y752738D01*
G01Y755378D02*
X213647Y755646D01*
X213492Y755953D01*
X213234Y756145D01*
X212872Y756221D01*
X212511Y756145D01*
X212201Y755915D01*
X212046Y755570D01*
Y755186D01*
X211942Y754956D01*
X211684Y754765D01*
X211322Y754688D01*
X210961Y754803D01*
X210702Y755071D01*
X210599Y755378D01*
X210702Y755685D01*
X210961Y755953D01*
X211322Y756068D01*
X211684Y755991D01*
X211942Y755800D01*
X212046Y755570D01*
Y755186D01*
X212201Y754841D01*
X212511Y754611D01*
X212872Y754535D01*
X213234Y754611D01*
X213492Y754803D01*
X213647Y755110D01*
X213699Y755378D01*
G01X210143Y758948D02*
X207043D01*
Y759907D01*
X207198Y760213D01*
X207405Y760405D01*
X207818Y760482D01*
X208231Y760405D01*
X208490Y760175D01*
X208645Y759907D01*
Y758948D01*
G01Y759907D02*
X210143Y760482D01*
G01Y762815D02*
X210091Y763083D01*
X209936Y763390D01*
X209678Y763582D01*
X209316Y763658D01*
X208955Y763582D01*
X208645Y763352D01*
X208490Y763007D01*
Y762623D01*
X208386Y762393D01*
X208128Y762202D01*
X207766Y762125D01*
X207405Y762240D01*
X207146Y762508D01*
X207043Y762815D01*
X207146Y763122D01*
X207405Y763390D01*
X207766Y763505D01*
X208128Y763428D01*
X208386Y763237D01*
X208490Y763007D01*
Y762623D01*
X208645Y762278D01*
X208955Y762048D01*
X209316Y761972D01*
X209678Y762048D01*
X209936Y762240D01*
X210091Y762547D01*
X210143Y762815D01*
G01Y766375D02*
X207043D01*
X209265Y764957D01*
Y766873D01*
G01X209678Y768172D02*
X209936Y768402D01*
X210091Y768670D01*
X210143Y769015D01*
X210040Y769360D01*
X209833Y769628D01*
X209471Y769820D01*
X209058Y769858D01*
X208645Y769782D01*
X208386Y769590D01*
X208180Y769322D01*
X208128Y769053D01*
X208180Y768785D01*
X208386Y768440D01*
X207043Y768555D01*
Y769590D01*
G01X205643Y758948D02*
X202543D01*
Y759907D01*
X202698Y760213D01*
X202905Y760405D01*
X203318Y760482D01*
X203731Y760405D01*
X203990Y760175D01*
X204145Y759907D01*
Y758948D01*
G01Y759907D02*
X205643Y760482D01*
G01Y762815D02*
X205591Y763083D01*
X205436Y763390D01*
X205178Y763582D01*
X204816Y763658D01*
X204455Y763582D01*
X204145Y763352D01*
X203990Y763007D01*
Y762623D01*
X203886Y762393D01*
X203628Y762202D01*
X203266Y762125D01*
X202905Y762240D01*
X202646Y762508D01*
X202543Y762815D01*
X202646Y763122D01*
X202905Y763390D01*
X203266Y763505D01*
X203628Y763428D01*
X203886Y763237D01*
X203990Y763007D01*
Y762623D01*
X204145Y762278D01*
X204455Y762048D01*
X204816Y761972D01*
X205178Y762048D01*
X205436Y762240D01*
X205591Y762547D01*
X205643Y762815D01*
G01Y766375D02*
X202543D01*
X204765Y764957D01*
Y766873D01*
G01X205643Y769015D02*
X205591Y769283D01*
X205436Y769590D01*
X205178Y769782D01*
X204816Y769858D01*
X204455Y769782D01*
X204145Y769552D01*
X203990Y769207D01*
Y768823D01*
X203886Y768593D01*
X203628Y768402D01*
X203266Y768325D01*
X202905Y768440D01*
X202646Y768708D01*
X202543Y769015D01*
X202646Y769322D01*
X202905Y769590D01*
X203266Y769705D01*
X203628Y769628D01*
X203886Y769437D01*
X203990Y769207D01*
Y768823D01*
X204145Y768478D01*
X204455Y768248D01*
X204816Y768172D01*
X205178Y768248D01*
X205436Y768440D01*
X205591Y768747D01*
X205643Y769015D01*
G01X201143Y758948D02*
X198043D01*
Y759907D01*
X198198Y760213D01*
X198405Y760405D01*
X198818Y760482D01*
X199231Y760405D01*
X199490Y760175D01*
X199645Y759907D01*
Y758948D01*
G01Y759907D02*
X201143Y760482D01*
G01Y762815D02*
X201091Y763083D01*
X200936Y763390D01*
X200678Y763582D01*
X200316Y763658D01*
X199955Y763582D01*
X199645Y763352D01*
X199490Y763007D01*
Y762623D01*
X199386Y762393D01*
X199128Y762202D01*
X198766Y762125D01*
X198405Y762240D01*
X198146Y762508D01*
X198043Y762815D01*
X198146Y763122D01*
X198405Y763390D01*
X198766Y763505D01*
X199128Y763428D01*
X199386Y763237D01*
X199490Y763007D01*
Y762623D01*
X199645Y762278D01*
X199955Y762048D01*
X200316Y761972D01*
X200678Y762048D01*
X200936Y762240D01*
X201091Y762547D01*
X201143Y762815D01*
G01Y766375D02*
X198043D01*
X200265Y764957D01*
Y766873D01*
G01X200781Y768363D02*
X201040Y768632D01*
X201143Y768938D01*
X201040Y769245D01*
X200730Y769513D01*
X200265Y769705D01*
X199800Y769782D01*
X199231D01*
X198766Y769705D01*
X198353Y769513D01*
X198146Y769283D01*
X198043Y769015D01*
X198146Y768708D01*
X198353Y768478D01*
X198663Y768325D01*
X199076Y768248D01*
X199438Y768325D01*
X199800Y768517D01*
X200006Y768747D01*
X200058Y769015D01*
X199955Y769322D01*
X199696Y769552D01*
X199231Y769782D01*
G01X218681Y4918D02*
Y8018D01*
X219601D01*
X219908Y7863D01*
X220138Y7501D01*
X220215Y7088D01*
X220138Y6675D01*
X219946Y6365D01*
X219601Y6210D01*
X218681D01*
G01X223391Y7760D02*
X223161Y7915D01*
X222893Y8018D01*
X222586D01*
X222241Y7863D01*
X221973Y7605D01*
X221781Y7295D01*
X221628Y6778D01*
X221590Y6313D01*
X221666Y5848D01*
X221781Y5538D01*
X222011Y5228D01*
X222280Y5021D01*
X222548Y4918D01*
X222816D01*
X223085Y5021D01*
X223315Y5176D01*
X223506Y5383D01*
G01X225648Y4918D02*
X225916Y4970D01*
X226223Y5125D01*
X226415Y5383D01*
X226491Y5745D01*
X226415Y6106D01*
X226185Y6416D01*
X225840Y6571D01*
X225456D01*
X225226Y6675D01*
X225035Y6933D01*
X224958Y7295D01*
X225073Y7656D01*
X225341Y7915D01*
X225648Y8018D01*
X225955Y7915D01*
X226223Y7656D01*
X226338Y7295D01*
X226261Y6933D01*
X226070Y6675D01*
X225840Y6571D01*
X225456D01*
X225111Y6416D01*
X224881Y6106D01*
X224805Y5745D01*
X224881Y5383D01*
X225073Y5125D01*
X225380Y4970D01*
X225648Y4918D01*
G01X228748Y8018D02*
X228441Y7915D01*
X228211Y7656D01*
X228058Y7346D01*
X227943Y6933D01*
X227905Y6468D01*
X227943Y6003D01*
X228058Y5590D01*
X228211Y5280D01*
X228441Y5021D01*
X228748Y4918D01*
X229055Y5021D01*
X229285Y5280D01*
X229438Y5590D01*
X229553Y6003D01*
X229591Y6468D01*
X229553Y6933D01*
X229438Y7346D01*
X229285Y7656D01*
X229055Y7915D01*
X228748Y8018D01*
G01X217473Y8635D02*
Y44331D01*
G01X235189Y8635D02*
X217473D01*
G01X214579Y56352D02*
Y29974D01*
G01X217473Y44331D02*
X235189D01*
G01X226714Y66201D02*
Y51201D01*
G01X220014Y58701D02*
X226614D01*
G01X226714Y51201D02*
X219914D01*
G01D02*
Y66201D01*
G01X218566Y58945D02*
X215466D01*
Y59865D01*
X215621Y60172D01*
X215983Y60402D01*
X216396Y60479D01*
X216809Y60402D01*
X217119Y60210D01*
X217274Y59865D01*
Y58945D01*
G01X215724Y63655D02*
X215569Y63425D01*
X215466Y63157D01*
Y62850D01*
X215621Y62505D01*
X215879Y62237D01*
X216189Y62045D01*
X216706Y61892D01*
X217171Y61854D01*
X217636Y61930D01*
X217946Y62045D01*
X218256Y62275D01*
X218463Y62544D01*
X218566Y62812D01*
Y63080D01*
X218463Y63349D01*
X218308Y63579D01*
X218101Y63770D01*
G01X218566Y65835D02*
X217894Y65912D01*
X217326Y66027D01*
X216809Y66180D01*
X216241Y66372D01*
X215466Y66679D01*
Y65145D01*
G01X218566Y69012D02*
X218514Y69280D01*
X218359Y69587D01*
X218101Y69779D01*
X217739Y69855D01*
X217378Y69779D01*
X217068Y69549D01*
X216913Y69204D01*
Y68820D01*
X216809Y68590D01*
X216551Y68399D01*
X216189Y68322D01*
X215828Y68437D01*
X215569Y68705D01*
X215466Y69012D01*
X215569Y69319D01*
X215828Y69587D01*
X216189Y69702D01*
X216551Y69625D01*
X216809Y69434D01*
X216913Y69204D01*
Y68820D01*
X217068Y68475D01*
X217378Y68245D01*
X217739Y68169D01*
X218101Y68245D01*
X218359Y68437D01*
X218514Y68744D01*
X218566Y69012D01*
G01X214457Y58961D02*
X211357D01*
Y59881D01*
X211512Y60188D01*
X211874Y60418D01*
X212287Y60495D01*
X212700Y60418D01*
X213010Y60226D01*
X213165Y59881D01*
Y58961D01*
G01X211615Y63671D02*
X211460Y63441D01*
X211357Y63173D01*
Y62866D01*
X211512Y62521D01*
X211770Y62253D01*
X212080Y62061D01*
X212597Y61908D01*
X213062Y61870D01*
X213527Y61946D01*
X213837Y62061D01*
X214147Y62291D01*
X214354Y62560D01*
X214457Y62828D01*
Y63096D01*
X214354Y63365D01*
X214199Y63595D01*
X213992Y63786D01*
G01X214457Y65928D02*
X214405Y66196D01*
X214250Y66503D01*
X213992Y66695D01*
X213630Y66771D01*
X213269Y66695D01*
X212959Y66465D01*
X212804Y66120D01*
Y65736D01*
X212700Y65506D01*
X212442Y65315D01*
X212080Y65238D01*
X211719Y65353D01*
X211460Y65621D01*
X211357Y65928D01*
X211460Y66235D01*
X211719Y66503D01*
X212080Y66618D01*
X212442Y66541D01*
X212700Y66350D01*
X212804Y66120D01*
Y65736D01*
X212959Y65391D01*
X213269Y65161D01*
X213630Y65085D01*
X213992Y65161D01*
X214250Y65353D01*
X214405Y65660D01*
X214457Y65928D01*
G01Y69028D02*
X211357D01*
X211977Y68568D01*
G01X214457D02*
Y69488D01*
G01X217368Y49544D02*
Y51424D01*
G01X216003Y50406D02*
X218733D01*
G01X219914Y66201D02*
X226714D01*
G01X223090Y141080D02*
Y129800D01*
G01X235390Y141080D02*
X223090D01*
G01X223324Y157195D02*
X223094Y157350D01*
X222826Y157453D01*
X222519D01*
X222174Y157298D01*
X221906Y157040D01*
X221714Y156730D01*
X221561Y156213D01*
X221523Y155748D01*
X221599Y155283D01*
X221714Y154973D01*
X221944Y154663D01*
X222213Y154456D01*
X222481Y154353D01*
X222749D01*
X223018Y154456D01*
X223248Y154611D01*
X223439Y154818D01*
G01X224853Y155645D02*
X225121Y156006D01*
X225351Y156213D01*
X225658Y156316D01*
X225926Y156213D01*
X226118Y156006D01*
X226271Y155696D01*
X226309Y155335D01*
X226271Y155025D01*
X226118Y154715D01*
X225888Y154456D01*
X225619Y154353D01*
X225313Y154456D01*
X225044Y154766D01*
X224891Y155231D01*
X224853Y155748D01*
X224929Y156420D01*
X225044Y156781D01*
X225236Y157143D01*
X225504Y157401D01*
X225773Y157453D01*
X226041Y157350D01*
X226233Y157091D01*
G01X228681Y154353D02*
Y157453D01*
X228221Y156833D01*
G01Y154353D02*
X229141D01*
G01X231704D02*
X231781Y155025D01*
X231896Y155593D01*
X232049Y156110D01*
X232241Y156678D01*
X232548Y157453D01*
X231014D01*
G01X218480Y159020D02*
X235220D01*
G01X218480Y190630D02*
Y159020D01*
G01X216197Y215484D02*
Y222167D01*
X216218D01*
X218411Y219974D01*
X218390Y219953D01*
X213562D01*
X215797Y222188D01*
X216134D01*
G01X212242Y363339D02*
X212402Y363589D01*
X212589Y363714D01*
X212802Y363756D01*
X213069Y363673D01*
X213256Y363464D01*
X213309Y363214D01*
X213282Y362964D01*
X213176Y362756D01*
X212642Y362339D01*
X212402Y362048D01*
X212242Y361631D01*
X212189Y361256D01*
X213309D01*
G01X214442Y362298D02*
X214629Y362589D01*
X214789Y362756D01*
X215002Y362839D01*
X215189Y362756D01*
X215322Y362589D01*
X215429Y362339D01*
X215456Y362048D01*
X215429Y361798D01*
X215322Y361548D01*
X215162Y361339D01*
X214976Y361256D01*
X214762Y361339D01*
X214576Y361589D01*
X214469Y361964D01*
X214442Y362381D01*
X214496Y362923D01*
X214576Y363214D01*
X214709Y363506D01*
X214896Y363714D01*
X215082Y363756D01*
X215269Y363673D01*
X215402Y363464D01*
G01X214242Y358839D02*
X214402Y359089D01*
X214589Y359214D01*
X214802Y359256D01*
X215069Y359173D01*
X215256Y358964D01*
X215309Y358714D01*
X215282Y358464D01*
X215176Y358256D01*
X214642Y357839D01*
X214402Y357548D01*
X214242Y357131D01*
X214189Y356756D01*
X215309D01*
G01X216896D02*
X216949Y357298D01*
X217029Y357756D01*
X217136Y358173D01*
X217269Y358631D01*
X217482Y359256D01*
X216416D01*
G01X216242Y363339D02*
X216402Y363589D01*
X216589Y363714D01*
X216802Y363756D01*
X217069Y363673D01*
X217256Y363464D01*
X217309Y363214D01*
X217282Y362964D01*
X217176Y362756D01*
X216642Y362339D01*
X216402Y362048D01*
X216242Y361631D01*
X216189Y361256D01*
X217309D01*
G01X218949D02*
X219136Y361298D01*
X219349Y361423D01*
X219482Y361631D01*
X219536Y361923D01*
X219482Y362214D01*
X219322Y362464D01*
X219082Y362589D01*
X218816D01*
X218656Y362673D01*
X218522Y362881D01*
X218469Y363173D01*
X218549Y363464D01*
X218736Y363673D01*
X218949Y363756D01*
X219162Y363673D01*
X219349Y363464D01*
X219429Y363173D01*
X219376Y362881D01*
X219242Y362673D01*
X219082Y362589D01*
X218816D01*
X218576Y362464D01*
X218416Y362214D01*
X218362Y361923D01*
X218416Y361631D01*
X218549Y361423D01*
X218762Y361298D01*
X218949Y361256D01*
G01X217742Y358839D02*
X217902Y359089D01*
X218089Y359214D01*
X218302Y359256D01*
X218569Y359173D01*
X218756Y358964D01*
X218809Y358714D01*
X218782Y358464D01*
X218676Y358256D01*
X218142Y357839D01*
X217902Y357548D01*
X217742Y357131D01*
X217689Y356756D01*
X218809D01*
G01X219996Y357048D02*
X220182Y356839D01*
X220396Y356756D01*
X220609Y356839D01*
X220796Y357089D01*
X220929Y357464D01*
X220982Y357839D01*
Y358298D01*
X220929Y358673D01*
X220796Y359006D01*
X220636Y359173D01*
X220449Y359256D01*
X220236Y359173D01*
X220076Y359006D01*
X219969Y358756D01*
X219916Y358423D01*
X219969Y358131D01*
X220102Y357839D01*
X220262Y357673D01*
X220449Y357631D01*
X220662Y357714D01*
X220822Y357923D01*
X220982Y358298D01*
G01X225162Y357256D02*
X225322Y356964D01*
X225536Y356798D01*
X225776Y356756D01*
X225989Y356798D01*
X226202Y357006D01*
X226336Y357256D01*
X226362Y357506D01*
X226309Y357798D01*
X226122Y358006D01*
X225936Y358089D01*
X225696D01*
G01X225936D02*
X226096Y358214D01*
X226229Y358423D01*
X226282Y358673D01*
X226229Y358923D01*
X226096Y359131D01*
X225856Y359256D01*
X225616Y359214D01*
X225376Y359048D01*
G01X227362Y357256D02*
X227522Y356964D01*
X227736Y356798D01*
X227976Y356756D01*
X228189Y356798D01*
X228402Y357006D01*
X228536Y357256D01*
X228562Y357506D01*
X228509Y357798D01*
X228322Y358006D01*
X228136Y358089D01*
X227896D01*
G01X228136D02*
X228296Y358214D01*
X228429Y358423D01*
X228482Y358673D01*
X228429Y358923D01*
X228296Y359131D01*
X228056Y359256D01*
X227816Y359214D01*
X227576Y359048D01*
G01X221662Y357256D02*
X221822Y356964D01*
X222036Y356798D01*
X222276Y356756D01*
X222489Y356798D01*
X222702Y357006D01*
X222836Y357256D01*
X222862Y357506D01*
X222809Y357798D01*
X222622Y358006D01*
X222436Y358089D01*
X222196D01*
G01X222436D02*
X222596Y358214D01*
X222729Y358423D01*
X222782Y358673D01*
X222729Y358923D01*
X222596Y359131D01*
X222356Y359256D01*
X222116Y359214D01*
X221876Y359048D01*
G01X224449Y356756D02*
Y359256D01*
X224129Y358756D01*
G01Y356756D02*
X224769D01*
G01X223662Y361756D02*
X223822Y361464D01*
X224036Y361298D01*
X224276Y361256D01*
X224489Y361298D01*
X224702Y361506D01*
X224836Y361756D01*
X224862Y362006D01*
X224809Y362298D01*
X224622Y362506D01*
X224436Y362589D01*
X224196D01*
G01X224436D02*
X224596Y362714D01*
X224729Y362923D01*
X224782Y363173D01*
X224729Y363423D01*
X224596Y363631D01*
X224356Y363756D01*
X224116Y363714D01*
X223876Y363548D01*
G01X225942Y363339D02*
X226102Y363589D01*
X226289Y363714D01*
X226502Y363756D01*
X226769Y363673D01*
X226956Y363464D01*
X227009Y363214D01*
X226982Y362964D01*
X226876Y362756D01*
X226342Y362339D01*
X226102Y362048D01*
X225942Y361631D01*
X225889Y361256D01*
X227009D01*
G01X220162Y361756D02*
X220322Y361464D01*
X220536Y361298D01*
X220776Y361256D01*
X220989Y361298D01*
X221202Y361506D01*
X221336Y361756D01*
X221362Y362006D01*
X221309Y362298D01*
X221122Y362506D01*
X220936Y362589D01*
X220696D01*
G01X220936D02*
X221096Y362714D01*
X221229Y362923D01*
X221282Y363173D01*
X221229Y363423D01*
X221096Y363631D01*
X220856Y363756D01*
X220616Y363714D01*
X220376Y363548D01*
G01X222949Y363756D02*
X222736Y363673D01*
X222576Y363464D01*
X222469Y363214D01*
X222389Y362881D01*
X222362Y362506D01*
X222389Y362131D01*
X222469Y361798D01*
X222576Y361548D01*
X222736Y361339D01*
X222949Y361256D01*
X223162Y361339D01*
X223322Y361548D01*
X223429Y361798D01*
X223509Y362131D01*
X223536Y362506D01*
X223509Y362881D01*
X223429Y363214D01*
X223322Y363464D01*
X223162Y363673D01*
X222949Y363756D01*
G01X215764Y389676D02*
X215609Y389446D01*
X215506Y389178D01*
Y388871D01*
X215661Y388526D01*
X215919Y388258D01*
X216229Y388066D01*
X216746Y387913D01*
X217211Y387875D01*
X217676Y387951D01*
X217986Y388066D01*
X218296Y388296D01*
X218503Y388565D01*
X218606Y388833D01*
Y389101D01*
X218503Y389370D01*
X218348Y389600D01*
X218141Y389791D01*
G01X218606Y391933D02*
X215506D01*
X216126Y391473D01*
G01X218606D02*
Y392393D01*
G01X217986Y394190D02*
X218348Y394420D01*
X218554Y394726D01*
X218606Y395071D01*
X218554Y395378D01*
X218296Y395685D01*
X217986Y395876D01*
X217676Y395915D01*
X217314Y395838D01*
X217056Y395570D01*
X216953Y395301D01*
Y394956D01*
G01Y395301D02*
X216798Y395531D01*
X216539Y395723D01*
X216229Y395800D01*
X215919Y395723D01*
X215661Y395531D01*
X215506Y395186D01*
X215558Y394841D01*
X215764Y394496D01*
G01X218606Y398056D02*
X217934Y398133D01*
X217366Y398248D01*
X216849Y398401D01*
X216281Y398593D01*
X215506Y398900D01*
Y397366D01*
G01X213260Y393278D02*
Y387078D01*
G01X214329Y383848D02*
Y377648D01*
G01X215129D02*
Y383848D01*
G01D02*
X218329D01*
G01D02*
Y377648D01*
G01D02*
X215129D01*
G01X219129D02*
Y383848D01*
G01D02*
X222329D01*
G01D02*
Y377648D01*
G01D02*
X219129D01*
G01X226329Y383848D02*
Y377648D01*
G01X223129D02*
Y383848D01*
G01D02*
X226329D01*
G01Y377648D02*
X223129D01*
G01X222828Y398215D02*
Y392015D01*
G01D02*
X219628D01*
G01D02*
Y398215D01*
G01X226828D02*
Y392015D01*
G01D02*
X223628D01*
G01D02*
Y398215D01*
G01X215559Y401873D02*
X215404Y401643D01*
X215301Y401375D01*
Y401068D01*
X215456Y400723D01*
X215714Y400455D01*
X216024Y400263D01*
X216541Y400110D01*
X217006Y400072D01*
X217471Y400148D01*
X217781Y400263D01*
X218091Y400493D01*
X218298Y400762D01*
X218401Y401030D01*
Y401298D01*
X218298Y401567D01*
X218143Y401797D01*
X217936Y401988D01*
G01X218401Y404130D02*
X215301D01*
X215921Y403670D01*
G01X218401D02*
Y404590D01*
G01X217781Y406387D02*
X218143Y406617D01*
X218349Y406923D01*
X218401Y407268D01*
X218349Y407575D01*
X218091Y407882D01*
X217781Y408073D01*
X217471Y408112D01*
X217109Y408035D01*
X216851Y407767D01*
X216748Y407498D01*
Y407153D01*
G01Y407498D02*
X216593Y407728D01*
X216334Y407920D01*
X216024Y407997D01*
X215714Y407920D01*
X215456Y407728D01*
X215301Y407383D01*
X215353Y407038D01*
X215559Y406693D01*
G01X218401Y410330D02*
X218349Y410598D01*
X218194Y410905D01*
X217936Y411097D01*
X217574Y411173D01*
X217213Y411097D01*
X216903Y410867D01*
X216748Y410522D01*
Y410138D01*
X216644Y409908D01*
X216386Y409717D01*
X216024Y409640D01*
X215663Y409755D01*
X215404Y410023D01*
X215301Y410330D01*
X215404Y410637D01*
X215663Y410905D01*
X216024Y411020D01*
X216386Y410943D01*
X216644Y410752D01*
X216748Y410522D01*
Y410138D01*
X216903Y409793D01*
X217213Y409563D01*
X217574Y409487D01*
X217936Y409563D01*
X218194Y409755D01*
X218349Y410062D01*
X218401Y410330D01*
G01X213300Y400214D02*
Y394014D01*
G01X222783Y399491D02*
X219683D01*
Y400450D01*
X219838Y400756D01*
X220045Y400948D01*
X220458Y401025D01*
X220871Y400948D01*
X221130Y400718D01*
X221285Y400450D01*
Y399491D01*
G01Y400450D02*
X222783Y401025D01*
G01Y403358D02*
X219683D01*
X220303Y402898D01*
G01X222783D02*
Y403818D01*
G01X222421Y405806D02*
X222680Y406075D01*
X222783Y406381D01*
X222680Y406688D01*
X222370Y406956D01*
X221905Y407148D01*
X221440Y407225D01*
X220871D01*
X220406Y407148D01*
X219993Y406956D01*
X219786Y406726D01*
X219683Y406458D01*
X219786Y406151D01*
X219993Y405921D01*
X220303Y405768D01*
X220716Y405691D01*
X221078Y405768D01*
X221440Y405960D01*
X221646Y406190D01*
X221698Y406458D01*
X221595Y406765D01*
X221336Y406995D01*
X220871Y407225D01*
G01X221491Y408830D02*
X221130Y409098D01*
X220923Y409328D01*
X220820Y409635D01*
X220923Y409903D01*
X221130Y410095D01*
X221440Y410248D01*
X221801Y410286D01*
X222111Y410248D01*
X222421Y410095D01*
X222680Y409865D01*
X222783Y409596D01*
X222680Y409290D01*
X222370Y409021D01*
X221905Y408868D01*
X221388Y408830D01*
X220716Y408906D01*
X220355Y409021D01*
X219993Y409213D01*
X219735Y409481D01*
X219683Y409750D01*
X219786Y410018D01*
X220045Y410210D01*
G01X219628Y398215D02*
X222828D01*
G01X226783Y399491D02*
X223683D01*
Y400450D01*
X223838Y400756D01*
X224045Y400948D01*
X224458Y401025D01*
X224871Y400948D01*
X225130Y400718D01*
X225285Y400450D01*
Y399491D01*
G01Y400450D02*
X226783Y401025D01*
G01Y403358D02*
X223683D01*
X224303Y402898D01*
G01X226783D02*
Y403818D01*
G01X226421Y405806D02*
X226680Y406075D01*
X226783Y406381D01*
X226680Y406688D01*
X226370Y406956D01*
X225905Y407148D01*
X225440Y407225D01*
X224871D01*
X224406Y407148D01*
X223993Y406956D01*
X223786Y406726D01*
X223683Y406458D01*
X223786Y406151D01*
X223993Y405921D01*
X224303Y405768D01*
X224716Y405691D01*
X225078Y405768D01*
X225440Y405960D01*
X225646Y406190D01*
X225698Y406458D01*
X225595Y406765D01*
X225336Y406995D01*
X224871Y407225D01*
G01X226783Y409481D02*
X226111Y409558D01*
X225543Y409673D01*
X225026Y409826D01*
X224458Y410018D01*
X223683Y410325D01*
Y408791D01*
G01X223628Y398215D02*
X226828D01*
G01X229746Y448297D02*
X226646D01*
Y449256D01*
X226801Y449562D01*
X227008Y449754D01*
X227421Y449831D01*
X227834Y449754D01*
X228093Y449524D01*
X228248Y449256D01*
Y448297D01*
G01Y449256D02*
X229746Y449831D01*
G01X229126Y451321D02*
X229488Y451551D01*
X229694Y451857D01*
X229746Y452202D01*
X229694Y452509D01*
X229436Y452816D01*
X229126Y453007D01*
X228816Y453046D01*
X228454Y452969D01*
X228196Y452701D01*
X228093Y452432D01*
Y452087D01*
G01Y452432D02*
X227938Y452662D01*
X227679Y452854D01*
X227369Y452931D01*
X227059Y452854D01*
X226801Y452662D01*
X226646Y452317D01*
X226698Y451972D01*
X226904Y451627D01*
G01X229746Y455724D02*
X226646D01*
X228868Y454306D01*
Y456222D01*
G01X229746Y458824D02*
X226646D01*
X228868Y457406D01*
Y459322D01*
G01X222353Y465292D02*
Y471492D01*
G01X225553Y465292D02*
X222353D01*
G01X225553Y471492D02*
Y465292D01*
G01X226642Y465249D02*
Y471449D01*
G01X229842Y465249D02*
X226642D01*
G01X222231Y458206D02*
X222391Y458456D01*
X222578Y458581D01*
X222791Y458623D01*
X223058Y458540D01*
X223245Y458331D01*
X223298Y458081D01*
X223271Y457831D01*
X223165Y457623D01*
X222631Y457206D01*
X222391Y456915D01*
X222231Y456498D01*
X222178Y456123D01*
X223298D01*
G01X221409Y472353D02*
Y459753D01*
G01X216209Y473653D02*
Y478653D01*
G01X211609Y473853D02*
Y478453D01*
G01X218040Y480833D02*
X221240D01*
G01X218040Y474633D02*
Y480833D01*
G01X221240Y474633D02*
X218040D01*
G01X221240Y480833D02*
Y474633D01*
G01X222353Y471492D02*
X225553D01*
G01X226642Y471449D02*
X229842D01*
G01X221651Y473123D02*
X221811Y472831D01*
X222025Y472665D01*
X222265Y472623D01*
X222478Y472665D01*
X222691Y472873D01*
X222825Y473123D01*
X222851Y473373D01*
X222798Y473665D01*
X222611Y473873D01*
X222425Y473956D01*
X222185D01*
G01X222425D02*
X222585Y474081D01*
X222718Y474290D01*
X222771Y474540D01*
X222718Y474790D01*
X222585Y474998D01*
X222345Y475123D01*
X222105Y475081D01*
X221865Y474915D01*
G01X221228Y493345D02*
Y568541D01*
G01X296424Y493345D02*
X221228D01*
G01X224938Y570315D02*
X221838Y571273D01*
X224938Y572231D01*
G01X223853Y571886D02*
Y570660D01*
G01X223285Y574680D02*
X223130Y574833D01*
X222871Y574948D01*
X222510Y575025D01*
X222200Y574948D01*
X221993Y574795D01*
X221838Y574526D01*
Y573491D01*
X224938D01*
Y574756D01*
X224731Y575025D01*
X224421Y575178D01*
X224060Y575255D01*
X223698Y575178D01*
X223388Y574948D01*
X223285Y574680D01*
Y573491D01*
G01X221228Y568541D02*
X296424D01*
G01X213953Y595457D02*
Y598457D01*
G01X217053Y598557D02*
Y595357D01*
G01X218228Y586122D02*
X228428D01*
G01X218228Y581522D02*
Y586122D01*
G01X228428Y581522D02*
X218228D01*
G01X217236Y608998D02*
X219458D01*
X219923Y609151D01*
X220233Y609458D01*
X220336Y609841D01*
X220233Y610224D01*
X219923Y610531D01*
X219458Y610684D01*
X217236D01*
G01X219716Y612098D02*
X220078Y612328D01*
X220284Y612634D01*
X220336Y612979D01*
X220284Y613286D01*
X220026Y613593D01*
X219716Y613784D01*
X219406Y613823D01*
X219044Y613746D01*
X218786Y613478D01*
X218683Y613209D01*
Y612864D01*
G01Y613209D02*
X218528Y613439D01*
X218269Y613631D01*
X217959Y613708D01*
X217649Y613631D01*
X217391Y613439D01*
X217236Y613094D01*
X217288Y612749D01*
X217494Y612404D01*
G01X219044Y615313D02*
X218683Y615581D01*
X218476Y615811D01*
X218373Y616118D01*
X218476Y616386D01*
X218683Y616578D01*
X218993Y616731D01*
X219354Y616769D01*
X219664Y616731D01*
X219974Y616578D01*
X220233Y616348D01*
X220336Y616079D01*
X220233Y615773D01*
X219923Y615504D01*
X219458Y615351D01*
X218941Y615313D01*
X218269Y615389D01*
X217908Y615504D01*
X217546Y615696D01*
X217288Y615964D01*
X217236Y616233D01*
X217339Y616501D01*
X217598Y616693D01*
G01X221869Y607433D02*
Y611233D01*
G01D02*
X223669Y613033D01*
G01X225269Y609533D02*
G02I-1000J0D01*
G01X241669Y607433D02*
X221869D01*
G01X213953Y599457D02*
Y602457D01*
G01X217053Y602557D02*
Y599357D01*
G01X223669Y613033D02*
X221869Y614833D01*
G01D02*
Y618633D01*
G01D02*
X241669D01*
G01X218531Y623954D02*
X218376Y623724D01*
X218273Y623456D01*
Y623149D01*
X218428Y622804D01*
X218686Y622536D01*
X218996Y622344D01*
X219513Y622191D01*
X219978Y622153D01*
X220443Y622229D01*
X220753Y622344D01*
X221063Y622574D01*
X221270Y622843D01*
X221373Y623111D01*
Y623379D01*
X221270Y623648D01*
X221115Y623878D01*
X220908Y624069D01*
G01X220753Y625368D02*
X221115Y625598D01*
X221321Y625904D01*
X221373Y626249D01*
X221321Y626556D01*
X221063Y626863D01*
X220753Y627054D01*
X220443Y627093D01*
X220081Y627016D01*
X219823Y626748D01*
X219720Y626479D01*
Y626134D01*
G01Y626479D02*
X219565Y626709D01*
X219306Y626901D01*
X218996Y626978D01*
X218686Y626901D01*
X218428Y626709D01*
X218273Y626364D01*
X218325Y626019D01*
X218531Y625674D01*
G01X221011Y628659D02*
X221270Y628928D01*
X221373Y629234D01*
X221270Y629541D01*
X220960Y629809D01*
X220495Y630001D01*
X220030Y630078D01*
X219461D01*
X218996Y630001D01*
X218583Y629809D01*
X218376Y629579D01*
X218273Y629311D01*
X218376Y629004D01*
X218583Y628774D01*
X218893Y628621D01*
X219306Y628544D01*
X219668Y628621D01*
X220030Y628813D01*
X220236Y629043D01*
X220288Y629311D01*
X220185Y629618D01*
X219926Y629848D01*
X219461Y630078D01*
G01X218273Y632411D02*
X218376Y632104D01*
X218635Y631874D01*
X218945Y631721D01*
X219358Y631606D01*
X219823Y631568D01*
X220288Y631606D01*
X220701Y631721D01*
X221011Y631874D01*
X221270Y632104D01*
X221373Y632411D01*
X221270Y632718D01*
X221011Y632948D01*
X220701Y633101D01*
X220288Y633216D01*
X219823Y633254D01*
X219358Y633216D01*
X218945Y633101D01*
X218635Y632948D01*
X218376Y632718D01*
X218273Y632411D01*
G01X213974Y623577D02*
Y620377D01*
G01Y627577D02*
Y624377D01*
G01Y631577D02*
Y628377D01*
G01Y639577D02*
Y636377D01*
G01Y635577D02*
Y632377D01*
G01X222729Y640614D02*
Y634414D01*
G01D02*
X219529D01*
G01D02*
Y640614D01*
G01D02*
X222729D01*
G01X219629Y637514D02*
X222629D01*
G01X226355Y643705D02*
X223255D01*
Y644664D01*
X223410Y644970D01*
X223617Y645162D01*
X224030Y645239D01*
X224443Y645162D01*
X224702Y644932D01*
X224857Y644664D01*
Y643705D01*
G01Y644664D02*
X226355Y645239D01*
G01X225890Y646729D02*
X226148Y646959D01*
X226303Y647227D01*
X226355Y647572D01*
X226252Y647917D01*
X226045Y648185D01*
X225683Y648377D01*
X225270Y648415D01*
X224857Y648339D01*
X224598Y648147D01*
X224392Y647879D01*
X224340Y647610D01*
X224392Y647342D01*
X224598Y646997D01*
X223255Y647112D01*
Y648147D01*
G01X225890Y649829D02*
X226148Y650059D01*
X226303Y650327D01*
X226355Y650672D01*
X226252Y651017D01*
X226045Y651285D01*
X225683Y651477D01*
X225270Y651515D01*
X224857Y651439D01*
X224598Y651247D01*
X224392Y650979D01*
X224340Y650710D01*
X224392Y650442D01*
X224598Y650097D01*
X223255Y650212D01*
Y651247D01*
G01X225735Y652929D02*
X226097Y653159D01*
X226303Y653465D01*
X226355Y653810D01*
X226303Y654117D01*
X226045Y654424D01*
X225735Y654615D01*
X225425Y654654D01*
X225063Y654577D01*
X224805Y654309D01*
X224702Y654040D01*
Y653695D01*
G01Y654040D02*
X224547Y654270D01*
X224288Y654462D01*
X223978Y654539D01*
X223668Y654462D01*
X223410Y654270D01*
X223255Y653925D01*
X223307Y653580D01*
X223513Y653235D01*
G01X226779Y634414D02*
X223579D01*
G01X226779Y640614D02*
Y634414D01*
G01X223579D02*
Y640614D01*
G01D02*
X226779D01*
G01X220804Y670272D02*
Y673272D01*
G01X217704Y670172D02*
Y673372D01*
G01X223904Y670172D02*
X217704D01*
G01Y673372D02*
X223904D01*
G01D02*
Y670172D01*
G01X224631Y675179D02*
Y691179D01*
G01X236835Y675179D02*
X224631D01*
G01X214788Y672034D02*
Y674534D01*
X213801Y672742D01*
X215135D01*
G01X224726Y671938D02*
X224886Y671730D01*
X225073Y671605D01*
X225313Y671563D01*
X225553Y671646D01*
X225740Y671813D01*
X225873Y672105D01*
X225900Y672438D01*
X225846Y672771D01*
X225713Y672980D01*
X225526Y673146D01*
X225340Y673188D01*
X225153Y673146D01*
X224913Y672980D01*
X224993Y674063D01*
X225713D01*
G01X223207Y691179D02*
Y675179D01*
G01X225741Y692438D02*
X225901Y692146D01*
X226115Y691980D01*
X226355Y691938D01*
X226568Y691980D01*
X226781Y692188D01*
X226915Y692438D01*
X226941Y692688D01*
X226888Y692980D01*
X226701Y693188D01*
X226515Y693271D01*
X226275D01*
G01X226515D02*
X226675Y693396D01*
X226808Y693605D01*
X226861Y693855D01*
X226808Y694105D01*
X226675Y694313D01*
X226435Y694438D01*
X226195Y694396D01*
X225955Y694230D01*
G01X224631Y691179D02*
X236835D01*
G01X220037Y692047D02*
Y694547D01*
X219717Y694047D01*
G01Y692047D02*
X220357D01*
G01X211651Y693123D02*
X211811Y692831D01*
X212025Y692665D01*
X212265Y692623D01*
X212478Y692665D01*
X212691Y692873D01*
X212825Y693123D01*
X212851Y693373D01*
X212798Y693665D01*
X212611Y693873D01*
X212425Y693956D01*
X212185D01*
G01X212425D02*
X212585Y694081D01*
X212718Y694290D01*
X212771Y694540D01*
X212718Y694790D01*
X212585Y694998D01*
X212345Y695123D01*
X212105Y695081D01*
X211865Y694915D01*
G01X215584Y693036D02*
Y695536D01*
X216118D01*
X216331Y695411D01*
X216491Y695244D01*
X216624Y694994D01*
X216731Y694703D01*
X216758Y694286D01*
X216731Y693869D01*
X216624Y693578D01*
X216491Y693328D01*
X216331Y693161D01*
X216118Y693036D01*
X215584D01*
G01X221940Y711456D02*
Y696456D01*
G01X223440D02*
Y711456D01*
G01X236440Y696456D02*
X223440D01*
G01X211900Y717330D02*
X266430D01*
G01X211900Y721940D02*
Y717330D01*
G01X216105Y712063D02*
X216313Y712276D01*
X216438Y712516D01*
Y712730D01*
X216313Y712943D01*
X216105Y713103D01*
X215813Y713183D01*
X215521Y713130D01*
X215271Y712996D01*
X215105Y712756D01*
X215021Y712436D01*
X214855Y712250D01*
X214563Y712170D01*
X214271Y712223D01*
X214063Y712356D01*
X213938Y712543D01*
Y712730D01*
X214021Y712916D01*
X214230Y713076D01*
G01X223100Y714706D02*
X223633D01*
Y713956D01*
X223473Y713706D01*
X223287Y713539D01*
X223020Y713456D01*
X222753Y713539D01*
X222567Y713706D01*
X222407Y713956D01*
X222300Y714248D01*
X222247Y714581D01*
Y714873D01*
X222300Y715123D01*
X222407Y715414D01*
X222567Y715664D01*
X222727Y715831D01*
X222940Y715956D01*
X223127D01*
X223340Y715873D01*
X223500Y715706D01*
G01X224878Y713956D02*
X225091Y713748D01*
X225331Y713623D01*
X225545D01*
X225758Y713748D01*
X225918Y713956D01*
X225998Y714248D01*
X225945Y714540D01*
X225811Y714790D01*
X225571Y714956D01*
X225251Y715040D01*
X225065Y715206D01*
X224985Y715498D01*
X225038Y715790D01*
X225171Y715998D01*
X225358Y716123D01*
X225545D01*
X225731Y716040D01*
X225891Y715831D01*
G01X223440Y711456D02*
X236440D01*
G01X223040Y737556D02*
X219840D01*
G01X223040Y743756D02*
Y737556D01*
G01X219840D02*
Y743756D01*
G01X227440Y729156D02*
X224440D01*
G01X227540Y726056D02*
X224340D01*
G01Y732256D02*
X227540D01*
G01X224340Y726056D02*
Y732256D01*
G01X214040Y743756D02*
Y737556D01*
G01X218540D02*
X215340D01*
G01X218540Y743756D02*
Y737556D01*
G01X215340D02*
Y743756D01*
G01X214039Y732256D02*
Y726056D01*
G01X224340Y737556D02*
Y743756D01*
G01X227540Y737556D02*
X224340D01*
G01X219840Y732256D02*
X223040D01*
G01X219840Y726056D02*
Y732256D01*
G01X223040Y726056D02*
X219840D01*
G01X223040Y732256D02*
Y726056D01*
G01X215340Y732256D02*
X218540D01*
G01X215340Y726056D02*
Y732256D01*
G01X218540Y726056D02*
X215340D01*
G01X218540Y732256D02*
Y726056D01*
G01X222940Y740656D02*
X219940D01*
G01X219840Y743756D02*
X223040D01*
G01X223886Y746921D02*
X223731Y746691D01*
X223628Y746423D01*
Y746116D01*
X223783Y745771D01*
X224041Y745503D01*
X224351Y745311D01*
X224868Y745158D01*
X225333Y745120D01*
X225798Y745196D01*
X226108Y745311D01*
X226418Y745541D01*
X226625Y745810D01*
X226728Y746078D01*
Y746346D01*
X226625Y746615D01*
X226470Y746845D01*
X226263Y747036D01*
G01X226728Y749101D02*
X226056Y749178D01*
X225488Y749293D01*
X224971Y749446D01*
X224403Y749638D01*
X223628Y749945D01*
Y748411D01*
G01X226728Y752278D02*
X223628D01*
X224248Y751818D01*
G01X226728D02*
Y752738D01*
G01X224145Y754650D02*
X223835Y754880D01*
X223680Y755148D01*
X223628Y755455D01*
X223731Y755838D01*
X223990Y756106D01*
X224300Y756183D01*
X224610Y756145D01*
X224868Y755991D01*
X225385Y755225D01*
X225746Y754880D01*
X226263Y754650D01*
X226728Y754573D01*
Y756183D01*
G01X215340Y743756D02*
X218540D01*
G01X218440Y740656D02*
X215440D01*
G01X224340Y743756D02*
X227540D01*
G01X222728Y745311D02*
X219628D01*
Y746270D01*
X219783Y746576D01*
X219990Y746768D01*
X220403Y746845D01*
X220816Y746768D01*
X221075Y746538D01*
X221230Y746270D01*
Y745311D01*
G01Y746270D02*
X222728Y746845D01*
G01X222366Y748526D02*
X222625Y748795D01*
X222728Y749101D01*
X222625Y749408D01*
X222315Y749676D01*
X221850Y749868D01*
X221385Y749945D01*
X220816D01*
X220351Y749868D01*
X219938Y749676D01*
X219731Y749446D01*
X219628Y749178D01*
X219731Y748871D01*
X219938Y748641D01*
X220248Y748488D01*
X220661Y748411D01*
X221023Y748488D01*
X221385Y748680D01*
X221591Y748910D01*
X221643Y749178D01*
X221540Y749485D01*
X221281Y749715D01*
X220816Y749945D01*
G01X222263Y751435D02*
X222521Y751665D01*
X222676Y751933D01*
X222728Y752278D01*
X222625Y752623D01*
X222418Y752891D01*
X222056Y753083D01*
X221643Y753121D01*
X221230Y753045D01*
X220971Y752853D01*
X220765Y752585D01*
X220713Y752316D01*
X220765Y752048D01*
X220971Y751703D01*
X219628Y751818D01*
Y752853D01*
G01X220145Y754650D02*
X219835Y754880D01*
X219680Y755148D01*
X219628Y755455D01*
X219731Y755838D01*
X219990Y756106D01*
X220300Y756183D01*
X220610Y756145D01*
X220868Y755991D01*
X221385Y755225D01*
X221746Y754880D01*
X222263Y754650D01*
X222728Y754573D01*
Y756183D01*
G01X218144Y745311D02*
X215044D01*
Y746270D01*
X215199Y746576D01*
X215406Y746768D01*
X215819Y746845D01*
X216232Y746768D01*
X216491Y746538D01*
X216646Y746270D01*
Y745311D01*
G01Y746270D02*
X218144Y746845D01*
G01Y749178D02*
X218092Y749446D01*
X217937Y749753D01*
X217679Y749945D01*
X217317Y750021D01*
X216956Y749945D01*
X216646Y749715D01*
X216491Y749370D01*
Y748986D01*
X216387Y748756D01*
X216129Y748565D01*
X215767Y748488D01*
X215406Y748603D01*
X215147Y748871D01*
X215044Y749178D01*
X215147Y749485D01*
X215406Y749753D01*
X215767Y749868D01*
X216129Y749791D01*
X216387Y749600D01*
X216491Y749370D01*
Y748986D01*
X216646Y748641D01*
X216956Y748411D01*
X217317Y748335D01*
X217679Y748411D01*
X217937Y748603D01*
X218092Y748910D01*
X218144Y749178D01*
G01X215561Y751550D02*
X215251Y751780D01*
X215096Y752048D01*
X215044Y752355D01*
X215147Y752738D01*
X215406Y753006D01*
X215716Y753083D01*
X216026Y753045D01*
X216284Y752891D01*
X216801Y752125D01*
X217162Y751780D01*
X217679Y751550D01*
X218144Y751473D01*
Y753083D01*
G01X215044Y755378D02*
X215147Y755071D01*
X215406Y754841D01*
X215716Y754688D01*
X216129Y754573D01*
X216594Y754535D01*
X217059Y754573D01*
X217472Y754688D01*
X217782Y754841D01*
X218041Y755071D01*
X218144Y755378D01*
X218041Y755685D01*
X217782Y755915D01*
X217472Y756068D01*
X217059Y756183D01*
X216594Y756221D01*
X216129Y756183D01*
X215716Y756068D01*
X215406Y755915D01*
X215147Y755685D01*
X215044Y755378D01*
G01X221216Y760558D02*
X221061Y760328D01*
X220958Y760060D01*
Y759753D01*
X221113Y759408D01*
X221371Y759140D01*
X221681Y758948D01*
X222198Y758795D01*
X222663Y758757D01*
X223128Y758833D01*
X223438Y758948D01*
X223748Y759178D01*
X223955Y759447D01*
X224058Y759715D01*
Y759983D01*
X223955Y760252D01*
X223800Y760482D01*
X223593Y760673D01*
G01X224058Y762738D02*
X223386Y762815D01*
X222818Y762930D01*
X222301Y763083D01*
X221733Y763275D01*
X220958Y763582D01*
Y762048D01*
G01X224058Y765915D02*
X220958D01*
X221578Y765455D01*
G01X224058D02*
Y766375D01*
G01X223593Y768172D02*
X223851Y768402D01*
X224006Y768670D01*
X224058Y769015D01*
X223955Y769360D01*
X223748Y769628D01*
X223386Y769820D01*
X222973Y769858D01*
X222560Y769782D01*
X222301Y769590D01*
X222095Y769322D01*
X222043Y769053D01*
X222095Y768785D01*
X222301Y768440D01*
X220958Y768555D01*
Y769590D01*
G01X212470Y760558D02*
X212315Y760328D01*
X212212Y760060D01*
Y759753D01*
X212367Y759408D01*
X212625Y759140D01*
X212935Y758948D01*
X213452Y758795D01*
X213917Y758757D01*
X214382Y758833D01*
X214692Y758948D01*
X215002Y759178D01*
X215209Y759447D01*
X215312Y759715D01*
Y759983D01*
X215209Y760252D01*
X215054Y760482D01*
X214847Y760673D01*
G01Y761972D02*
X215105Y762202D01*
X215260Y762470D01*
X215312Y762815D01*
X215209Y763160D01*
X215002Y763428D01*
X214640Y763620D01*
X214227Y763658D01*
X213814Y763582D01*
X213555Y763390D01*
X213349Y763122D01*
X213297Y762853D01*
X213349Y762585D01*
X213555Y762240D01*
X212212Y762355D01*
Y763390D01*
G01X215312Y765915D02*
X215260Y766183D01*
X215105Y766490D01*
X214847Y766682D01*
X214485Y766758D01*
X214124Y766682D01*
X213814Y766452D01*
X213659Y766107D01*
Y765723D01*
X213555Y765493D01*
X213297Y765302D01*
X212935Y765225D01*
X212574Y765340D01*
X212315Y765608D01*
X212212Y765915D01*
X212315Y766222D01*
X212574Y766490D01*
X212935Y766605D01*
X213297Y766528D01*
X213555Y766337D01*
X213659Y766107D01*
Y765723D01*
X213814Y765378D01*
X214124Y765148D01*
X214485Y765072D01*
X214847Y765148D01*
X215105Y765340D01*
X215260Y765647D01*
X215312Y765915D01*
G01Y768938D02*
X214640Y769015D01*
X214072Y769130D01*
X213555Y769283D01*
X212987Y769475D01*
X212212Y769782D01*
Y768248D01*
G01X216870Y760558D02*
X216715Y760328D01*
X216612Y760060D01*
Y759753D01*
X216767Y759408D01*
X217025Y759140D01*
X217335Y758948D01*
X217852Y758795D01*
X218317Y758757D01*
X218782Y758833D01*
X219092Y758948D01*
X219402Y759178D01*
X219609Y759447D01*
X219712Y759715D01*
Y759983D01*
X219609Y760252D01*
X219454Y760482D01*
X219247Y760673D01*
G01Y761972D02*
X219505Y762202D01*
X219660Y762470D01*
X219712Y762815D01*
X219609Y763160D01*
X219402Y763428D01*
X219040Y763620D01*
X218627Y763658D01*
X218214Y763582D01*
X217955Y763390D01*
X217749Y763122D01*
X217697Y762853D01*
X217749Y762585D01*
X217955Y762240D01*
X216612Y762355D01*
Y763390D01*
G01X219712Y765915D02*
X219660Y766183D01*
X219505Y766490D01*
X219247Y766682D01*
X218885Y766758D01*
X218524Y766682D01*
X218214Y766452D01*
X218059Y766107D01*
Y765723D01*
X217955Y765493D01*
X217697Y765302D01*
X217335Y765225D01*
X216974Y765340D01*
X216715Y765608D01*
X216612Y765915D01*
X216715Y766222D01*
X216974Y766490D01*
X217335Y766605D01*
X217697Y766528D01*
X217955Y766337D01*
X218059Y766107D01*
Y765723D01*
X218214Y765378D01*
X218524Y765148D01*
X218885Y765072D01*
X219247Y765148D01*
X219505Y765340D01*
X219660Y765647D01*
X219712Y765915D01*
G01X219350Y768363D02*
X219609Y768632D01*
X219712Y768938D01*
X219609Y769245D01*
X219299Y769513D01*
X218834Y769705D01*
X218369Y769782D01*
X217800D01*
X217335Y769705D01*
X216922Y769513D01*
X216715Y769283D01*
X216612Y769015D01*
X216715Y768708D01*
X216922Y768478D01*
X217232Y768325D01*
X217645Y768248D01*
X218007Y768325D01*
X218369Y768517D01*
X218575Y768747D01*
X218627Y769015D01*
X218524Y769322D01*
X218265Y769552D01*
X217800Y769782D01*
G01X228878Y758948D02*
X225778D01*
Y759907D01*
X225933Y760213D01*
X226140Y760405D01*
X226553Y760482D01*
X226966Y760405D01*
X227225Y760175D01*
X227380Y759907D01*
Y758948D01*
G01Y759907D02*
X228878Y760482D01*
G01X228516Y762163D02*
X228775Y762432D01*
X228878Y762738D01*
X228775Y763045D01*
X228465Y763313D01*
X228000Y763505D01*
X227535Y763582D01*
X226966D01*
X226501Y763505D01*
X226088Y763313D01*
X225881Y763083D01*
X225778Y762815D01*
X225881Y762508D01*
X226088Y762278D01*
X226398Y762125D01*
X226811Y762048D01*
X227173Y762125D01*
X227535Y762317D01*
X227741Y762547D01*
X227793Y762815D01*
X227690Y763122D01*
X227431Y763352D01*
X226966Y763582D01*
G01X228878Y766375D02*
X225778D01*
X228000Y764957D01*
Y766873D01*
G01X228516Y768363D02*
X228775Y768632D01*
X228878Y768938D01*
X228775Y769245D01*
X228465Y769513D01*
X228000Y769705D01*
X227535Y769782D01*
X226966D01*
X226501Y769705D01*
X226088Y769513D01*
X225881Y769283D01*
X225778Y769015D01*
X225881Y768708D01*
X226088Y768478D01*
X226398Y768325D01*
X226811Y768248D01*
X227173Y768325D01*
X227535Y768517D01*
X227741Y768747D01*
X227793Y769015D01*
X227690Y769322D01*
X227431Y769552D01*
X226966Y769782D01*
G01X232493Y-186364D02*
Y-194364D01*
X236493D01*
G01X244293D02*
Y-189031D01*
G01Y-189964D02*
X243893Y-189431D01*
X243293Y-189164D01*
X242593Y-189031D01*
X241893Y-189297D01*
X241293Y-189831D01*
X240893Y-190631D01*
X240693Y-191697D01*
X240893Y-192764D01*
X241293Y-193564D01*
X241893Y-194097D01*
X242593Y-194364D01*
X243293Y-194231D01*
X243893Y-193831D01*
X244293Y-193298D01*
G01X248393Y-196764D02*
X248993Y-197031D01*
X249793Y-196764D01*
X250293Y-196231D01*
X250693Y-195564D01*
X251293Y-193431D01*
X252593Y-189031D01*
G01X249393D02*
X251293Y-193431D01*
G01X256993Y-190764D02*
X260193D01*
X259893Y-189831D01*
X259393Y-189297D01*
X258693Y-189031D01*
X257993Y-189164D01*
X257393Y-189564D01*
X256993Y-190497D01*
X256793Y-191298D01*
Y-192097D01*
X256993Y-192897D01*
X257493Y-193697D01*
X258093Y-194231D01*
X258793Y-194364D01*
X259493Y-194097D01*
X260193Y-193298D01*
G01X265093Y-194364D02*
Y-189031D01*
G01Y-190097D02*
X265593Y-189564D01*
X266093Y-189164D01*
X266793Y-189031D01*
X267293Y-189164D01*
X267893Y-189564D01*
G01X235189Y44331D02*
Y8635D01*
G01X238140Y4174D02*
Y7274D01*
X239060D01*
X239367Y7119D01*
X239597Y6757D01*
X239674Y6344D01*
X239597Y5931D01*
X239405Y5621D01*
X239060Y5466D01*
X238140D01*
G01X242850Y7016D02*
X242620Y7171D01*
X242352Y7274D01*
X242045D01*
X241700Y7119D01*
X241432Y6861D01*
X241240Y6551D01*
X241087Y6034D01*
X241049Y5569D01*
X241125Y5104D01*
X241240Y4794D01*
X241470Y4484D01*
X241739Y4277D01*
X242007Y4174D01*
X242275D01*
X242544Y4277D01*
X242774Y4432D01*
X242965Y4639D01*
G01X245030Y4174D02*
X245107Y4846D01*
X245222Y5414D01*
X245375Y5931D01*
X245567Y6499D01*
X245874Y7274D01*
X244340D01*
G01X247555Y4536D02*
X247824Y4277D01*
X248130Y4174D01*
X248437Y4277D01*
X248705Y4587D01*
X248897Y5052D01*
X248974Y5517D01*
Y6086D01*
X248897Y6551D01*
X248705Y6964D01*
X248475Y7171D01*
X248207Y7274D01*
X247900Y7171D01*
X247670Y6964D01*
X247517Y6654D01*
X247440Y6241D01*
X247517Y5879D01*
X247709Y5517D01*
X247939Y5311D01*
X248207Y5259D01*
X248514Y5362D01*
X248744Y5621D01*
X248974Y6086D01*
G01X236289Y8635D02*
Y44331D01*
G01X254005Y8635D02*
X236289D01*
G01Y44331D02*
X254005D01*
G01X227914Y51201D02*
Y66201D01*
G01X228014Y58701D02*
X234614D01*
G01X234714Y66201D02*
Y51201D01*
G01D02*
X227914D01*
G01X236014Y58701D02*
X242614D01*
G01X235914Y51201D02*
Y66201D01*
G01X242714D02*
Y51201D01*
G01D02*
X235914D01*
G01X227914Y66201D02*
X234714D01*
G01X235914D02*
X242714D01*
G01X238516Y74076D02*
X238569Y74618D01*
X238649Y75076D01*
X238756Y75493D01*
X238889Y75951D01*
X239102Y76576D01*
X238036D01*
G01X240769Y74076D02*
Y76576D01*
X240449Y76076D01*
G01Y74076D02*
X241089D01*
G01X240762Y120511D02*
X240815Y121053D01*
X240895Y121511D01*
X241002Y121928D01*
X241135Y122386D01*
X241348Y123011D01*
X240282D01*
G01X242508Y122594D02*
X242668Y122844D01*
X242855Y122969D01*
X243068Y123011D01*
X243335Y122928D01*
X243522Y122719D01*
X243575Y122469D01*
X243548Y122219D01*
X243442Y122011D01*
X242908Y121594D01*
X242668Y121303D01*
X242508Y120886D01*
X242455Y120511D01*
X243575D01*
G01X231457Y134050D02*
X231710Y134300D01*
X231900Y134716D01*
X232027Y135300D01*
X231900Y135800D01*
X231647Y136133D01*
X231203Y136383D01*
X229493D01*
Y131383D01*
X231583D01*
X232027Y131716D01*
X232280Y132216D01*
X232407Y132800D01*
X232280Y133383D01*
X231900Y133883D01*
X231457Y134050D01*
X229493D01*
G01X235220Y159020D02*
Y129120D01*
G01X314216Y186845D02*
Y166468D01*
X241991D01*
Y201267D01*
X262489D01*
Y216288D01*
X288474D01*
G01X235662Y361756D02*
X235822Y361464D01*
X236036Y361298D01*
X236276Y361256D01*
X236489Y361298D01*
X236702Y361506D01*
X236836Y361756D01*
X236862Y362006D01*
X236809Y362298D01*
X236622Y362506D01*
X236436Y362589D01*
X236196D01*
G01X236436D02*
X236596Y362714D01*
X236729Y362923D01*
X236782Y363173D01*
X236729Y363423D01*
X236596Y363631D01*
X236356Y363756D01*
X236116Y363714D01*
X235876Y363548D01*
G01X238449Y361256D02*
X238636Y361298D01*
X238849Y361423D01*
X238982Y361631D01*
X239036Y361923D01*
X238982Y362214D01*
X238822Y362464D01*
X238582Y362589D01*
X238316D01*
X238156Y362673D01*
X238022Y362881D01*
X237969Y363173D01*
X238049Y363464D01*
X238236Y363673D01*
X238449Y363756D01*
X238662Y363673D01*
X238849Y363464D01*
X238929Y363173D01*
X238876Y362881D01*
X238742Y362673D01*
X238582Y362589D01*
X238316D01*
X238076Y362464D01*
X237916Y362214D01*
X237862Y361923D01*
X237916Y361631D01*
X238049Y361423D01*
X238262Y361298D01*
X238449Y361256D01*
G01X229162Y357256D02*
X229322Y356964D01*
X229536Y356798D01*
X229776Y356756D01*
X229989Y356798D01*
X230202Y357006D01*
X230336Y357256D01*
X230362Y357506D01*
X230309Y357798D01*
X230122Y358006D01*
X229936Y358089D01*
X229696D01*
G01X229936D02*
X230096Y358214D01*
X230229Y358423D01*
X230282Y358673D01*
X230229Y358923D01*
X230096Y359131D01*
X229856Y359256D01*
X229616Y359214D01*
X229376Y359048D01*
G01X231362Y357131D02*
X231522Y356923D01*
X231709Y356798D01*
X231949Y356756D01*
X232189Y356839D01*
X232376Y357006D01*
X232509Y357298D01*
X232536Y357631D01*
X232482Y357964D01*
X232349Y358173D01*
X232162Y358339D01*
X231976Y358381D01*
X231789Y358339D01*
X231549Y358173D01*
X231629Y359256D01*
X232349D01*
G01X227662Y361756D02*
X227822Y361464D01*
X228036Y361298D01*
X228276Y361256D01*
X228489Y361298D01*
X228702Y361506D01*
X228836Y361756D01*
X228862Y362006D01*
X228809Y362298D01*
X228622Y362506D01*
X228436Y362589D01*
X228196D01*
G01X228436D02*
X228596Y362714D01*
X228729Y362923D01*
X228782Y363173D01*
X228729Y363423D01*
X228596Y363631D01*
X228356Y363756D01*
X228116Y363714D01*
X227876Y363548D01*
G01X230769Y361256D02*
Y363756D01*
X229782Y361964D01*
X231116D01*
G01X231662Y361756D02*
X231822Y361464D01*
X232036Y361298D01*
X232276Y361256D01*
X232489Y361298D01*
X232702Y361506D01*
X232836Y361756D01*
X232862Y362006D01*
X232809Y362298D01*
X232622Y362506D01*
X232436Y362589D01*
X232196D01*
G01X232436D02*
X232596Y362714D01*
X232729Y362923D01*
X232782Y363173D01*
X232729Y363423D01*
X232596Y363631D01*
X232356Y363756D01*
X232116Y363714D01*
X231876Y363548D01*
G01X233942Y362298D02*
X234129Y362589D01*
X234289Y362756D01*
X234502Y362839D01*
X234689Y362756D01*
X234822Y362589D01*
X234929Y362339D01*
X234956Y362048D01*
X234929Y361798D01*
X234822Y361548D01*
X234662Y361339D01*
X234476Y361256D01*
X234262Y361339D01*
X234076Y361589D01*
X233969Y361964D01*
X233942Y362381D01*
X233996Y362923D01*
X234076Y363214D01*
X234209Y363506D01*
X234396Y363714D01*
X234582Y363756D01*
X234769Y363673D01*
X234902Y363464D01*
G01X238662Y357256D02*
X238822Y356964D01*
X239036Y356798D01*
X239276Y356756D01*
X239489Y356798D01*
X239702Y357006D01*
X239836Y357256D01*
X239862Y357506D01*
X239809Y357798D01*
X239622Y358006D01*
X239436Y358089D01*
X239196D01*
G01X239436D02*
X239596Y358214D01*
X239729Y358423D01*
X239782Y358673D01*
X239729Y358923D01*
X239596Y359131D01*
X239356Y359256D01*
X239116Y359214D01*
X238876Y359048D01*
G01X240996Y357048D02*
X241182Y356839D01*
X241396Y356756D01*
X241609Y356839D01*
X241796Y357089D01*
X241929Y357464D01*
X241982Y357839D01*
Y358298D01*
X241929Y358673D01*
X241796Y359006D01*
X241636Y359173D01*
X241449Y359256D01*
X241236Y359173D01*
X241076Y359006D01*
X240969Y358756D01*
X240916Y358423D01*
X240969Y358131D01*
X241102Y357839D01*
X241262Y357673D01*
X241449Y357631D01*
X241662Y357714D01*
X241822Y357923D01*
X241982Y358298D01*
G01X234162Y357256D02*
X234322Y356964D01*
X234536Y356798D01*
X234776Y356756D01*
X234989Y356798D01*
X235202Y357006D01*
X235336Y357256D01*
X235362Y357506D01*
X235309Y357798D01*
X235122Y358006D01*
X234936Y358089D01*
X234696D01*
G01X234936D02*
X235096Y358214D01*
X235229Y358423D01*
X235282Y358673D01*
X235229Y358923D01*
X235096Y359131D01*
X234856Y359256D01*
X234616Y359214D01*
X234376Y359048D01*
G01X236896Y356756D02*
X236949Y357298D01*
X237029Y357756D01*
X237136Y358173D01*
X237269Y358631D01*
X237482Y359256D01*
X236416D01*
G01X240569Y361256D02*
Y363756D01*
X239582Y361964D01*
X240916D01*
G01X242449Y363756D02*
X242236Y363673D01*
X242076Y363464D01*
X241969Y363214D01*
X241889Y362881D01*
X241862Y362506D01*
X241889Y362131D01*
X241969Y361798D01*
X242076Y361548D01*
X242236Y361339D01*
X242449Y361256D01*
X242662Y361339D01*
X242822Y361548D01*
X242929Y361798D01*
X243009Y362131D01*
X243036Y362506D01*
X243009Y362881D01*
X242929Y363214D01*
X242822Y363464D01*
X242662Y363673D01*
X242449Y363756D01*
G01X243069Y356756D02*
Y359256D01*
X242082Y357464D01*
X243416D01*
G01X244949Y356756D02*
Y359256D01*
X244629Y358756D01*
G01Y356756D02*
X245269D01*
G01X240220Y390960D02*
X259250D01*
G01X240220Y384940D02*
Y390960D01*
G01X234329Y383848D02*
Y377648D01*
G01D02*
X231129D01*
G01D02*
Y383848D01*
G01D02*
X234329D01*
G01X230329D02*
Y377648D01*
G01D02*
X227129D01*
G01D02*
Y383848D01*
G01D02*
X230329D01*
G01X238329D02*
Y377648D01*
G01D02*
X235129D01*
G01D02*
Y383848D01*
G01D02*
X238329D01*
G01X241106Y389564D02*
X247306D01*
G01Y386364D02*
X241106D01*
G01D02*
Y389564D01*
G01X242329Y383848D02*
Y377648D01*
G01D02*
X239129D01*
G01D02*
Y383848D01*
G01D02*
X242329D01*
G01X229052Y406019D02*
Y409119D01*
X229972D01*
X230279Y408964D01*
X230509Y408602D01*
X230586Y408189D01*
X230509Y407776D01*
X230317Y407466D01*
X229972Y407311D01*
X229052D01*
G01X233762Y408861D02*
X233532Y409016D01*
X233264Y409119D01*
X232957D01*
X232612Y408964D01*
X232344Y408706D01*
X232152Y408396D01*
X231999Y407879D01*
X231961Y407414D01*
X232037Y406949D01*
X232152Y406639D01*
X232382Y406329D01*
X232651Y406122D01*
X232919Y406019D01*
X233187D01*
X233456Y406122D01*
X233686Y406277D01*
X233877Y406484D01*
G01X236019Y406019D02*
Y409119D01*
X235559Y408499D01*
G01Y406019D02*
X236479D01*
G01X238391Y407311D02*
X238659Y407672D01*
X238889Y407879D01*
X239196Y407982D01*
X239464Y407879D01*
X239656Y407672D01*
X239809Y407362D01*
X239847Y407001D01*
X239809Y406691D01*
X239656Y406381D01*
X239426Y406122D01*
X239157Y406019D01*
X238851Y406122D01*
X238582Y406432D01*
X238429Y406897D01*
X238391Y407414D01*
X238467Y408086D01*
X238582Y408447D01*
X238774Y408809D01*
X239042Y409067D01*
X239311Y409119D01*
X239579Y409016D01*
X239771Y408757D01*
G01X229052Y397715D02*
Y400815D01*
X229972D01*
X230279Y400660D01*
X230509Y400298D01*
X230586Y399885D01*
X230509Y399472D01*
X230317Y399162D01*
X229972Y399007D01*
X229052D01*
G01X233762Y400557D02*
X233532Y400712D01*
X233264Y400815D01*
X232957D01*
X232612Y400660D01*
X232344Y400402D01*
X232152Y400092D01*
X231999Y399575D01*
X231961Y399110D01*
X232037Y398645D01*
X232152Y398335D01*
X232382Y398025D01*
X232651Y397818D01*
X232919Y397715D01*
X233187D01*
X233456Y397818D01*
X233686Y397973D01*
X233877Y398180D01*
G01X236019Y397715D02*
Y400815D01*
X235559Y400195D01*
G01Y397715D02*
X236479D01*
G01X238276Y398335D02*
X238506Y397973D01*
X238812Y397767D01*
X239157Y397715D01*
X239464Y397767D01*
X239771Y398025D01*
X239962Y398335D01*
X240001Y398645D01*
X239924Y399007D01*
X239656Y399265D01*
X239387Y399368D01*
X239042D01*
G01X239387D02*
X239617Y399523D01*
X239809Y399782D01*
X239886Y400092D01*
X239809Y400402D01*
X239617Y400660D01*
X239272Y400815D01*
X238927Y400763D01*
X238582Y400557D01*
G01X241376Y398335D02*
X241606Y397973D01*
X241912Y397767D01*
X242257Y397715D01*
X242564Y397767D01*
X242871Y398025D01*
X243062Y398335D01*
X243101Y398645D01*
X243024Y399007D01*
X242756Y399265D01*
X242487Y399368D01*
X242142D01*
G01X242487D02*
X242717Y399523D01*
X242909Y399782D01*
X242986Y400092D01*
X242909Y400402D01*
X242717Y400660D01*
X242372Y400815D01*
X242027Y400763D01*
X241682Y400557D01*
G01X229052Y401976D02*
Y405076D01*
X229972D01*
X230279Y404921D01*
X230509Y404559D01*
X230586Y404146D01*
X230509Y403733D01*
X230317Y403423D01*
X229972Y403268D01*
X229052D01*
G01X233762Y404818D02*
X233532Y404973D01*
X233264Y405076D01*
X232957D01*
X232612Y404921D01*
X232344Y404663D01*
X232152Y404353D01*
X231999Y403836D01*
X231961Y403371D01*
X232037Y402906D01*
X232152Y402596D01*
X232382Y402286D01*
X232651Y402079D01*
X232919Y401976D01*
X233187D01*
X233456Y402079D01*
X233686Y402234D01*
X233877Y402441D01*
G01X236019Y401976D02*
Y405076D01*
X235559Y404456D01*
G01Y401976D02*
X236479D01*
G01X239042D02*
X239119Y402648D01*
X239234Y403216D01*
X239387Y403733D01*
X239579Y404301D01*
X239886Y405076D01*
X238352D01*
G01X236390Y421556D02*
Y414956D01*
G01X243890Y414856D02*
X228890D01*
G01Y421656D02*
X243890D01*
G01X228890Y414856D02*
Y421656D01*
G01X227737Y440968D02*
Y414590D01*
G01X229052Y410234D02*
Y413334D01*
X229972D01*
X230279Y413179D01*
X230509Y412817D01*
X230586Y412404D01*
X230509Y411991D01*
X230317Y411681D01*
X229972Y411526D01*
X229052D01*
G01X233762Y413076D02*
X233532Y413231D01*
X233264Y413334D01*
X232957D01*
X232612Y413179D01*
X232344Y412921D01*
X232152Y412611D01*
X231999Y412094D01*
X231961Y411629D01*
X232037Y411164D01*
X232152Y410854D01*
X232382Y410544D01*
X232651Y410337D01*
X232919Y410234D01*
X233187D01*
X233456Y410337D01*
X233686Y410492D01*
X233877Y410699D01*
G01X236019Y410234D02*
Y413334D01*
X235559Y412714D01*
G01Y410234D02*
X236479D01*
G01X239119D02*
X239387Y410286D01*
X239694Y410441D01*
X239886Y410699D01*
X239962Y411061D01*
X239886Y411422D01*
X239656Y411732D01*
X239311Y411887D01*
X238927D01*
X238697Y411991D01*
X238506Y412249D01*
X238429Y412611D01*
X238544Y412972D01*
X238812Y413231D01*
X239119Y413334D01*
X239426Y413231D01*
X239694Y412972D01*
X239809Y412611D01*
X239732Y412249D01*
X239541Y411991D01*
X239311Y411887D01*
X238927D01*
X238582Y411732D01*
X238352Y411422D01*
X238276Y411061D01*
X238352Y410699D01*
X238544Y410441D01*
X238851Y410286D01*
X239119Y410234D01*
G01X228955Y422735D02*
Y429535D01*
G01X236455Y429435D02*
Y422835D01*
G01X243955Y422735D02*
X228955D01*
G01X243955Y430735D02*
X228955D01*
G01Y437535D02*
X243955D01*
G01X228955Y430735D02*
Y437535D01*
G01X236455Y437435D02*
Y430835D01*
G01X233402Y438336D02*
Y441536D01*
G01X236502Y441436D02*
Y438436D01*
G01X239602Y438336D02*
X233402D01*
G01X239602Y441536D02*
Y438336D01*
G01X228955Y429535D02*
X243955D01*
G01X233402Y441536D02*
X239602D01*
G01X234035Y448297D02*
X230935D01*
Y449256D01*
X231090Y449562D01*
X231297Y449754D01*
X231710Y449831D01*
X232123Y449754D01*
X232382Y449524D01*
X232537Y449256D01*
Y448297D01*
G01Y449256D02*
X234035Y449831D01*
G01X233415Y451321D02*
X233777Y451551D01*
X233983Y451857D01*
X234035Y452202D01*
X233983Y452509D01*
X233725Y452816D01*
X233415Y453007D01*
X233105Y453046D01*
X232743Y452969D01*
X232485Y452701D01*
X232382Y452432D01*
Y452087D01*
G01Y452432D02*
X232227Y452662D01*
X231968Y452854D01*
X231658Y452931D01*
X231348Y452854D01*
X231090Y452662D01*
X230935Y452317D01*
X230987Y451972D01*
X231193Y451627D01*
G01X234035Y455724D02*
X230935D01*
X233157Y454306D01*
Y456222D01*
G01X233415Y457521D02*
X233777Y457751D01*
X233983Y458057D01*
X234035Y458402D01*
X233983Y458709D01*
X233725Y459016D01*
X233415Y459207D01*
X233105Y459246D01*
X232743Y459169D01*
X232485Y458901D01*
X232382Y458632D01*
Y458287D01*
G01Y458632D02*
X232227Y458862D01*
X231968Y459054D01*
X231658Y459131D01*
X231348Y459054D01*
X231090Y458862D01*
X230935Y458517D01*
X230987Y458172D01*
X231193Y457827D01*
G01X241964Y448297D02*
X238864D01*
Y449256D01*
X239019Y449562D01*
X239226Y449754D01*
X239639Y449831D01*
X240052Y449754D01*
X240311Y449524D01*
X240466Y449256D01*
Y448297D01*
G01Y449256D02*
X241964Y449831D01*
G01X241344Y451321D02*
X241706Y451551D01*
X241912Y451857D01*
X241964Y452202D01*
X241912Y452509D01*
X241654Y452816D01*
X241344Y453007D01*
X241034Y453046D01*
X240672Y452969D01*
X240414Y452701D01*
X240311Y452432D01*
Y452087D01*
G01Y452432D02*
X240156Y452662D01*
X239897Y452854D01*
X239587Y452931D01*
X239277Y452854D01*
X239019Y452662D01*
X238864Y452317D01*
X238916Y451972D01*
X239122Y451627D01*
G01X241964Y455264D02*
X238864D01*
X239484Y454804D01*
G01X241964D02*
Y455724D01*
G01Y458287D02*
X241292Y458364D01*
X240724Y458479D01*
X240207Y458632D01*
X239639Y458824D01*
X238864Y459131D01*
Y457597D01*
G01X237964Y448297D02*
X234864D01*
Y449256D01*
X235019Y449562D01*
X235226Y449754D01*
X235639Y449831D01*
X236052Y449754D01*
X236311Y449524D01*
X236466Y449256D01*
Y448297D01*
G01Y449256D02*
X237964Y449831D01*
G01X237344Y451321D02*
X237706Y451551D01*
X237912Y451857D01*
X237964Y452202D01*
X237912Y452509D01*
X237654Y452816D01*
X237344Y453007D01*
X237034Y453046D01*
X236672Y452969D01*
X236414Y452701D01*
X236311Y452432D01*
Y452087D01*
G01Y452432D02*
X236156Y452662D01*
X235897Y452854D01*
X235587Y452931D01*
X235277Y452854D01*
X235019Y452662D01*
X234864Y452317D01*
X234916Y451972D01*
X235122Y451627D01*
G01X237964Y455724D02*
X234864D01*
X237086Y454306D01*
Y456222D01*
G01X237964Y458364D02*
X234864D01*
X235484Y457904D01*
G01X237964D02*
Y458824D01*
G01X237723Y442297D02*
Y445397D01*
X238682D01*
X238988Y445242D01*
X239180Y445035D01*
X239257Y444622D01*
X239180Y444209D01*
X238950Y443950D01*
X238682Y443795D01*
X237723D01*
G01X238682D02*
X239257Y442297D01*
G01X241590D02*
Y445397D01*
X241130Y444777D01*
G01Y442297D02*
X242050D01*
G01X244690D02*
Y445397D01*
X244230Y444777D01*
G01Y442297D02*
X245150D01*
G01X247790D02*
Y445397D01*
X247330Y444777D01*
G01Y442297D02*
X248250D01*
G01X250890D02*
Y445397D01*
X250430Y444777D01*
G01Y442297D02*
X251350D01*
G01X229842Y471449D02*
Y465249D01*
G01X243609Y465053D02*
X240409D01*
G01D02*
Y471253D01*
G01X239209Y465053D02*
X236009D01*
G01X239209Y471253D02*
Y465053D01*
G01X236009D02*
Y471253D01*
G01X234909Y465053D02*
X231709D01*
G01X234909Y471253D02*
Y465053D01*
G01X231709D02*
Y471253D01*
G01X308235Y481534D02*
X241438D01*
G01X240309Y479653D02*
X243509D01*
G01X240309Y473453D02*
Y479653D01*
G01X243509Y473453D02*
X240309D01*
G01X236009Y479653D02*
X239209D01*
G01X236009Y473453D02*
Y479653D01*
G01X239209Y473453D02*
X236009D01*
G01X239209Y479653D02*
Y473453D01*
G01X231709Y479653D02*
X234909D01*
G01X231709Y473453D02*
Y479653D01*
G01X234909Y473453D02*
X231709D01*
G01X234909Y479653D02*
Y473453D01*
G01X240409Y471253D02*
X243609D01*
G01X236009D02*
X239209D01*
G01X231709D02*
X234909D01*
G01X233438Y573815D02*
X230338Y574773D01*
X233438Y575731D01*
G01X232353Y575386D02*
Y574160D01*
G01X233438Y576915D02*
X230338Y577873D01*
X233438Y578831D01*
G01X232353Y578486D02*
Y577260D01*
G01X234521Y571688D02*
X233126D01*
X231421Y570921D01*
G01Y572455D02*
X233126Y571688D01*
G01X234571Y576837D02*
X237671Y577374D01*
X234571Y577987D01*
X237671Y578600D01*
X234571Y579137D01*
G01X237720Y570730D02*
X240820Y571688D01*
X237720Y572646D01*
G01X240870Y577144D02*
X243092D01*
X243557Y577297D01*
X243867Y577604D01*
X243970Y577987D01*
X243867Y578370D01*
X243557Y578677D01*
X243092Y578830D01*
X240870D01*
G01X229870Y594480D02*
X243620D01*
G01X229870Y581460D02*
Y594480D01*
G01X229910Y581460D02*
X229870D01*
G01X242141Y584756D02*
X248341D01*
G01X242141Y581556D02*
Y584756D01*
G01X248341Y581556D02*
X242141D01*
G01Y588756D02*
X248341D01*
G01X242141Y585556D02*
Y588756D01*
G01X248341Y585556D02*
X242141D01*
G01X230952Y581327D02*
Y585927D01*
G01X241152Y581327D02*
X230952D01*
G01Y585927D02*
X241152D01*
G01X236052D02*
Y581327D01*
G01X241152Y585927D02*
Y581327D01*
G01X228428Y586122D02*
Y581522D01*
G01X230852Y587027D02*
Y591627D01*
G01X241052Y587027D02*
X230852D01*
G01Y591627D02*
X241052D01*
G01D02*
Y587027D01*
G01X241669Y618633D02*
Y607433D01*
G01X245827Y613530D02*
X242727D01*
Y614489D01*
X242882Y614795D01*
X243089Y614987D01*
X243502Y615064D01*
X243915Y614987D01*
X244174Y614757D01*
X244329Y614489D01*
Y613530D01*
G01Y614489D02*
X245827Y615064D01*
G01Y617397D02*
X242727D01*
X243347Y616937D01*
G01X245827D02*
Y617857D01*
G01Y620497D02*
X242727D01*
X243347Y620037D01*
G01X245827D02*
Y620957D01*
G01X242727Y623597D02*
X242830Y623290D01*
X243089Y623060D01*
X243399Y622907D01*
X243812Y622792D01*
X244277Y622754D01*
X244742Y622792D01*
X245155Y622907D01*
X245465Y623060D01*
X245724Y623290D01*
X245827Y623597D01*
X245724Y623904D01*
X245465Y624134D01*
X245155Y624287D01*
X244742Y624402D01*
X244277Y624440D01*
X243812Y624402D01*
X243399Y624287D01*
X243089Y624134D01*
X242830Y623904D01*
X242727Y623597D01*
G01X245827Y626620D02*
X245155Y626697D01*
X244587Y626812D01*
X244070Y626965D01*
X243502Y627157D01*
X242727Y627464D01*
Y625930D01*
G01X240863Y627366D02*
Y629866D01*
X241397D01*
X241610Y629741D01*
X241770Y629574D01*
X241903Y629324D01*
X242010Y629033D01*
X242037Y628616D01*
X242010Y628199D01*
X241903Y627908D01*
X241770Y627658D01*
X241610Y627491D01*
X241397Y627366D01*
X240863D01*
G01X230799Y634414D02*
X227599D01*
G01D02*
Y640614D01*
G01D02*
X230799D01*
G01D02*
Y634414D01*
G01X230067Y630850D02*
X230280Y630642D01*
X230520Y630517D01*
X230734D01*
X230947Y630642D01*
X231107Y630850D01*
X231187Y631142D01*
X231134Y631434D01*
X231000Y631684D01*
X230760Y631850D01*
X230440Y631934D01*
X230254Y632100D01*
X230174Y632392D01*
X230227Y632684D01*
X230360Y632892D01*
X230547Y633017D01*
X230734D01*
X230920Y632934D01*
X231080Y632725D01*
G01X232163Y643670D02*
X243975D01*
G01Y631046D02*
X232163D01*
G01D02*
Y643670D01*
G01X227659Y655711D02*
X227504Y655481D01*
X227401Y655213D01*
Y654906D01*
X227556Y654561D01*
X227814Y654293D01*
X228124Y654101D01*
X228641Y653948D01*
X229106Y653910D01*
X229571Y653986D01*
X229881Y654101D01*
X230191Y654331D01*
X230398Y654600D01*
X230501Y654868D01*
Y655136D01*
X230398Y655405D01*
X230243Y655635D01*
X230036Y655826D01*
G01X230501Y657968D02*
X230449Y658236D01*
X230294Y658543D01*
X230036Y658735D01*
X229674Y658811D01*
X229313Y658735D01*
X229003Y658505D01*
X228848Y658160D01*
Y657776D01*
X228744Y657546D01*
X228486Y657355D01*
X228124Y657278D01*
X227763Y657393D01*
X227504Y657661D01*
X227401Y657968D01*
X227504Y658275D01*
X227763Y658543D01*
X228124Y658658D01*
X228486Y658581D01*
X228744Y658390D01*
X228848Y658160D01*
Y657776D01*
X229003Y657431D01*
X229313Y657201D01*
X229674Y657125D01*
X230036Y657201D01*
X230294Y657393D01*
X230449Y657700D01*
X230501Y657968D01*
G01Y661528D02*
X227401D01*
X229623Y660110D01*
Y662026D01*
G01X229209Y663440D02*
X228848Y663708D01*
X228641Y663938D01*
X228538Y664245D01*
X228641Y664513D01*
X228848Y664705D01*
X229158Y664858D01*
X229519Y664896D01*
X229829Y664858D01*
X230139Y664705D01*
X230398Y664475D01*
X230501Y664206D01*
X230398Y663900D01*
X230088Y663631D01*
X229623Y663478D01*
X229106Y663440D01*
X228434Y663516D01*
X228073Y663631D01*
X227711Y663823D01*
X227453Y664091D01*
X227401Y664360D01*
X227504Y664628D01*
X227763Y664820D01*
G01X228084Y647774D02*
X231084D01*
G01X227984Y650874D02*
X231184D01*
G01X227984Y644674D02*
Y650874D01*
G01X231184Y644674D02*
X227984D01*
G01X231184Y650874D02*
Y644674D01*
G01X239356Y654101D02*
X236256D01*
Y655060D01*
X236411Y655366D01*
X236618Y655558D01*
X237031Y655635D01*
X237444Y655558D01*
X237703Y655328D01*
X237858Y655060D01*
Y654101D01*
G01Y655060D02*
X239356Y655635D01*
G01Y657968D02*
X236256D01*
X236876Y657508D01*
G01X239356D02*
Y658428D01*
G01X236773Y660340D02*
X236463Y660570D01*
X236308Y660838D01*
X236256Y661145D01*
X236359Y661528D01*
X236618Y661796D01*
X236928Y661873D01*
X237238Y661835D01*
X237496Y661681D01*
X238013Y660915D01*
X238374Y660570D01*
X238891Y660340D01*
X239356Y660263D01*
Y661873D01*
G01X238736Y663325D02*
X239098Y663555D01*
X239304Y663861D01*
X239356Y664206D01*
X239304Y664513D01*
X239046Y664820D01*
X238736Y665011D01*
X238426Y665050D01*
X238064Y664973D01*
X237806Y664705D01*
X237703Y664436D01*
Y664091D01*
G01Y664436D02*
X237548Y664666D01*
X237289Y664858D01*
X236979Y664935D01*
X236669Y664858D01*
X236411Y664666D01*
X236256Y664321D01*
X236308Y663976D01*
X236514Y663631D01*
G01X238064Y666540D02*
X237703Y666808D01*
X237496Y667038D01*
X237393Y667345D01*
X237496Y667613D01*
X237703Y667805D01*
X238013Y667958D01*
X238374Y667996D01*
X238684Y667958D01*
X238994Y667805D01*
X239253Y667575D01*
X239356Y667306D01*
X239253Y667000D01*
X238943Y666731D01*
X238478Y666578D01*
X237961Y666540D01*
X237289Y666616D01*
X236928Y666731D01*
X236566Y666923D01*
X236308Y667191D01*
X236256Y667460D01*
X236359Y667728D01*
X236618Y667920D01*
G01X239051Y644674D02*
X235851D01*
G01X239051Y650874D02*
Y644674D01*
G01X235851Y650874D02*
X239051D01*
G01X235851Y644674D02*
Y650874D01*
G01X243871Y654101D02*
X240771D01*
Y655060D01*
X240926Y655366D01*
X241133Y655558D01*
X241546Y655635D01*
X241959Y655558D01*
X242218Y655328D01*
X242373Y655060D01*
Y654101D01*
G01Y655060D02*
X243871Y655635D01*
G01Y657968D02*
X240771D01*
X241391Y657508D01*
G01X243871D02*
Y658428D01*
G01Y661068D02*
X240771D01*
X241391Y660608D01*
G01X243871D02*
Y661528D01*
G01X240771Y664168D02*
X240874Y663861D01*
X241133Y663631D01*
X241443Y663478D01*
X241856Y663363D01*
X242321Y663325D01*
X242786Y663363D01*
X243199Y663478D01*
X243509Y663631D01*
X243768Y663861D01*
X243871Y664168D01*
X243768Y664475D01*
X243509Y664705D01*
X243199Y664858D01*
X242786Y664973D01*
X242321Y665011D01*
X241856Y664973D01*
X241443Y664858D01*
X241133Y664705D01*
X240874Y664475D01*
X240771Y664168D01*
G01X243509Y666616D02*
X243768Y666885D01*
X243871Y667191D01*
X243768Y667498D01*
X243458Y667766D01*
X242993Y667958D01*
X242528Y668035D01*
X241959D01*
X241494Y667958D01*
X241081Y667766D01*
X240874Y667536D01*
X240771Y667268D01*
X240874Y666961D01*
X241081Y666731D01*
X241391Y666578D01*
X241804Y666501D01*
X242166Y666578D01*
X242528Y666770D01*
X242734Y667000D01*
X242786Y667268D01*
X242683Y667575D01*
X242424Y667805D01*
X241959Y668035D01*
G01X240070Y644578D02*
Y650778D01*
G01X243270Y644578D02*
X240070D01*
G01Y650778D02*
X243270D01*
G01X234721Y654101D02*
X231621D01*
Y655060D01*
X231776Y655366D01*
X231983Y655558D01*
X232396Y655635D01*
X232809Y655558D01*
X233068Y655328D01*
X233223Y655060D01*
Y654101D01*
G01Y655060D02*
X234721Y655635D01*
G01Y657968D02*
X231621D01*
X232241Y657508D01*
G01X234721D02*
Y658428D01*
G01Y661068D02*
X231621D01*
X232241Y660608D01*
G01X234721D02*
Y661528D01*
G01X231621Y664168D02*
X231724Y663861D01*
X231983Y663631D01*
X232293Y663478D01*
X232706Y663363D01*
X233171Y663325D01*
X233636Y663363D01*
X234049Y663478D01*
X234359Y663631D01*
X234618Y663861D01*
X234721Y664168D01*
X234618Y664475D01*
X234359Y664705D01*
X234049Y664858D01*
X233636Y664973D01*
X233171Y665011D01*
X232706Y664973D01*
X232293Y664858D01*
X231983Y664705D01*
X231724Y664475D01*
X231621Y664168D01*
G01X234721Y667268D02*
X234669Y667536D01*
X234514Y667843D01*
X234256Y668035D01*
X233894Y668111D01*
X233533Y668035D01*
X233223Y667805D01*
X233068Y667460D01*
Y667076D01*
X232964Y666846D01*
X232706Y666655D01*
X232344Y666578D01*
X231983Y666693D01*
X231724Y666961D01*
X231621Y667268D01*
X231724Y667575D01*
X231983Y667843D01*
X232344Y667958D01*
X232706Y667881D01*
X232964Y667690D01*
X233068Y667460D01*
Y667076D01*
X233223Y666731D01*
X233533Y666501D01*
X233894Y666425D01*
X234256Y666501D01*
X234514Y666693D01*
X234669Y667000D01*
X234721Y667268D01*
G01X231984Y650874D02*
X235184D01*
G01X231984Y644674D02*
Y650874D01*
G01X235184Y644674D02*
X231984D01*
G01X235184Y650874D02*
Y644674D01*
G01X234592Y670172D02*
Y673172D01*
G01X231492Y670072D02*
Y673272D01*
G01X237692Y670072D02*
X231492D01*
G01X237692Y673272D02*
Y670072D01*
G01X231492Y673272D02*
X237692D01*
G01X238183Y672219D02*
X238343Y672011D01*
X238530Y671886D01*
X238770Y671844D01*
X239010Y671927D01*
X239197Y672094D01*
X239330Y672386D01*
X239357Y672719D01*
X239303Y673052D01*
X239170Y673261D01*
X238983Y673427D01*
X238797Y673469D01*
X238610Y673427D01*
X238370Y673261D01*
X238450Y674344D01*
X239170D01*
G01X228680Y672034D02*
Y674534D01*
X227693Y672742D01*
X229027D01*
G01X236835Y691179D02*
Y675179D01*
G01X242499Y672062D02*
Y674562D01*
X241512Y672770D01*
X242846D01*
G01X238131Y675179D02*
Y691179D01*
G01X250335Y675179D02*
X238131D01*
G01X236122Y691984D02*
Y694484D01*
X235802Y693984D01*
G01Y691984D02*
X236442D01*
G01X238328Y692521D02*
X238488Y692229D01*
X238702Y692063D01*
X238942Y692021D01*
X239155Y692063D01*
X239368Y692271D01*
X239502Y692521D01*
X239528Y692771D01*
X239475Y693063D01*
X239288Y693271D01*
X239102Y693354D01*
X238862D01*
G01X239102D02*
X239262Y693479D01*
X239395Y693688D01*
X239448Y693938D01*
X239395Y694188D01*
X239262Y694396D01*
X239022Y694521D01*
X238782Y694479D01*
X238542Y694313D01*
G01X238131Y691179D02*
X250335D01*
G01X229802Y693181D02*
Y695681D01*
X230336D01*
X230549Y695556D01*
X230709Y695389D01*
X230842Y695139D01*
X230949Y694848D01*
X230976Y694431D01*
X230949Y694014D01*
X230842Y693723D01*
X230709Y693473D01*
X230549Y693306D01*
X230336Y693181D01*
X229802D01*
G01X236440Y711456D02*
Y696456D01*
G01X237940D02*
Y711456D01*
G01X250940Y696456D02*
X237940D01*
G01X235598Y713873D02*
X236131D01*
Y713123D01*
X235971Y712873D01*
X235785Y712706D01*
X235518Y712623D01*
X235251Y712706D01*
X235065Y712873D01*
X234905Y713123D01*
X234798Y713415D01*
X234745Y713748D01*
Y714040D01*
X234798Y714290D01*
X234905Y714581D01*
X235065Y714831D01*
X235225Y714998D01*
X235438Y715123D01*
X235625D01*
X235838Y715040D01*
X235998Y714873D01*
G01X240878Y712956D02*
X241091Y712748D01*
X241331Y712623D01*
X241545D01*
X241758Y712748D01*
X241918Y712956D01*
X241998Y713248D01*
X241945Y713540D01*
X241811Y713790D01*
X241571Y713956D01*
X241251Y714040D01*
X241065Y714206D01*
X240985Y714498D01*
X241038Y714790D01*
X241171Y714998D01*
X241358Y715123D01*
X241545D01*
X241731Y715040D01*
X241891Y714831D01*
G01X237940Y711456D02*
X250940D01*
G01X227540Y732256D02*
Y726056D01*
G01X236440Y729156D02*
X233440D01*
G01X236540Y726056D02*
X233340D01*
G01X236540Y732256D02*
Y726056D01*
G01X233340Y732256D02*
X236540D01*
G01X233340Y726056D02*
Y732256D01*
G01X241040Y737556D02*
X237840D01*
G01X241040Y743756D02*
Y737556D01*
G01X237840D02*
Y743756D01*
G01X232040Y737556D02*
X228840D01*
G01D02*
Y743756D01*
G01X232040D02*
Y737556D01*
G01X245440Y729156D02*
X242440D01*
G01X245540Y726056D02*
X242340D01*
G01Y732256D02*
X245540D01*
G01X242340Y726056D02*
Y732256D01*
G01X227540Y743756D02*
Y737556D01*
G01X237840Y732256D02*
X241040D01*
G01X237840Y726056D02*
Y732256D01*
G01X241040Y726056D02*
X237840D01*
G01X241040Y732256D02*
Y726056D01*
G01X233340Y737556D02*
Y743756D01*
G01X236540Y737556D02*
X233340D01*
G01X236540Y743756D02*
Y737556D01*
G01X228840Y732256D02*
X232040D01*
G01X228840Y726056D02*
Y732256D01*
G01X232040Y726056D02*
X228840D01*
G01X232040Y732256D02*
Y726056D01*
G01X242340Y737556D02*
Y743756D01*
G01X245540Y737556D02*
X242340D01*
G01X232046Y746921D02*
X231891Y746691D01*
X231788Y746423D01*
Y746116D01*
X231943Y745771D01*
X232201Y745503D01*
X232511Y745311D01*
X233028Y745158D01*
X233493Y745120D01*
X233958Y745196D01*
X234268Y745311D01*
X234578Y745541D01*
X234785Y745810D01*
X234888Y746078D01*
Y746346D01*
X234785Y746615D01*
X234630Y746845D01*
X234423Y747036D01*
G01X234888Y749101D02*
X234216Y749178D01*
X233648Y749293D01*
X233131Y749446D01*
X232563Y749638D01*
X231788Y749945D01*
Y748411D01*
G01Y752278D02*
X231891Y751971D01*
X232150Y751741D01*
X232460Y751588D01*
X232873Y751473D01*
X233338Y751435D01*
X233803Y751473D01*
X234216Y751588D01*
X234526Y751741D01*
X234785Y751971D01*
X234888Y752278D01*
X234785Y752585D01*
X234526Y752815D01*
X234216Y752968D01*
X233803Y753083D01*
X233338Y753121D01*
X232873Y753083D01*
X232460Y752968D01*
X232150Y752815D01*
X231891Y752585D01*
X231788Y752278D01*
G01X233596Y754650D02*
X233235Y754918D01*
X233028Y755148D01*
X232925Y755455D01*
X233028Y755723D01*
X233235Y755915D01*
X233545Y756068D01*
X233906Y756106D01*
X234216Y756068D01*
X234526Y755915D01*
X234785Y755685D01*
X234888Y755416D01*
X234785Y755110D01*
X234475Y754841D01*
X234010Y754688D01*
X233493Y754650D01*
X232821Y754726D01*
X232460Y754841D01*
X232098Y755033D01*
X231840Y755301D01*
X231788Y755570D01*
X231891Y755838D01*
X232150Y756030D01*
G01X240940Y740656D02*
X237940D01*
G01X237840Y743756D02*
X241040D01*
G01X231940Y740656D02*
X228940D01*
G01X228840Y743756D02*
X232040D01*
G01X240126Y746921D02*
X239971Y746691D01*
X239868Y746423D01*
Y746116D01*
X240023Y745771D01*
X240281Y745503D01*
X240591Y745311D01*
X241108Y745158D01*
X241573Y745120D01*
X242038Y745196D01*
X242348Y745311D01*
X242658Y745541D01*
X242865Y745810D01*
X242968Y746078D01*
Y746346D01*
X242865Y746615D01*
X242710Y746845D01*
X242503Y747036D01*
G01X242968Y749101D02*
X242296Y749178D01*
X241728Y749293D01*
X241211Y749446D01*
X240643Y749638D01*
X239868Y749945D01*
Y748411D01*
G01Y752278D02*
X239971Y751971D01*
X240230Y751741D01*
X240540Y751588D01*
X240953Y751473D01*
X241418Y751435D01*
X241883Y751473D01*
X242296Y751588D01*
X242606Y751741D01*
X242865Y751971D01*
X242968Y752278D01*
X242865Y752585D01*
X242606Y752815D01*
X242296Y752968D01*
X241883Y753083D01*
X241418Y753121D01*
X240953Y753083D01*
X240540Y752968D01*
X240230Y752815D01*
X239971Y752585D01*
X239868Y752278D01*
G01Y755378D02*
X239971Y755071D01*
X240230Y754841D01*
X240540Y754688D01*
X240953Y754573D01*
X241418Y754535D01*
X241883Y754573D01*
X242296Y754688D01*
X242606Y754841D01*
X242865Y755071D01*
X242968Y755378D01*
X242865Y755685D01*
X242606Y755915D01*
X242296Y756068D01*
X241883Y756183D01*
X241418Y756221D01*
X240953Y756183D01*
X240540Y756068D01*
X240230Y755915D01*
X239971Y755685D01*
X239868Y755378D01*
G01X238968Y745311D02*
X235868D01*
Y746270D01*
X236023Y746576D01*
X236230Y746768D01*
X236643Y746845D01*
X237056Y746768D01*
X237315Y746538D01*
X237470Y746270D01*
Y745311D01*
G01Y746270D02*
X238968Y746845D01*
G01X238606Y748526D02*
X238865Y748795D01*
X238968Y749101D01*
X238865Y749408D01*
X238555Y749676D01*
X238090Y749868D01*
X237625Y749945D01*
X237056D01*
X236591Y749868D01*
X236178Y749676D01*
X235971Y749446D01*
X235868Y749178D01*
X235971Y748871D01*
X236178Y748641D01*
X236488Y748488D01*
X236901Y748411D01*
X237263Y748488D01*
X237625Y748680D01*
X237831Y748910D01*
X237883Y749178D01*
X237780Y749485D01*
X237521Y749715D01*
X237056Y749945D01*
G01X238968Y752738D02*
X235868D01*
X238090Y751320D01*
Y753236D01*
G01X235868Y755378D02*
X235971Y755071D01*
X236230Y754841D01*
X236540Y754688D01*
X236953Y754573D01*
X237418Y754535D01*
X237883Y754573D01*
X238296Y754688D01*
X238606Y754841D01*
X238865Y755071D01*
X238968Y755378D01*
X238865Y755685D01*
X238606Y755915D01*
X238296Y756068D01*
X237883Y756183D01*
X237418Y756221D01*
X236953Y756183D01*
X236540Y756068D01*
X236230Y755915D01*
X235971Y755685D01*
X235868Y755378D01*
G01X233340Y743756D02*
X236540D01*
G01X230728Y745311D02*
X227628D01*
Y746270D01*
X227783Y746576D01*
X227990Y746768D01*
X228403Y746845D01*
X228816Y746768D01*
X229075Y746538D01*
X229230Y746270D01*
Y745311D01*
G01Y746270D02*
X230728Y746845D01*
G01X230366Y748526D02*
X230625Y748795D01*
X230728Y749101D01*
X230625Y749408D01*
X230315Y749676D01*
X229850Y749868D01*
X229385Y749945D01*
X228816D01*
X228351Y749868D01*
X227938Y749676D01*
X227731Y749446D01*
X227628Y749178D01*
X227731Y748871D01*
X227938Y748641D01*
X228248Y748488D01*
X228661Y748411D01*
X229023Y748488D01*
X229385Y748680D01*
X229591Y748910D01*
X229643Y749178D01*
X229540Y749485D01*
X229281Y749715D01*
X228816Y749945D01*
G01X230728Y752738D02*
X227628D01*
X229850Y751320D01*
Y753236D01*
G01X229436Y754650D02*
X229075Y754918D01*
X228868Y755148D01*
X228765Y755455D01*
X228868Y755723D01*
X229075Y755915D01*
X229385Y756068D01*
X229746Y756106D01*
X230056Y756068D01*
X230366Y755915D01*
X230625Y755685D01*
X230728Y755416D01*
X230625Y755110D01*
X230315Y754841D01*
X229850Y754688D01*
X229333Y754650D01*
X228661Y754726D01*
X228300Y754841D01*
X227938Y755033D01*
X227680Y755301D01*
X227628Y755570D01*
X227731Y755838D01*
X227990Y756030D01*
G01X242340Y743756D02*
X245540D01*
G01X238916Y760558D02*
X238761Y760328D01*
X238658Y760060D01*
Y759753D01*
X238813Y759408D01*
X239071Y759140D01*
X239381Y758948D01*
X239898Y758795D01*
X240363Y758757D01*
X240828Y758833D01*
X241138Y758948D01*
X241448Y759178D01*
X241655Y759447D01*
X241758Y759715D01*
Y759983D01*
X241655Y760252D01*
X241500Y760482D01*
X241293Y760673D01*
G01X241758Y762738D02*
X241086Y762815D01*
X240518Y762930D01*
X240001Y763083D01*
X239433Y763275D01*
X238658Y763582D01*
Y762048D01*
G01Y765915D02*
X238761Y765608D01*
X239020Y765378D01*
X239330Y765225D01*
X239743Y765110D01*
X240208Y765072D01*
X240673Y765110D01*
X241086Y765225D01*
X241396Y765378D01*
X241655Y765608D01*
X241758Y765915D01*
X241655Y766222D01*
X241396Y766452D01*
X241086Y766605D01*
X240673Y766720D01*
X240208Y766758D01*
X239743Y766720D01*
X239330Y766605D01*
X239020Y766452D01*
X238761Y766222D01*
X238658Y765915D01*
G01X241138Y768172D02*
X241500Y768402D01*
X241706Y768708D01*
X241758Y769053D01*
X241706Y769360D01*
X241448Y769667D01*
X241138Y769858D01*
X240828Y769897D01*
X240466Y769820D01*
X240208Y769552D01*
X240105Y769283D01*
Y768938D01*
G01Y769283D02*
X239950Y769513D01*
X239691Y769705D01*
X239381Y769782D01*
X239071Y769705D01*
X238813Y769513D01*
X238658Y769168D01*
X238710Y768823D01*
X238916Y768478D01*
G01X230356Y760558D02*
X230201Y760328D01*
X230098Y760060D01*
Y759753D01*
X230253Y759408D01*
X230511Y759140D01*
X230821Y758948D01*
X231338Y758795D01*
X231803Y758757D01*
X232268Y758833D01*
X232578Y758948D01*
X232888Y759178D01*
X233095Y759447D01*
X233198Y759715D01*
Y759983D01*
X233095Y760252D01*
X232940Y760482D01*
X232733Y760673D01*
G01X233198Y762738D02*
X232526Y762815D01*
X231958Y762930D01*
X231441Y763083D01*
X230873Y763275D01*
X230098Y763582D01*
Y762048D01*
G01Y765915D02*
X230201Y765608D01*
X230460Y765378D01*
X230770Y765225D01*
X231183Y765110D01*
X231648Y765072D01*
X232113Y765110D01*
X232526Y765225D01*
X232836Y765378D01*
X233095Y765608D01*
X233198Y765915D01*
X233095Y766222D01*
X232836Y766452D01*
X232526Y766605D01*
X232113Y766720D01*
X231648Y766758D01*
X231183Y766720D01*
X230770Y766605D01*
X230460Y766452D01*
X230201Y766222D01*
X230098Y765915D01*
G01X232836Y768363D02*
X233095Y768632D01*
X233198Y768938D01*
X233095Y769245D01*
X232785Y769513D01*
X232320Y769705D01*
X231855Y769782D01*
X231286D01*
X230821Y769705D01*
X230408Y769513D01*
X230201Y769283D01*
X230098Y769015D01*
X230201Y768708D01*
X230408Y768478D01*
X230718Y768325D01*
X231131Y768248D01*
X231493Y768325D01*
X231855Y768517D01*
X232061Y768747D01*
X232113Y769015D01*
X232010Y769322D01*
X231751Y769552D01*
X231286Y769782D01*
G01X237508Y758948D02*
X234408D01*
Y759907D01*
X234563Y760213D01*
X234770Y760405D01*
X235183Y760482D01*
X235596Y760405D01*
X235855Y760175D01*
X236010Y759907D01*
Y758948D01*
G01Y759907D02*
X237508Y760482D01*
G01X237146Y762163D02*
X237405Y762432D01*
X237508Y762738D01*
X237405Y763045D01*
X237095Y763313D01*
X236630Y763505D01*
X236165Y763582D01*
X235596D01*
X235131Y763505D01*
X234718Y763313D01*
X234511Y763083D01*
X234408Y762815D01*
X234511Y762508D01*
X234718Y762278D01*
X235028Y762125D01*
X235441Y762048D01*
X235803Y762125D01*
X236165Y762317D01*
X236371Y762547D01*
X236423Y762815D01*
X236320Y763122D01*
X236061Y763352D01*
X235596Y763582D01*
G01X237508Y766375D02*
X234408D01*
X236630Y764957D01*
Y766873D01*
G01X236888Y768172D02*
X237250Y768402D01*
X237456Y768708D01*
X237508Y769053D01*
X237456Y769360D01*
X237198Y769667D01*
X236888Y769858D01*
X236578Y769897D01*
X236216Y769820D01*
X235958Y769552D01*
X235855Y769283D01*
Y768938D01*
G01Y769283D02*
X235700Y769513D01*
X235441Y769705D01*
X235131Y769782D01*
X234821Y769705D01*
X234563Y769513D01*
X234408Y769168D01*
X234460Y768823D01*
X234666Y768478D01*
G01X245758Y758948D02*
X242658D01*
Y759907D01*
X242813Y760213D01*
X243020Y760405D01*
X243433Y760482D01*
X243846Y760405D01*
X244105Y760175D01*
X244260Y759907D01*
Y758948D01*
G01Y759907D02*
X245758Y760482D01*
G01X245396Y762163D02*
X245655Y762432D01*
X245758Y762738D01*
X245655Y763045D01*
X245345Y763313D01*
X244880Y763505D01*
X244415Y763582D01*
X243846D01*
X243381Y763505D01*
X242968Y763313D01*
X242761Y763083D01*
X242658Y762815D01*
X242761Y762508D01*
X242968Y762278D01*
X243278Y762125D01*
X243691Y762048D01*
X244053Y762125D01*
X244415Y762317D01*
X244621Y762547D01*
X244673Y762815D01*
X244570Y763122D01*
X244311Y763352D01*
X243846Y763582D01*
G01X245138Y765072D02*
X245500Y765302D01*
X245706Y765608D01*
X245758Y765953D01*
X245706Y766260D01*
X245448Y766567D01*
X245138Y766758D01*
X244828Y766797D01*
X244466Y766720D01*
X244208Y766452D01*
X244105Y766183D01*
Y765838D01*
G01Y766183D02*
X243950Y766413D01*
X243691Y766605D01*
X243381Y766682D01*
X243071Y766605D01*
X242813Y766413D01*
X242658Y766068D01*
X242710Y765723D01*
X242916Y765378D01*
G01X245758Y768938D02*
X245086Y769015D01*
X244518Y769130D01*
X244001Y769283D01*
X243433Y769475D01*
X242658Y769782D01*
Y768248D01*
G01X254793Y-236364D02*
X257193D01*
G01X255993D02*
Y-244364D01*
G01X254793D02*
X257193D01*
G01X262593D02*
Y-239031D01*
G01Y-240097D02*
X263093Y-239564D01*
X263593Y-239164D01*
X264293Y-239031D01*
X264793Y-239164D01*
X265393Y-239564D01*
G01X270493Y-240764D02*
X273693D01*
X273393Y-239831D01*
X272893Y-239297D01*
X272193Y-239031D01*
X271493Y-239164D01*
X270893Y-239564D01*
X270493Y-240497D01*
X270293Y-241298D01*
Y-242097D01*
X270493Y-242897D01*
X270993Y-243697D01*
X271593Y-244231D01*
X272293Y-244364D01*
X272993Y-244097D01*
X273693Y-243298D01*
G01X278293Y-244364D02*
Y-239031D01*
G01Y-240364D02*
X278693Y-239697D01*
X279293Y-239164D01*
X280093Y-239031D01*
X280793Y-239164D01*
X281393Y-239697D01*
X281693Y-240631D01*
Y-244364D01*
G01X286493Y-240764D02*
X289693D01*
X289393Y-239831D01*
X288893Y-239297D01*
X288193Y-239031D01*
X287493Y-239164D01*
X286893Y-239564D01*
X286493Y-240497D01*
X286293Y-241298D01*
Y-242097D01*
X286493Y-242897D01*
X286993Y-243697D01*
X287593Y-244231D01*
X288293Y-244364D01*
X288993Y-244097D01*
X289693Y-243298D01*
G01X243893Y-218298D02*
X244693Y-218964D01*
X245593Y-219364D01*
X246393D01*
X247193Y-218964D01*
X247793Y-218298D01*
X248093Y-217364D01*
X247893Y-216431D01*
X247393Y-215631D01*
X246493Y-215097D01*
X245293Y-214831D01*
X244593Y-214297D01*
X244293Y-213364D01*
X244493Y-212431D01*
X244993Y-211764D01*
X245693Y-211364D01*
X246393D01*
X247093Y-211631D01*
X247693Y-212297D01*
G01X252793Y-211364D02*
X255193D01*
G01X253993D02*
Y-219364D01*
G01X252793D02*
X255193D01*
G01X259993Y-211364D02*
Y-219364D01*
X263993D01*
G01X267793D02*
Y-211364D01*
G01X271593D02*
X267793Y-216298D01*
G01X272193Y-219364D02*
X269493Y-214031D01*
G01X276693Y-216697D02*
X279293D01*
G01X285993Y-211364D02*
Y-219364D01*
G01X283693Y-211364D02*
X288293D01*
G01X293993Y-219364D02*
X293193Y-219231D01*
X292493Y-218697D01*
X291893Y-217897D01*
X291493Y-216964D01*
X291293Y-215897D01*
Y-214831D01*
X291493Y-213764D01*
X291893Y-212831D01*
X292493Y-212031D01*
X293193Y-211497D01*
X293993Y-211364D01*
X294793Y-211497D01*
X295493Y-212031D01*
X296093Y-212831D01*
X296493Y-213764D01*
X296693Y-214831D01*
Y-215897D01*
X296493Y-216964D01*
X296093Y-217897D01*
X295493Y-218697D01*
X294793Y-219231D01*
X293993Y-219364D01*
G01X299993D02*
Y-211364D01*
X302393D01*
X303193Y-211764D01*
X303793Y-212697D01*
X303993Y-213764D01*
X303793Y-214831D01*
X303293Y-215631D01*
X302393Y-216031D01*
X299993D01*
G01X257926Y13759D02*
X254826D01*
Y14679D01*
X254981Y14986D01*
X255343Y15216D01*
X255756Y15293D01*
X256169Y15216D01*
X256479Y15024D01*
X256634Y14679D01*
Y13759D01*
G01X255084Y18469D02*
X254929Y18239D01*
X254826Y17971D01*
Y17664D01*
X254981Y17319D01*
X255239Y17051D01*
X255549Y16859D01*
X256066Y16706D01*
X256531Y16668D01*
X256996Y16744D01*
X257306Y16859D01*
X257616Y17089D01*
X257823Y17358D01*
X257926Y17626D01*
Y17894D01*
X257823Y18163D01*
X257668Y18393D01*
X257461Y18584D01*
G01Y19883D02*
X257719Y20113D01*
X257874Y20381D01*
X257926Y20726D01*
X257823Y21071D01*
X257616Y21339D01*
X257254Y21531D01*
X256841Y21569D01*
X256428Y21493D01*
X256169Y21301D01*
X255963Y21033D01*
X255911Y20764D01*
X255963Y20496D01*
X256169Y20151D01*
X254826Y20266D01*
Y21301D01*
G01X255343Y23098D02*
X255033Y23328D01*
X254878Y23596D01*
X254826Y23903D01*
X254929Y24286D01*
X255188Y24554D01*
X255498Y24631D01*
X255808Y24593D01*
X256066Y24439D01*
X256583Y23673D01*
X256944Y23328D01*
X257461Y23098D01*
X257926Y23021D01*
Y24631D01*
G01X254005Y44331D02*
Y8635D01*
G01X257520Y1154D02*
X254420D01*
Y2074D01*
X254575Y2381D01*
X254937Y2611D01*
X255350Y2688D01*
X255763Y2611D01*
X256073Y2419D01*
X256228Y2074D01*
Y1154D01*
G01X257520Y4254D02*
X254420D01*
Y5213D01*
X254575Y5519D01*
X254782Y5711D01*
X255195Y5788D01*
X255608Y5711D01*
X255867Y5481D01*
X256022Y5213D01*
Y4254D01*
G01Y5213D02*
X257520Y5788D01*
G01Y8121D02*
X254420D01*
X255040Y7661D01*
G01X257520D02*
Y8581D01*
G01Y11221D02*
X257468Y11489D01*
X257313Y11796D01*
X257055Y11988D01*
X256693Y12064D01*
X256332Y11988D01*
X256022Y11758D01*
X255867Y11413D01*
Y11029D01*
X255763Y10799D01*
X255505Y10608D01*
X255143Y10531D01*
X254782Y10646D01*
X254523Y10914D01*
X254420Y11221D01*
X254523Y11528D01*
X254782Y11796D01*
X255143Y11911D01*
X255505Y11834D01*
X255763Y11643D01*
X255867Y11413D01*
Y11029D01*
X256022Y10684D01*
X256332Y10454D01*
X256693Y10378D01*
X257055Y10454D01*
X257313Y10646D01*
X257468Y10953D01*
X257520Y11221D01*
G01X261520Y1154D02*
X258420D01*
Y2074D01*
X258575Y2381D01*
X258937Y2611D01*
X259350Y2688D01*
X259763Y2611D01*
X260073Y2419D01*
X260228Y2074D01*
Y1154D01*
G01X261520Y4254D02*
X258420D01*
Y5213D01*
X258575Y5519D01*
X258782Y5711D01*
X259195Y5788D01*
X259608Y5711D01*
X259867Y5481D01*
X260022Y5213D01*
Y4254D01*
G01Y5213D02*
X261520Y5788D01*
G01Y8121D02*
X258420D01*
X259040Y7661D01*
G01X261520D02*
Y8581D01*
G01X261158Y10569D02*
X261417Y10838D01*
X261520Y11144D01*
X261417Y11451D01*
X261107Y11719D01*
X260642Y11911D01*
X260177Y11988D01*
X259608D01*
X259143Y11911D01*
X258730Y11719D01*
X258523Y11489D01*
X258420Y11221D01*
X258523Y10914D01*
X258730Y10684D01*
X259040Y10531D01*
X259453Y10454D01*
X259815Y10531D01*
X260177Y10723D01*
X260383Y10953D01*
X260435Y11221D01*
X260332Y11528D01*
X260073Y11758D01*
X259608Y11988D01*
G01X258585Y23332D02*
Y26532D01*
G01X264785Y23332D02*
X258585D01*
G01Y26532D02*
X264785D01*
G01X264348Y27629D02*
X258148D01*
G01D02*
Y30829D01*
G01X256451Y40473D02*
Y43573D01*
X257371D01*
X257678Y43418D01*
X257908Y43056D01*
X257985Y42643D01*
X257908Y42230D01*
X257716Y41920D01*
X257371Y41765D01*
X256451D01*
G01X261161Y43315D02*
X260931Y43470D01*
X260663Y43573D01*
X260356D01*
X260011Y43418D01*
X259743Y43160D01*
X259551Y42850D01*
X259398Y42333D01*
X259360Y41868D01*
X259436Y41403D01*
X259551Y41093D01*
X259781Y40783D01*
X260050Y40576D01*
X260318Y40473D01*
X260586D01*
X260855Y40576D01*
X261085Y40731D01*
X261276Y40938D01*
G01X262575D02*
X262805Y40680D01*
X263073Y40525D01*
X263418Y40473D01*
X263763Y40576D01*
X264031Y40783D01*
X264223Y41145D01*
X264261Y41558D01*
X264185Y41971D01*
X263993Y42230D01*
X263725Y42436D01*
X263456Y42488D01*
X263188Y42436D01*
X262843Y42230D01*
X262958Y43573D01*
X263993D01*
G01X266518Y40473D02*
Y43573D01*
X266058Y42953D01*
G01Y40473D02*
X266978D01*
G01X256451Y44709D02*
Y47809D01*
X257371D01*
X257678Y47654D01*
X257908Y47292D01*
X257985Y46879D01*
X257908Y46466D01*
X257716Y46156D01*
X257371Y46001D01*
X256451D01*
G01X259551Y44709D02*
Y47809D01*
X260510D01*
X260816Y47654D01*
X261008Y47447D01*
X261085Y47034D01*
X261008Y46621D01*
X260778Y46362D01*
X260510Y46207D01*
X259551D01*
G01X260510D02*
X261085Y44709D01*
G01X262690Y47292D02*
X262920Y47602D01*
X263188Y47757D01*
X263495Y47809D01*
X263878Y47706D01*
X264146Y47447D01*
X264223Y47137D01*
X264185Y46827D01*
X264031Y46569D01*
X263265Y46052D01*
X262920Y45691D01*
X262690Y45174D01*
X262613Y44709D01*
X264223D01*
G01X266518D02*
Y47809D01*
X266058Y47189D01*
G01Y44709D02*
X266978D01*
G01X258148Y30829D02*
X264348D01*
G01X255111Y61733D02*
Y55533D01*
G01D02*
X251911D01*
G01D02*
Y61733D01*
G01X252011Y58633D02*
X255011D01*
G01X256451Y48953D02*
Y52053D01*
X257371D01*
X257678Y51898D01*
X257908Y51536D01*
X257985Y51123D01*
X257908Y50710D01*
X257716Y50400D01*
X257371Y50245D01*
X256451D01*
G01X261161Y51795D02*
X260931Y51950D01*
X260663Y52053D01*
X260356D01*
X260011Y51898D01*
X259743Y51640D01*
X259551Y51330D01*
X259398Y50813D01*
X259360Y50348D01*
X259436Y49883D01*
X259551Y49573D01*
X259781Y49263D01*
X260050Y49056D01*
X260318Y48953D01*
X260586D01*
X260855Y49056D01*
X261085Y49211D01*
X261276Y49418D01*
G01X262575D02*
X262805Y49160D01*
X263073Y49005D01*
X263418Y48953D01*
X263763Y49056D01*
X264031Y49263D01*
X264223Y49625D01*
X264261Y50038D01*
X264185Y50451D01*
X263993Y50710D01*
X263725Y50916D01*
X263456Y50968D01*
X263188Y50916D01*
X262843Y50710D01*
X262958Y52053D01*
X263993D01*
G01X265675Y49573D02*
X265905Y49211D01*
X266211Y49005D01*
X266556Y48953D01*
X266863Y49005D01*
X267170Y49263D01*
X267361Y49573D01*
X267400Y49883D01*
X267323Y50245D01*
X267055Y50503D01*
X266786Y50606D01*
X266441D01*
G01X266786D02*
X267016Y50761D01*
X267208Y51020D01*
X267285Y51330D01*
X267208Y51640D01*
X267016Y51898D01*
X266671Y52053D01*
X266326Y52001D01*
X265981Y51795D01*
G01X258485Y63159D02*
X258330Y62929D01*
X258227Y62661D01*
Y62354D01*
X258382Y62009D01*
X258640Y61741D01*
X258950Y61549D01*
X259467Y61396D01*
X259932Y61358D01*
X260397Y61434D01*
X260707Y61549D01*
X261017Y61779D01*
X261224Y62048D01*
X261327Y62316D01*
Y62584D01*
X261224Y62853D01*
X261069Y63083D01*
X260862Y63274D01*
G01X261327Y65416D02*
X258227D01*
X258847Y64956D01*
G01X261327D02*
Y65876D01*
G01X260035Y67788D02*
X259674Y68056D01*
X259467Y68286D01*
X259364Y68593D01*
X259467Y68861D01*
X259674Y69053D01*
X259984Y69206D01*
X260345Y69244D01*
X260655Y69206D01*
X260965Y69053D01*
X261224Y68823D01*
X261327Y68554D01*
X261224Y68248D01*
X260914Y67979D01*
X260449Y67826D01*
X259932Y67788D01*
X259260Y67864D01*
X258899Y67979D01*
X258537Y68171D01*
X258279Y68439D01*
X258227Y68708D01*
X258330Y68976D01*
X258589Y69168D01*
G01X261327Y72076D02*
X258227D01*
X260449Y70658D01*
Y72574D01*
G01X243914Y51201D02*
Y66201D01*
G01X250714D02*
Y51201D01*
G01D02*
X243914D01*
G01X244014Y58701D02*
X250614D01*
G01X253301Y49384D02*
Y51264D01*
G01X251936Y50246D02*
X254666D01*
G01X256451Y53359D02*
Y56459D01*
X257371D01*
X257678Y56304D01*
X257908Y55942D01*
X257985Y55529D01*
X257908Y55116D01*
X257716Y54806D01*
X257371Y54651D01*
X256451D01*
G01X259551Y53359D02*
Y56459D01*
X260510D01*
X260816Y56304D01*
X261008Y56097D01*
X261085Y55684D01*
X261008Y55271D01*
X260778Y55012D01*
X260510Y54857D01*
X259551D01*
G01X260510D02*
X261085Y53359D01*
G01X262690Y55942D02*
X262920Y56252D01*
X263188Y56407D01*
X263495Y56459D01*
X263878Y56356D01*
X264146Y56097D01*
X264223Y55787D01*
X264185Y55477D01*
X264031Y55219D01*
X263265Y54702D01*
X262920Y54341D01*
X262690Y53824D01*
X262613Y53359D01*
X264223D01*
G01X266518Y56459D02*
X266211Y56356D01*
X265981Y56097D01*
X265828Y55787D01*
X265713Y55374D01*
X265675Y54909D01*
X265713Y54444D01*
X265828Y54031D01*
X265981Y53721D01*
X266211Y53462D01*
X266518Y53359D01*
X266825Y53462D01*
X267055Y53721D01*
X267208Y54031D01*
X267323Y54444D01*
X267361Y54909D01*
X267323Y55374D01*
X267208Y55787D01*
X267055Y56097D01*
X266825Y56356D01*
X266518Y56459D01*
G01X251911Y61733D02*
X255111D01*
G01X243914Y66201D02*
X250714D01*
G01X251884Y73826D02*
X251937Y74368D01*
X252017Y74826D01*
X252124Y75243D01*
X252257Y75701D01*
X252470Y76326D01*
X251404D01*
G01X253550Y74326D02*
X253710Y74034D01*
X253924Y73868D01*
X254164Y73826D01*
X254377Y73868D01*
X254590Y74076D01*
X254724Y74326D01*
X254750Y74576D01*
X254697Y74868D01*
X254510Y75076D01*
X254324Y75159D01*
X254084D01*
G01X254324D02*
X254484Y75284D01*
X254617Y75493D01*
X254670Y75743D01*
X254617Y75993D01*
X254484Y76201D01*
X254244Y76326D01*
X254004Y76284D01*
X253764Y76118D01*
G01X242965Y79527D02*
X251965D01*
G01X251097Y121304D02*
X251150Y121846D01*
X251230Y122304D01*
X251337Y122721D01*
X251470Y123179D01*
X251683Y123804D01*
X250617D01*
G01X253670Y121304D02*
Y123804D01*
X252683Y122012D01*
X254017D01*
G01X253165Y112204D02*
X243965D01*
G01X248649Y168225D02*
X245549D01*
Y169184D01*
X245704Y169490D01*
X245911Y169682D01*
X246324Y169759D01*
X246737Y169682D01*
X246996Y169452D01*
X247151Y169184D01*
Y168225D01*
G01Y169184D02*
X248649Y169759D01*
G01X247357Y171364D02*
X246996Y171632D01*
X246789Y171862D01*
X246686Y172169D01*
X246789Y172437D01*
X246996Y172629D01*
X247306Y172782D01*
X247667Y172820D01*
X247977Y172782D01*
X248287Y172629D01*
X248546Y172399D01*
X248649Y172130D01*
X248546Y171824D01*
X248236Y171555D01*
X247771Y171402D01*
X247254Y171364D01*
X246582Y171440D01*
X246221Y171555D01*
X245859Y171747D01*
X245601Y172015D01*
X245549Y172284D01*
X245652Y172552D01*
X245911Y172744D01*
G01X248649Y175652D02*
X245549D01*
X247771Y174234D01*
Y176150D01*
G01X248649Y178752D02*
X245549D01*
X247771Y177334D01*
Y179250D01*
G01X249452Y173159D02*
Y170937D01*
X249605Y170472D01*
X249912Y170162D01*
X250295Y170059D01*
X250678Y170162D01*
X250985Y170472D01*
X251138Y170937D01*
Y173159D01*
G01X253395Y170059D02*
Y173159D01*
X252935Y172539D01*
G01Y170059D02*
X253855D01*
G01X256495D02*
Y173159D01*
X256035Y172539D01*
G01Y170059D02*
X256955D01*
G01X259518D02*
X259595Y170731D01*
X259710Y171299D01*
X259863Y171816D01*
X260055Y172384D01*
X260362Y173159D01*
X258828D01*
G01X255248Y180139D02*
Y183239D01*
X256207D01*
X256513Y183084D01*
X256705Y182877D01*
X256782Y182464D01*
X256705Y182051D01*
X256475Y181792D01*
X256207Y181637D01*
X255248D01*
G01X256207D02*
X256782Y180139D01*
G01X259115D02*
Y183239D01*
X258655Y182619D01*
G01Y180139D02*
X259575D01*
G01X261487Y182722D02*
X261717Y183032D01*
X261985Y183187D01*
X262292Y183239D01*
X262675Y183136D01*
X262943Y182877D01*
X263020Y182567D01*
X262982Y182257D01*
X262828Y181999D01*
X262062Y181482D01*
X261717Y181121D01*
X261487Y180604D01*
X261410Y180139D01*
X263020D01*
G01X265315D02*
X265583Y180191D01*
X265890Y180346D01*
X266082Y180604D01*
X266158Y180966D01*
X266082Y181327D01*
X265852Y181637D01*
X265507Y181792D01*
X265123D01*
X264893Y181896D01*
X264702Y182154D01*
X264625Y182516D01*
X264740Y182877D01*
X265008Y183136D01*
X265315Y183239D01*
X265622Y183136D01*
X265890Y182877D01*
X266005Y182516D01*
X265928Y182154D01*
X265737Y181896D01*
X265507Y181792D01*
X265123D01*
X264778Y181637D01*
X264548Y181327D01*
X264472Y180966D01*
X264548Y180604D01*
X264740Y180346D01*
X265047Y180191D01*
X265315Y180139D01*
G01X267687Y182722D02*
X267917Y183032D01*
X268185Y183187D01*
X268492Y183239D01*
X268875Y183136D01*
X269143Y182877D01*
X269220Y182567D01*
X269182Y182257D01*
X269028Y181999D01*
X268262Y181482D01*
X267917Y181121D01*
X267687Y180604D01*
X267610Y180139D01*
X269220D01*
G01X248510Y188986D02*
X250732D01*
X251197Y189139D01*
X251507Y189446D01*
X251610Y189829D01*
X251507Y190212D01*
X251197Y190519D01*
X250732Y190672D01*
X248510D01*
G01X251610Y192929D02*
X248510D01*
X249130Y192469D01*
G01X251610D02*
Y193389D01*
G01Y196029D02*
X248510D01*
X249130Y195569D01*
G01X251610D02*
Y196489D01*
G01Y199129D02*
X251558Y199397D01*
X251403Y199704D01*
X251145Y199896D01*
X250783Y199972D01*
X250422Y199896D01*
X250112Y199666D01*
X249957Y199321D01*
Y198937D01*
X249853Y198707D01*
X249595Y198516D01*
X249233Y198439D01*
X248872Y198554D01*
X248613Y198822D01*
X248510Y199129D01*
X248613Y199436D01*
X248872Y199704D01*
X249233Y199819D01*
X249595Y199742D01*
X249853Y199551D01*
X249957Y199321D01*
Y198937D01*
X250112Y198592D01*
X250422Y198362D01*
X250783Y198286D01*
X251145Y198362D01*
X251403Y198554D01*
X251558Y198861D01*
X251610Y199129D01*
G01X244569Y361256D02*
Y363756D01*
X243582Y361964D01*
X244916D01*
G01X245942Y363339D02*
X246102Y363589D01*
X246289Y363714D01*
X246502Y363756D01*
X246769Y363673D01*
X246956Y363464D01*
X247009Y363214D01*
X246982Y362964D01*
X246876Y362756D01*
X246342Y362339D01*
X246102Y362048D01*
X245942Y361631D01*
X245889Y361256D01*
X247009D01*
G01X248069D02*
Y363756D01*
X247082Y361964D01*
X248416D01*
G01X250269Y361256D02*
Y363756D01*
X249282Y361964D01*
X250616D01*
G01X251069Y356756D02*
Y359256D01*
X250082Y357464D01*
X251416D01*
G01X252362Y357131D02*
X252522Y356923D01*
X252709Y356798D01*
X252949Y356756D01*
X253189Y356839D01*
X253376Y357006D01*
X253509Y357298D01*
X253536Y357631D01*
X253482Y357964D01*
X253349Y358173D01*
X253162Y358339D01*
X252976Y358381D01*
X252789Y358339D01*
X252549Y358173D01*
X252629Y359256D01*
X253349D01*
G01X252069Y361256D02*
Y363756D01*
X251082Y361964D01*
X252416D01*
G01X253442Y362298D02*
X253629Y362589D01*
X253789Y362756D01*
X254002Y362839D01*
X254189Y362756D01*
X254322Y362589D01*
X254429Y362339D01*
X254456Y362048D01*
X254429Y361798D01*
X254322Y361548D01*
X254162Y361339D01*
X253976Y361256D01*
X253762Y361339D01*
X253576Y361589D01*
X253469Y361964D01*
X253442Y362381D01*
X253496Y362923D01*
X253576Y363214D01*
X253709Y363506D01*
X253896Y363714D01*
X254082Y363756D01*
X254269Y363673D01*
X254402Y363464D01*
G01X255069Y356756D02*
Y359256D01*
X254082Y357464D01*
X255416D01*
G01X256896Y356756D02*
X256949Y357298D01*
X257029Y357756D01*
X257136Y358173D01*
X257269Y358631D01*
X257482Y359256D01*
X256416D01*
G01X255800Y360419D02*
Y362919D01*
X254813Y361127D01*
X256147D01*
G01X257680Y360419D02*
X257867Y360461D01*
X258080Y360586D01*
X258213Y360794D01*
X258267Y361086D01*
X258213Y361377D01*
X258053Y361627D01*
X257813Y361752D01*
X257547D01*
X257387Y361836D01*
X257253Y362044D01*
X257200Y362336D01*
X257280Y362627D01*
X257467Y362836D01*
X257680Y362919D01*
X257893Y362836D01*
X258080Y362627D01*
X258160Y362336D01*
X258107Y362044D01*
X257973Y361836D01*
X257813Y361752D01*
X257547D01*
X257307Y361627D01*
X257147Y361377D01*
X257093Y361086D01*
X257147Y360794D01*
X257280Y360586D01*
X257493Y360461D01*
X257680Y360419D01*
G01X258569Y356756D02*
Y359256D01*
X257582Y357464D01*
X258916D01*
G01X259996Y357048D02*
X260182Y356839D01*
X260396Y356756D01*
X260609Y356839D01*
X260796Y357089D01*
X260929Y357464D01*
X260982Y357839D01*
Y358298D01*
X260929Y358673D01*
X260796Y359006D01*
X260636Y359173D01*
X260449Y359256D01*
X260236Y359173D01*
X260076Y359006D01*
X259969Y358756D01*
X259916Y358423D01*
X259969Y358131D01*
X260102Y357839D01*
X260262Y357673D01*
X260449Y357631D01*
X260662Y357714D01*
X260822Y357923D01*
X260982Y358298D01*
G01X246569Y356756D02*
Y359256D01*
X245582Y357464D01*
X246916D01*
G01X247862Y357256D02*
X248022Y356964D01*
X248236Y356798D01*
X248476Y356756D01*
X248689Y356798D01*
X248902Y357006D01*
X249036Y357256D01*
X249062Y357506D01*
X249009Y357798D01*
X248822Y358006D01*
X248636Y358089D01*
X248396D01*
G01X248636D02*
X248796Y358214D01*
X248929Y358423D01*
X248982Y358673D01*
X248929Y358923D01*
X248796Y359131D01*
X248556Y359256D01*
X248316Y359214D01*
X248076Y359048D01*
G01X243170Y376440D02*
X286590D01*
G01X248606Y390264D02*
X258806D01*
G01X253706D02*
Y385664D01*
G01X258806D02*
X248606D01*
G01D02*
Y390264D01*
G01X247306Y389564D02*
Y386364D01*
G01X243129Y377648D02*
Y383848D01*
G01D02*
X246329D01*
G01D02*
Y377648D01*
G01D02*
X243129D01*
G01X247129D02*
Y383848D01*
G01D02*
X250329D01*
G01D02*
Y377648D01*
G01D02*
X247129D01*
G01X254329Y383848D02*
Y377648D01*
G01D02*
X251129D01*
G01D02*
Y383848D01*
G01D02*
X254329D01*
G01X258329D02*
Y377648D01*
G01X255129D02*
Y383848D01*
G01D02*
X258329D01*
G01Y377648D02*
X255129D01*
G01X246510Y408076D02*
X246203Y408128D01*
X245935Y408334D01*
X245705Y408644D01*
X245552Y409006D01*
X245475Y409419D01*
Y409833D01*
X245552Y410246D01*
X245705Y410608D01*
X245935Y410918D01*
X246203Y411124D01*
X246510Y411176D01*
X246817Y411124D01*
X247085Y410918D01*
X247315Y410608D01*
X247468Y410246D01*
X247545Y409833D01*
Y409419D01*
X247468Y409006D01*
X247315Y408644D01*
X247085Y408334D01*
X246817Y408128D01*
X246510Y408076D01*
G01X246817Y408903D02*
X247277Y408076D01*
G01X248882Y410659D02*
X249112Y410969D01*
X249380Y411124D01*
X249687Y411176D01*
X250070Y411073D01*
X250338Y410814D01*
X250415Y410504D01*
X250377Y410194D01*
X250223Y409936D01*
X249457Y409419D01*
X249112Y409058D01*
X248882Y408541D01*
X248805Y408076D01*
X250415D01*
G01X252058Y408438D02*
X252327Y408179D01*
X252633Y408076D01*
X252940Y408179D01*
X253208Y408489D01*
X253400Y408954D01*
X253477Y409419D01*
Y409988D01*
X253400Y410453D01*
X253208Y410866D01*
X252978Y411073D01*
X252710Y411176D01*
X252403Y411073D01*
X252173Y410866D01*
X252020Y410556D01*
X251943Y410143D01*
X252020Y409781D01*
X252212Y409419D01*
X252442Y409213D01*
X252710Y409161D01*
X253017Y409264D01*
X253247Y409523D01*
X253477Y409988D01*
G01X256450Y396576D02*
Y392070D01*
G01Y403881D02*
Y399376D01*
G01X255745Y403881D02*
X256450D01*
G01X244639D02*
X245345D01*
G01X244639Y399376D02*
Y403881D01*
G01X256450Y392070D02*
X255745D01*
G01X245445D02*
X244639D01*
G01D02*
Y396576D01*
G01X256112Y405726D02*
Y408226D01*
X256646D01*
X256859Y408101D01*
X257019Y407934D01*
X257152Y407684D01*
X257259Y407393D01*
X257286Y406976D01*
X257259Y406559D01*
X257152Y406268D01*
X257019Y406018D01*
X256859Y405851D01*
X256646Y405726D01*
X256112D01*
G01X258512Y405356D02*
X271136D01*
G01X258512Y393544D02*
Y405356D01*
G01X271136Y393544D02*
X258512D01*
G01X243890Y421656D02*
Y414856D01*
G01X243955Y429535D02*
Y422735D01*
G01X256398Y419404D02*
X253198D01*
G01X256398Y425604D02*
Y419404D01*
G01X253198D02*
Y425604D01*
G01X260398Y419404D02*
X257198D01*
G01D02*
Y425604D01*
G01X250442Y424158D02*
Y424691D01*
X251192D01*
X251442Y424531D01*
X251609Y424345D01*
X251692Y424078D01*
X251609Y423811D01*
X251442Y423625D01*
X251192Y423465D01*
X250900Y423358D01*
X250567Y423305D01*
X250275D01*
X250025Y423358D01*
X249734Y423465D01*
X249484Y423625D01*
X249317Y423785D01*
X249192Y423998D01*
Y424185D01*
X249275Y424398D01*
X249442Y424558D01*
G01X259620Y409657D02*
X259313Y409709D01*
X259045Y409915D01*
X258815Y410225D01*
X258662Y410587D01*
X258585Y411000D01*
Y411414D01*
X258662Y411827D01*
X258815Y412189D01*
X259045Y412499D01*
X259313Y412705D01*
X259620Y412757D01*
X259927Y412705D01*
X260195Y412499D01*
X260425Y412189D01*
X260578Y411827D01*
X260655Y411414D01*
Y411000D01*
X260578Y410587D01*
X260425Y410225D01*
X260195Y409915D01*
X259927Y409709D01*
X259620Y409657D01*
G01X259927Y410484D02*
X260387Y409657D01*
G01X261877Y410277D02*
X262107Y409915D01*
X262413Y409709D01*
X262758Y409657D01*
X263065Y409709D01*
X263372Y409967D01*
X263563Y410277D01*
X263602Y410587D01*
X263525Y410949D01*
X263257Y411207D01*
X262988Y411310D01*
X262643D01*
G01X262988D02*
X263218Y411465D01*
X263410Y411724D01*
X263487Y412034D01*
X263410Y412344D01*
X263218Y412602D01*
X262873Y412757D01*
X262528Y412705D01*
X262183Y412499D01*
G01X265820Y412757D02*
X265513Y412654D01*
X265283Y412395D01*
X265130Y412085D01*
X265015Y411672D01*
X264977Y411207D01*
X265015Y410742D01*
X265130Y410329D01*
X265283Y410019D01*
X265513Y409760D01*
X265820Y409657D01*
X266127Y409760D01*
X266357Y410019D01*
X266510Y410329D01*
X266625Y410742D01*
X266663Y411207D01*
X266625Y411672D01*
X266510Y412085D01*
X266357Y412395D01*
X266127Y412654D01*
X265820Y412757D01*
G01X243955Y437535D02*
Y430735D01*
G01X253198Y425604D02*
X256398D01*
G01X257198D02*
X260398D01*
G01X251354Y431761D02*
X251302Y431454D01*
X251096Y431186D01*
X250786Y430956D01*
X250424Y430803D01*
X250011Y430726D01*
X249597D01*
X249184Y430803D01*
X248822Y430956D01*
X248512Y431186D01*
X248306Y431454D01*
X248254Y431761D01*
X248306Y432068D01*
X248512Y432336D01*
X248822Y432566D01*
X249184Y432719D01*
X249597Y432796D01*
X250011D01*
X250424Y432719D01*
X250786Y432566D01*
X251096Y432336D01*
X251302Y432068D01*
X251354Y431761D01*
G01X250527Y432068D02*
X251354Y432528D01*
G01X250734Y434018D02*
X251096Y434248D01*
X251302Y434554D01*
X251354Y434899D01*
X251302Y435206D01*
X251044Y435513D01*
X250734Y435704D01*
X250424Y435743D01*
X250062Y435666D01*
X249804Y435398D01*
X249701Y435129D01*
Y434784D01*
G01Y435129D02*
X249546Y435359D01*
X249287Y435551D01*
X248977Y435628D01*
X248667Y435551D01*
X248409Y435359D01*
X248254Y435014D01*
X248306Y434669D01*
X248512Y434324D01*
G01X251354Y437961D02*
X251302Y438229D01*
X251147Y438536D01*
X250889Y438728D01*
X250527Y438804D01*
X250166Y438728D01*
X249856Y438498D01*
X249701Y438153D01*
Y437769D01*
X249597Y437539D01*
X249339Y437348D01*
X248977Y437271D01*
X248616Y437386D01*
X248357Y437654D01*
X248254Y437961D01*
X248357Y438268D01*
X248616Y438536D01*
X248977Y438651D01*
X249339Y438574D01*
X249597Y438383D01*
X249701Y438153D01*
Y437769D01*
X249856Y437424D01*
X250166Y437194D01*
X250527Y437118D01*
X250889Y437194D01*
X251147Y437386D01*
X251302Y437693D01*
X251354Y437961D01*
G01X252647Y428070D02*
Y440694D01*
G01X264459Y428070D02*
X252647D01*
G01X245964Y448297D02*
X242864D01*
Y449256D01*
X243019Y449562D01*
X243226Y449754D01*
X243639Y449831D01*
X244052Y449754D01*
X244311Y449524D01*
X244466Y449256D01*
Y448297D01*
G01Y449256D02*
X245964Y449831D01*
G01X245344Y451321D02*
X245706Y451551D01*
X245912Y451857D01*
X245964Y452202D01*
X245912Y452509D01*
X245654Y452816D01*
X245344Y453007D01*
X245034Y453046D01*
X244672Y452969D01*
X244414Y452701D01*
X244311Y452432D01*
Y452087D01*
G01Y452432D02*
X244156Y452662D01*
X243897Y452854D01*
X243587Y452931D01*
X243277Y452854D01*
X243019Y452662D01*
X242864Y452317D01*
X242916Y451972D01*
X243122Y451627D01*
G01X243381Y454536D02*
X243071Y454766D01*
X242916Y455034D01*
X242864Y455341D01*
X242967Y455724D01*
X243226Y455992D01*
X243536Y456069D01*
X243846Y456031D01*
X244104Y455877D01*
X244621Y455111D01*
X244982Y454766D01*
X245499Y454536D01*
X245964Y454459D01*
Y456069D01*
G01X243381Y457636D02*
X243071Y457866D01*
X242916Y458134D01*
X242864Y458441D01*
X242967Y458824D01*
X243226Y459092D01*
X243536Y459169D01*
X243846Y459131D01*
X244104Y458977D01*
X244621Y458211D01*
X244982Y457866D01*
X245499Y457636D01*
X245964Y457559D01*
Y459169D01*
G01X250081Y448297D02*
X246981D01*
Y449256D01*
X247136Y449562D01*
X247343Y449754D01*
X247756Y449831D01*
X248169Y449754D01*
X248428Y449524D01*
X248583Y449256D01*
Y448297D01*
G01Y449256D02*
X250081Y449831D01*
G01X249461Y451321D02*
X249823Y451551D01*
X250029Y451857D01*
X250081Y452202D01*
X250029Y452509D01*
X249771Y452816D01*
X249461Y453007D01*
X249151Y453046D01*
X248789Y452969D01*
X248531Y452701D01*
X248428Y452432D01*
Y452087D01*
G01Y452432D02*
X248273Y452662D01*
X248014Y452854D01*
X247704Y452931D01*
X247394Y452854D01*
X247136Y452662D01*
X246981Y452317D01*
X247033Y451972D01*
X247239Y451627D01*
G01X247498Y454536D02*
X247188Y454766D01*
X247033Y455034D01*
X246981Y455341D01*
X247084Y455724D01*
X247343Y455992D01*
X247653Y456069D01*
X247963Y456031D01*
X248221Y455877D01*
X248738Y455111D01*
X249099Y454766D01*
X249616Y454536D01*
X250081Y454459D01*
Y456069D01*
G01X248789Y457636D02*
X248428Y457904D01*
X248221Y458134D01*
X248118Y458441D01*
X248221Y458709D01*
X248428Y458901D01*
X248738Y459054D01*
X249099Y459092D01*
X249409Y459054D01*
X249719Y458901D01*
X249978Y458671D01*
X250081Y458402D01*
X249978Y458096D01*
X249668Y457827D01*
X249203Y457674D01*
X248686Y457636D01*
X248014Y457712D01*
X247653Y457827D01*
X247291Y458019D01*
X247033Y458287D01*
X246981Y458556D01*
X247084Y458824D01*
X247343Y459016D01*
G01X254081Y448297D02*
X250981D01*
Y449256D01*
X251136Y449562D01*
X251343Y449754D01*
X251756Y449831D01*
X252169Y449754D01*
X252428Y449524D01*
X252583Y449256D01*
Y448297D01*
G01Y449256D02*
X254081Y449831D01*
G01X253461Y451321D02*
X253823Y451551D01*
X254029Y451857D01*
X254081Y452202D01*
X254029Y452509D01*
X253771Y452816D01*
X253461Y453007D01*
X253151Y453046D01*
X252789Y452969D01*
X252531Y452701D01*
X252428Y452432D01*
Y452087D01*
G01Y452432D02*
X252273Y452662D01*
X252014Y452854D01*
X251704Y452931D01*
X251394Y452854D01*
X251136Y452662D01*
X250981Y452317D01*
X251033Y451972D01*
X251239Y451627D01*
G01X253461Y454421D02*
X253823Y454651D01*
X254029Y454957D01*
X254081Y455302D01*
X254029Y455609D01*
X253771Y455916D01*
X253461Y456107D01*
X253151Y456146D01*
X252789Y456069D01*
X252531Y455801D01*
X252428Y455532D01*
Y455187D01*
G01Y455532D02*
X252273Y455762D01*
X252014Y455954D01*
X251704Y456031D01*
X251394Y455954D01*
X251136Y455762D01*
X250981Y455417D01*
X251033Y455072D01*
X251239Y454727D01*
G01X254081Y458364D02*
X254029Y458632D01*
X253874Y458939D01*
X253616Y459131D01*
X253254Y459207D01*
X252893Y459131D01*
X252583Y458901D01*
X252428Y458556D01*
Y458172D01*
X252324Y457942D01*
X252066Y457751D01*
X251704Y457674D01*
X251343Y457789D01*
X251084Y458057D01*
X250981Y458364D01*
X251084Y458671D01*
X251343Y458939D01*
X251704Y459054D01*
X252066Y458977D01*
X252324Y458786D01*
X252428Y458556D01*
Y458172D01*
X252583Y457827D01*
X252893Y457597D01*
X253254Y457521D01*
X253616Y457597D01*
X253874Y457789D01*
X254029Y458096D01*
X254081Y458364D01*
G01X260002Y441992D02*
X253802D01*
G01D02*
Y445192D01*
G01D02*
X260002D01*
G01X258081Y448297D02*
X254981D01*
Y449256D01*
X255136Y449562D01*
X255343Y449754D01*
X255756Y449831D01*
X256169Y449754D01*
X256428Y449524D01*
X256583Y449256D01*
Y448297D01*
G01Y449256D02*
X258081Y449831D01*
G01X257461Y451321D02*
X257823Y451551D01*
X258029Y451857D01*
X258081Y452202D01*
X258029Y452509D01*
X257771Y452816D01*
X257461Y453007D01*
X257151Y453046D01*
X256789Y452969D01*
X256531Y452701D01*
X256428Y452432D01*
Y452087D01*
G01Y452432D02*
X256273Y452662D01*
X256014Y452854D01*
X255704Y452931D01*
X255394Y452854D01*
X255136Y452662D01*
X254981Y452317D01*
X255033Y451972D01*
X255239Y451627D01*
G01X258081Y455724D02*
X254981D01*
X257203Y454306D01*
Y456222D01*
G01X257616Y457521D02*
X257874Y457751D01*
X258029Y458019D01*
X258081Y458364D01*
X257978Y458709D01*
X257771Y458977D01*
X257409Y459169D01*
X256996Y459207D01*
X256583Y459131D01*
X256324Y458939D01*
X256118Y458671D01*
X256066Y458402D01*
X256118Y458134D01*
X256324Y457789D01*
X254981Y457904D01*
Y458939D01*
G01X252647Y440694D02*
X264459D01*
G01X243609Y471253D02*
Y465053D01*
G01X252909Y464553D02*
X249709D01*
G01X252909Y470753D02*
Y464553D01*
G01X249709D02*
Y470753D01*
G01D02*
X252909D01*
G01X257109Y464453D02*
X253909D01*
G01D02*
Y470653D01*
G01D02*
X257109D01*
G01D02*
Y464453D01*
G01X243509Y479653D02*
Y473453D01*
G01X244509Y479653D02*
X247709D01*
G01X244509Y473453D02*
Y479653D01*
G01X247709Y473453D02*
X244509D01*
G01X247709Y479653D02*
Y473453D01*
G01X253909Y479653D02*
X257109D01*
G01X253909Y473453D02*
Y479653D01*
G01X257109Y473453D02*
X253909D01*
G01X257109Y479653D02*
Y473453D01*
G01X249709Y479653D02*
X252909D01*
G01X249709Y473453D02*
Y479653D01*
G01X252909Y473453D02*
X249709D01*
G01X252909Y479653D02*
Y473453D01*
G01X244019Y571688D02*
X247119D01*
G01X244019Y570806D02*
Y572570D01*
G01X250269Y577220D02*
X247169D01*
Y578179D01*
X247324Y578485D01*
X247531Y578677D01*
X247944Y578754D01*
X248357Y578677D01*
X248616Y578447D01*
X248771Y578179D01*
Y577220D01*
G01Y578179D02*
X250269Y578754D01*
G01X253419Y570921D02*
X250319D01*
Y571841D01*
X250474Y572148D01*
X250836Y572378D01*
X251249Y572455D01*
X251662Y572378D01*
X251972Y572186D01*
X252127Y571841D01*
Y570921D01*
G01X254438Y576891D02*
X251338D01*
X254438Y578655D01*
X251338D01*
G01X259718Y570691D02*
X256618D01*
X259201Y571688D01*
X256618Y572685D01*
X259718D01*
G01X243620Y594480D02*
Y610590D01*
G01X251740Y581420D02*
X249260D01*
G01X251740Y598460D02*
Y581420D01*
G01X245241Y584656D02*
Y581656D01*
G01X248341Y584756D02*
Y581556D01*
G01X245241Y588656D02*
Y585656D01*
G01X248341Y588756D02*
Y585556D01*
G01X250874Y594782D02*
X244674D01*
G01X250874Y597982D02*
Y594782D01*
G01X244674D02*
Y597982D01*
G01X258709Y581453D02*
X255509D01*
G01Y587653D02*
X258709D01*
G01X255509Y581453D02*
Y587653D01*
G01X245770Y612370D02*
X245730D01*
G01X245770Y610590D02*
Y612370D01*
G01X243620Y610590D02*
X245770D01*
G01X261640Y598460D02*
X251740D01*
G01X254418Y604763D02*
Y611363D01*
G01X246918Y611463D02*
X261918D01*
G01X246918Y604663D02*
Y611463D01*
G01X261918Y604663D02*
X246918D01*
G01X252271Y600662D02*
Y603862D01*
G01D02*
X258471D01*
G01X255371Y600762D02*
Y603762D01*
G01X258471Y603862D02*
Y600662D01*
G01D02*
X252271D01*
G01X246918Y612471D02*
Y619271D01*
G01X261918Y612471D02*
X246918D01*
G01X244674Y597982D02*
X250874D01*
G01X250600Y627990D02*
X262490D01*
G01X254443Y620416D02*
Y627016D01*
G01X246943Y627116D02*
X261943D01*
G01X246943Y620316D02*
Y627116D01*
G01X261943Y620316D02*
X246943D01*
G01X246918Y619271D02*
X261918D01*
G01X254418Y612571D02*
Y619171D01*
G01X244713Y628084D02*
Y634284D01*
G01X247913D02*
Y628084D01*
G01D02*
X244713D01*
G01X248943Y636704D02*
X255543D01*
G01X255643Y644204D02*
Y629204D01*
G01X248843D02*
Y644204D01*
G01X255643Y629204D02*
X248843D01*
G01X247893Y643708D02*
X244693D01*
G01X247893Y649908D02*
Y643708D01*
G01X244693D02*
Y649908D01*
G01X244713Y634284D02*
X247913D01*
G01X258469Y642736D02*
X262975D01*
G01X258469Y641930D02*
Y642736D01*
G01Y630925D02*
Y631630D01*
G01X262975Y630925D02*
X258469D01*
G01X247354Y641057D02*
X247887D01*
Y640307D01*
X247727Y640057D01*
X247541Y639890D01*
X247274Y639807D01*
X247007Y639890D01*
X246821Y640057D01*
X246661Y640307D01*
X246554Y640599D01*
X246501Y640932D01*
Y641224D01*
X246554Y641474D01*
X246661Y641765D01*
X246821Y642015D01*
X246981Y642182D01*
X247194Y642307D01*
X247381D01*
X247594Y642224D01*
X247754Y642057D01*
G01X243975Y643670D02*
Y631046D01*
G01X259263Y662069D02*
X259033Y662224D01*
X258765Y662327D01*
X258458D01*
X258113Y662172D01*
X257845Y661914D01*
X257653Y661604D01*
X257500Y661087D01*
X257462Y660622D01*
X257538Y660157D01*
X257653Y659847D01*
X257883Y659537D01*
X258152Y659330D01*
X258420Y659227D01*
X258688D01*
X258957Y659330D01*
X259187Y659485D01*
X259378Y659692D01*
G01X260677D02*
X260907Y659434D01*
X261175Y659279D01*
X261520Y659227D01*
X261865Y659330D01*
X262133Y659537D01*
X262325Y659899D01*
X262363Y660312D01*
X262287Y660725D01*
X262095Y660984D01*
X261827Y661190D01*
X261558Y661242D01*
X261290Y661190D01*
X260945Y660984D01*
X261060Y662327D01*
X262095D01*
G01X264620Y659227D02*
X264888Y659279D01*
X265195Y659434D01*
X265387Y659692D01*
X265463Y660054D01*
X265387Y660415D01*
X265157Y660725D01*
X264812Y660880D01*
X264428D01*
X264198Y660984D01*
X264007Y661242D01*
X263930Y661604D01*
X264045Y661965D01*
X264313Y662224D01*
X264620Y662327D01*
X264927Y662224D01*
X265195Y661965D01*
X265310Y661604D01*
X265233Y661242D01*
X265042Y660984D01*
X264812Y660880D01*
X264428D01*
X264083Y660725D01*
X263853Y660415D01*
X263777Y660054D01*
X263853Y659692D01*
X264045Y659434D01*
X264352Y659279D01*
X264620Y659227D01*
G01X266992Y661810D02*
X267222Y662120D01*
X267490Y662275D01*
X267797Y662327D01*
X268180Y662224D01*
X268448Y661965D01*
X268525Y661655D01*
X268487Y661345D01*
X268333Y661087D01*
X267567Y660570D01*
X267222Y660209D01*
X266992Y659692D01*
X266915Y659227D01*
X268525D01*
G01X248843Y644204D02*
X255643D01*
G01X243270Y650778D02*
Y644578D01*
G01X248507Y654101D02*
X245407D01*
Y655060D01*
X245562Y655366D01*
X245769Y655558D01*
X246182Y655635D01*
X246595Y655558D01*
X246854Y655328D01*
X247009Y655060D01*
Y654101D01*
G01Y655060D02*
X248507Y655635D01*
G01Y657968D02*
X245407D01*
X246027Y657508D01*
G01X248507D02*
Y658428D01*
G01Y661068D02*
X245407D01*
X246027Y660608D01*
G01X248507D02*
Y661528D01*
G01Y664168D02*
X245407D01*
X246027Y663708D01*
G01X248507D02*
Y664628D01*
G01X245407Y667268D02*
X245510Y666961D01*
X245769Y666731D01*
X246079Y666578D01*
X246492Y666463D01*
X246957Y666425D01*
X247422Y666463D01*
X247835Y666578D01*
X248145Y666731D01*
X248404Y666961D01*
X248507Y667268D01*
X248404Y667575D01*
X248145Y667805D01*
X247835Y667958D01*
X247422Y668073D01*
X246957Y668111D01*
X246492Y668073D01*
X246079Y667958D01*
X245769Y667805D01*
X245510Y667575D01*
X245407Y667268D01*
G01X244693Y649908D02*
X247893D01*
G01X257329Y655278D02*
Y658378D01*
X258288D01*
X258594Y658223D01*
X258786Y658016D01*
X258863Y657603D01*
X258786Y657190D01*
X258556Y656931D01*
X258288Y656776D01*
X257329D01*
G01X258288D02*
X258863Y655278D01*
G01X260468Y656570D02*
X260736Y656931D01*
X260966Y657138D01*
X261273Y657241D01*
X261541Y657138D01*
X261733Y656931D01*
X261886Y656621D01*
X261924Y656260D01*
X261886Y655950D01*
X261733Y655640D01*
X261503Y655381D01*
X261234Y655278D01*
X260928Y655381D01*
X260659Y655691D01*
X260506Y656156D01*
X260468Y656673D01*
X260544Y657345D01*
X260659Y657706D01*
X260851Y658068D01*
X261119Y658326D01*
X261388Y658378D01*
X261656Y658275D01*
X261848Y658016D01*
G01X263568Y656570D02*
X263836Y656931D01*
X264066Y657138D01*
X264373Y657241D01*
X264641Y657138D01*
X264833Y656931D01*
X264986Y656621D01*
X265024Y656260D01*
X264986Y655950D01*
X264833Y655640D01*
X264603Y655381D01*
X264334Y655278D01*
X264028Y655381D01*
X263759Y655691D01*
X263606Y656156D01*
X263568Y656673D01*
X263644Y657345D01*
X263759Y657706D01*
X263951Y658068D01*
X264219Y658326D01*
X264488Y658378D01*
X264756Y658275D01*
X264948Y658016D01*
G01X266668Y657861D02*
X266898Y658171D01*
X267166Y658326D01*
X267473Y658378D01*
X267856Y658275D01*
X268124Y658016D01*
X268201Y657706D01*
X268163Y657396D01*
X268009Y657138D01*
X267243Y656621D01*
X266898Y656260D01*
X266668Y655743D01*
X266591Y655278D01*
X268201D01*
G01X257329Y651001D02*
Y654101D01*
X258288D01*
X258594Y653946D01*
X258786Y653739D01*
X258863Y653326D01*
X258786Y652913D01*
X258556Y652654D01*
X258288Y652499D01*
X257329D01*
G01X258288D02*
X258863Y651001D01*
G01X260468Y652293D02*
X260736Y652654D01*
X260966Y652861D01*
X261273Y652964D01*
X261541Y652861D01*
X261733Y652654D01*
X261886Y652344D01*
X261924Y651983D01*
X261886Y651673D01*
X261733Y651363D01*
X261503Y651104D01*
X261234Y651001D01*
X260928Y651104D01*
X260659Y651414D01*
X260506Y651879D01*
X260468Y652396D01*
X260544Y653068D01*
X260659Y653429D01*
X260851Y653791D01*
X261119Y654049D01*
X261388Y654101D01*
X261656Y653998D01*
X261848Y653739D01*
G01X264219Y651001D02*
X264296Y651673D01*
X264411Y652241D01*
X264564Y652758D01*
X264756Y653326D01*
X265063Y654101D01*
X263529D01*
G01X266668Y652293D02*
X266936Y652654D01*
X267166Y652861D01*
X267473Y652964D01*
X267741Y652861D01*
X267933Y652654D01*
X268086Y652344D01*
X268124Y651983D01*
X268086Y651673D01*
X267933Y651363D01*
X267703Y651104D01*
X267434Y651001D01*
X267128Y651104D01*
X266859Y651414D01*
X266706Y651879D01*
X266668Y652396D01*
X266744Y653068D01*
X266859Y653429D01*
X267051Y653791D01*
X267319Y654049D01*
X267588Y654101D01*
X267856Y653998D01*
X268048Y653739D01*
G01X257329Y646904D02*
Y650004D01*
X258288D01*
X258594Y649849D01*
X258786Y649642D01*
X258863Y649229D01*
X258786Y648816D01*
X258556Y648557D01*
X258288Y648402D01*
X257329D01*
G01X258288D02*
X258863Y646904D01*
G01X260468Y648196D02*
X260736Y648557D01*
X260966Y648764D01*
X261273Y648867D01*
X261541Y648764D01*
X261733Y648557D01*
X261886Y648247D01*
X261924Y647886D01*
X261886Y647576D01*
X261733Y647266D01*
X261503Y647007D01*
X261234Y646904D01*
X260928Y647007D01*
X260659Y647317D01*
X260506Y647782D01*
X260468Y648299D01*
X260544Y648971D01*
X260659Y649332D01*
X260851Y649694D01*
X261119Y649952D01*
X261388Y650004D01*
X261656Y649901D01*
X261848Y649642D01*
G01X264219Y646904D02*
X264296Y647576D01*
X264411Y648144D01*
X264564Y648661D01*
X264756Y649229D01*
X265063Y650004D01*
X263529D01*
G01X267396Y646904D02*
X267664Y646956D01*
X267971Y647111D01*
X268163Y647369D01*
X268239Y647731D01*
X268163Y648092D01*
X267933Y648402D01*
X267588Y648557D01*
X267204D01*
X266974Y648661D01*
X266783Y648919D01*
X266706Y649281D01*
X266821Y649642D01*
X267089Y649901D01*
X267396Y650004D01*
X267703Y649901D01*
X267971Y649642D01*
X268086Y649281D01*
X268009Y648919D01*
X267818Y648661D01*
X267588Y648557D01*
X267204D01*
X266859Y648402D01*
X266629Y648092D01*
X266553Y647731D01*
X266629Y647369D01*
X266821Y647111D01*
X267128Y646956D01*
X267396Y646904D01*
G01X248050Y670272D02*
Y673272D01*
G01X244950Y670172D02*
Y673372D01*
G01X251150Y670172D02*
X244950D01*
G01X251150Y673372D02*
Y670172D01*
G01X244950Y673372D02*
X251150D01*
G01X258370Y670172D02*
Y673372D01*
G01X264570Y670172D02*
X258370D01*
G01Y673372D02*
X264570D01*
G01X257953Y665929D02*
X257723Y666084D01*
X257455Y666187D01*
X257148D01*
X256803Y666032D01*
X256535Y665774D01*
X256343Y665464D01*
X256190Y664947D01*
X256152Y664482D01*
X256228Y664017D01*
X256343Y663707D01*
X256573Y663397D01*
X256842Y663190D01*
X257110Y663087D01*
X257378D01*
X257647Y663190D01*
X257877Y663345D01*
X258068Y663552D01*
G01X260210Y663087D02*
X260478Y663139D01*
X260785Y663294D01*
X260977Y663552D01*
X261053Y663914D01*
X260977Y664275D01*
X260747Y664585D01*
X260402Y664740D01*
X260018D01*
X259788Y664844D01*
X259597Y665102D01*
X259520Y665464D01*
X259635Y665825D01*
X259903Y666084D01*
X260210Y666187D01*
X260517Y666084D01*
X260785Y665825D01*
X260900Y665464D01*
X260823Y665102D01*
X260632Y664844D01*
X260402Y664740D01*
X260018D01*
X259673Y664585D01*
X259443Y664275D01*
X259367Y663914D01*
X259443Y663552D01*
X259635Y663294D01*
X259942Y663139D01*
X260210Y663087D01*
G01X263310D02*
X263578Y663139D01*
X263885Y663294D01*
X264077Y663552D01*
X264153Y663914D01*
X264077Y664275D01*
X263847Y664585D01*
X263502Y664740D01*
X263118D01*
X262888Y664844D01*
X262697Y665102D01*
X262620Y665464D01*
X262735Y665825D01*
X263003Y666084D01*
X263310Y666187D01*
X263617Y666084D01*
X263885Y665825D01*
X264000Y665464D01*
X263923Y665102D01*
X263732Y664844D01*
X263502Y664740D01*
X263118D01*
X262773Y664585D01*
X262543Y664275D01*
X262467Y663914D01*
X262543Y663552D01*
X262735Y663294D01*
X263042Y663139D01*
X263310Y663087D01*
G01X265567Y663552D02*
X265797Y663294D01*
X266065Y663139D01*
X266410Y663087D01*
X266755Y663190D01*
X267023Y663397D01*
X267215Y663759D01*
X267253Y664172D01*
X267177Y664585D01*
X266985Y664844D01*
X266717Y665050D01*
X266448Y665102D01*
X266180Y665050D01*
X265835Y664844D01*
X265950Y666187D01*
X266985D01*
G01X251820Y672047D02*
X251980Y671839D01*
X252167Y671714D01*
X252407Y671672D01*
X252647Y671755D01*
X252834Y671922D01*
X252967Y672214D01*
X252994Y672547D01*
X252940Y672880D01*
X252807Y673089D01*
X252620Y673255D01*
X252434Y673297D01*
X252247Y673255D01*
X252007Y673089D01*
X252087Y674172D01*
X252807D01*
G01X250335Y691179D02*
Y675179D01*
G01X255226Y672035D02*
Y674535D01*
X254239Y672743D01*
X255573D01*
G01X256513Y672327D02*
X256673Y672119D01*
X256860Y671994D01*
X257100Y671952D01*
X257340Y672035D01*
X257527Y672202D01*
X257660Y672494D01*
X257687Y672827D01*
X257633Y673160D01*
X257500Y673369D01*
X257313Y673535D01*
X257127Y673577D01*
X256940Y673535D01*
X256700Y673369D01*
X256780Y674452D01*
X257500D01*
G01X251631Y675179D02*
Y691179D01*
G01X263835Y675179D02*
X251631D01*
G01X249469Y692021D02*
Y694521D01*
X249149Y694021D01*
G01Y692021D02*
X249789D01*
G01X251631Y691179D02*
X263835D01*
G01X254316Y695545D02*
X260516D01*
G01X254316Y692345D02*
Y695545D01*
G01X260516Y692345D02*
X254316D01*
G01X251856Y693101D02*
X252016Y692809D01*
X252230Y692643D01*
X252470Y692601D01*
X252683Y692643D01*
X252896Y692851D01*
X253030Y693101D01*
X253056Y693351D01*
X253003Y693643D01*
X252816Y693851D01*
X252630Y693934D01*
X252390D01*
G01X252630D02*
X252790Y694059D01*
X252923Y694268D01*
X252976Y694518D01*
X252923Y694768D01*
X252790Y694976D01*
X252550Y695101D01*
X252310Y695059D01*
X252070Y694893D01*
G01X243476Y693217D02*
Y695717D01*
X244010D01*
X244223Y695592D01*
X244383Y695425D01*
X244516Y695175D01*
X244623Y694884D01*
X244650Y694467D01*
X244623Y694050D01*
X244516Y693759D01*
X244383Y693509D01*
X244223Y693342D01*
X244010Y693217D01*
X243476D01*
G01X250940Y711456D02*
Y696456D01*
G01X252440D02*
Y711456D01*
G01X265440Y696456D02*
X252440D01*
G01X246098Y713873D02*
X246631D01*
Y713123D01*
X246471Y712873D01*
X246285Y712706D01*
X246018Y712623D01*
X245751Y712706D01*
X245565Y712873D01*
X245405Y713123D01*
X245298Y713415D01*
X245245Y713748D01*
Y714040D01*
X245298Y714290D01*
X245405Y714581D01*
X245565Y714831D01*
X245725Y714998D01*
X245938Y715123D01*
X246125D01*
X246338Y715040D01*
X246498Y714873D01*
G01X257378Y712456D02*
X257591Y712248D01*
X257831Y712123D01*
X258045D01*
X258258Y712248D01*
X258418Y712456D01*
X258498Y712748D01*
X258445Y713040D01*
X258311Y713290D01*
X258071Y713456D01*
X257751Y713540D01*
X257565Y713706D01*
X257485Y713998D01*
X257538Y714290D01*
X257671Y714498D01*
X257858Y714623D01*
X258045D01*
X258231Y714540D01*
X258391Y714331D01*
G01X252440Y711456D02*
X265440D01*
G01X259040Y737556D02*
X255840D01*
G01D02*
Y743756D01*
G01X254440Y729156D02*
X251440D01*
G01X254540Y726056D02*
X251340D01*
G01X254540Y732256D02*
Y726056D01*
G01X251340Y732256D02*
X254540D01*
G01X251340Y726056D02*
Y732256D01*
G01X245540D02*
Y726056D01*
G01X250040Y737556D02*
X246840D01*
G01X250040Y743756D02*
Y737556D01*
G01X246840D02*
Y743756D01*
G01Y732256D02*
X250040D01*
G01X246840Y726056D02*
Y732256D01*
G01X250040Y726056D02*
X246840D01*
G01X250040Y732256D02*
Y726056D01*
G01X251341Y737556D02*
Y743756D01*
G01X254539Y737556D02*
X251341D01*
G01X254539Y743756D02*
Y737556D01*
G01X255840Y732256D02*
X259040D01*
G01X255840Y726056D02*
Y732256D01*
G01X259040Y726056D02*
X255840D01*
G01X245540Y743756D02*
Y737556D01*
G01X258940Y740656D02*
X255940D01*
G01X255840Y743756D02*
X259040D01*
G01X248361Y746921D02*
X248206Y746691D01*
X248103Y746423D01*
Y746116D01*
X248258Y745771D01*
X248516Y745503D01*
X248826Y745311D01*
X249343Y745158D01*
X249808Y745120D01*
X250273Y745196D01*
X250583Y745311D01*
X250893Y745541D01*
X251100Y745810D01*
X251203Y746078D01*
Y746346D01*
X251100Y746615D01*
X250945Y746845D01*
X250738Y747036D01*
G01X249911Y748450D02*
X249550Y748718D01*
X249343Y748948D01*
X249240Y749255D01*
X249343Y749523D01*
X249550Y749715D01*
X249860Y749868D01*
X250221Y749906D01*
X250531Y749868D01*
X250841Y749715D01*
X251100Y749485D01*
X251203Y749216D01*
X251100Y748910D01*
X250790Y748641D01*
X250325Y748488D01*
X249808Y748450D01*
X249136Y748526D01*
X248775Y748641D01*
X248413Y748833D01*
X248155Y749101D01*
X248103Y749370D01*
X248206Y749638D01*
X248465Y749830D01*
G01X250841Y751626D02*
X251100Y751895D01*
X251203Y752201D01*
X251100Y752508D01*
X250790Y752776D01*
X250325Y752968D01*
X249860Y753045D01*
X249291D01*
X248826Y752968D01*
X248413Y752776D01*
X248206Y752546D01*
X248103Y752278D01*
X248206Y751971D01*
X248413Y751741D01*
X248723Y751588D01*
X249136Y751511D01*
X249498Y751588D01*
X249860Y751780D01*
X250066Y752010D01*
X250118Y752278D01*
X250015Y752585D01*
X249756Y752815D01*
X249291Y753045D01*
G01X251203Y755838D02*
X248103D01*
X250325Y754420D01*
Y756336D01*
G01X249940Y740656D02*
X246940D01*
G01X246840Y743756D02*
X250040D01*
G01X246968Y745311D02*
X243868D01*
Y746270D01*
X244023Y746576D01*
X244230Y746768D01*
X244643Y746845D01*
X245056Y746768D01*
X245315Y746538D01*
X245470Y746270D01*
Y745311D01*
G01Y746270D02*
X246968Y746845D01*
G01X246606Y748526D02*
X246865Y748795D01*
X246968Y749101D01*
X246865Y749408D01*
X246555Y749676D01*
X246090Y749868D01*
X245625Y749945D01*
X245056D01*
X244591Y749868D01*
X244178Y749676D01*
X243971Y749446D01*
X243868Y749178D01*
X243971Y748871D01*
X244178Y748641D01*
X244488Y748488D01*
X244901Y748411D01*
X245263Y748488D01*
X245625Y748680D01*
X245831Y748910D01*
X245883Y749178D01*
X245780Y749485D01*
X245521Y749715D01*
X245056Y749945D01*
G01X246348Y751435D02*
X246710Y751665D01*
X246916Y751971D01*
X246968Y752316D01*
X246916Y752623D01*
X246658Y752930D01*
X246348Y753121D01*
X246038Y753160D01*
X245676Y753083D01*
X245418Y752815D01*
X245315Y752546D01*
Y752201D01*
G01Y752546D02*
X245160Y752776D01*
X244901Y752968D01*
X244591Y753045D01*
X244281Y752968D01*
X244023Y752776D01*
X243868Y752431D01*
X243920Y752086D01*
X244126Y751741D01*
G01X246968Y755838D02*
X243868D01*
X246090Y754420D01*
Y756336D01*
G01X251341Y743756D02*
X254539D01*
G01X255642Y745311D02*
X252542D01*
Y746270D01*
X252697Y746576D01*
X252904Y746768D01*
X253317Y746845D01*
X253730Y746768D01*
X253989Y746538D01*
X254144Y746270D01*
Y745311D01*
G01Y746270D02*
X255642Y746845D01*
G01Y749178D02*
X255590Y749446D01*
X255435Y749753D01*
X255177Y749945D01*
X254815Y750021D01*
X254454Y749945D01*
X254144Y749715D01*
X253989Y749370D01*
Y748986D01*
X253885Y748756D01*
X253627Y748565D01*
X253265Y748488D01*
X252904Y748603D01*
X252645Y748871D01*
X252542Y749178D01*
X252645Y749485D01*
X252904Y749753D01*
X253265Y749868D01*
X253627Y749791D01*
X253885Y749600D01*
X253989Y749370D01*
Y748986D01*
X254144Y748641D01*
X254454Y748411D01*
X254815Y748335D01*
X255177Y748411D01*
X255435Y748603D01*
X255590Y748910D01*
X255642Y749178D01*
G01Y752278D02*
X255590Y752546D01*
X255435Y752853D01*
X255177Y753045D01*
X254815Y753121D01*
X254454Y753045D01*
X254144Y752815D01*
X253989Y752470D01*
Y752086D01*
X253885Y751856D01*
X253627Y751665D01*
X253265Y751588D01*
X252904Y751703D01*
X252645Y751971D01*
X252542Y752278D01*
X252645Y752585D01*
X252904Y752853D01*
X253265Y752968D01*
X253627Y752891D01*
X253885Y752700D01*
X253989Y752470D01*
Y752086D01*
X254144Y751741D01*
X254454Y751511D01*
X254815Y751435D01*
X255177Y751511D01*
X255435Y751703D01*
X255590Y752010D01*
X255642Y752278D01*
G01X252542Y755378D02*
X252645Y755071D01*
X252904Y754841D01*
X253214Y754688D01*
X253627Y754573D01*
X254092Y754535D01*
X254557Y754573D01*
X254970Y754688D01*
X255280Y754841D01*
X255539Y755071D01*
X255642Y755378D01*
X255539Y755685D01*
X255280Y755915D01*
X254970Y756068D01*
X254557Y756183D01*
X254092Y756221D01*
X253627Y756183D01*
X253214Y756068D01*
X252904Y755915D01*
X252645Y755685D01*
X252542Y755378D01*
G01X260237Y745311D02*
X257137D01*
Y746270D01*
X257292Y746576D01*
X257499Y746768D01*
X257912Y746845D01*
X258325Y746768D01*
X258584Y746538D01*
X258739Y746270D01*
Y745311D01*
G01Y746270D02*
X260237Y746845D01*
G01Y749178D02*
X260185Y749446D01*
X260030Y749753D01*
X259772Y749945D01*
X259410Y750021D01*
X259049Y749945D01*
X258739Y749715D01*
X258584Y749370D01*
Y748986D01*
X258480Y748756D01*
X258222Y748565D01*
X257860Y748488D01*
X257499Y748603D01*
X257240Y748871D01*
X257137Y749178D01*
X257240Y749485D01*
X257499Y749753D01*
X257860Y749868D01*
X258222Y749791D01*
X258480Y749600D01*
X258584Y749370D01*
Y748986D01*
X258739Y748641D01*
X259049Y748411D01*
X259410Y748335D01*
X259772Y748411D01*
X260030Y748603D01*
X260185Y748910D01*
X260237Y749178D01*
G01Y752201D02*
X259565Y752278D01*
X258997Y752393D01*
X258480Y752546D01*
X257912Y752738D01*
X257137Y753045D01*
Y751511D01*
G01X260237Y755301D02*
X259565Y755378D01*
X258997Y755493D01*
X258480Y755646D01*
X257912Y755838D01*
X257137Y756145D01*
Y754611D01*
G01X254743Y760558D02*
X254588Y760328D01*
X254485Y760060D01*
Y759753D01*
X254640Y759408D01*
X254898Y759140D01*
X255208Y758948D01*
X255725Y758795D01*
X256190Y758757D01*
X256655Y758833D01*
X256965Y758948D01*
X257275Y759178D01*
X257482Y759447D01*
X257585Y759715D01*
Y759983D01*
X257482Y760252D01*
X257327Y760482D01*
X257120Y760673D01*
G01X256293Y762087D02*
X255932Y762355D01*
X255725Y762585D01*
X255622Y762892D01*
X255725Y763160D01*
X255932Y763352D01*
X256242Y763505D01*
X256603Y763543D01*
X256913Y763505D01*
X257223Y763352D01*
X257482Y763122D01*
X257585Y762853D01*
X257482Y762547D01*
X257172Y762278D01*
X256707Y762125D01*
X256190Y762087D01*
X255518Y762163D01*
X255157Y762278D01*
X254795Y762470D01*
X254537Y762738D01*
X254485Y763007D01*
X254588Y763275D01*
X254847Y763467D01*
G01X257585Y766375D02*
X254485D01*
X256707Y764957D01*
Y766873D01*
G01X256965Y768172D02*
X257327Y768402D01*
X257533Y768708D01*
X257585Y769053D01*
X257533Y769360D01*
X257275Y769667D01*
X256965Y769858D01*
X256655Y769897D01*
X256293Y769820D01*
X256035Y769552D01*
X255932Y769283D01*
Y768938D01*
G01Y769283D02*
X255777Y769513D01*
X255518Y769705D01*
X255208Y769782D01*
X254898Y769705D01*
X254640Y769513D01*
X254485Y769168D01*
X254537Y768823D01*
X254743Y768478D01*
G01X246916Y760558D02*
X246761Y760328D01*
X246658Y760060D01*
Y759753D01*
X246813Y759408D01*
X247071Y759140D01*
X247381Y758948D01*
X247898Y758795D01*
X248363Y758757D01*
X248828Y758833D01*
X249138Y758948D01*
X249448Y759178D01*
X249655Y759447D01*
X249758Y759715D01*
Y759983D01*
X249655Y760252D01*
X249500Y760482D01*
X249293Y760673D01*
G01X248466Y762087D02*
X248105Y762355D01*
X247898Y762585D01*
X247795Y762892D01*
X247898Y763160D01*
X248105Y763352D01*
X248415Y763505D01*
X248776Y763543D01*
X249086Y763505D01*
X249396Y763352D01*
X249655Y763122D01*
X249758Y762853D01*
X249655Y762547D01*
X249345Y762278D01*
X248880Y762125D01*
X248363Y762087D01*
X247691Y762163D01*
X247330Y762278D01*
X246968Y762470D01*
X246710Y762738D01*
X246658Y763007D01*
X246761Y763275D01*
X247020Y763467D01*
G01X249396Y765263D02*
X249655Y765532D01*
X249758Y765838D01*
X249655Y766145D01*
X249345Y766413D01*
X248880Y766605D01*
X248415Y766682D01*
X247846D01*
X247381Y766605D01*
X246968Y766413D01*
X246761Y766183D01*
X246658Y765915D01*
X246761Y765608D01*
X246968Y765378D01*
X247278Y765225D01*
X247691Y765148D01*
X248053Y765225D01*
X248415Y765417D01*
X248621Y765647D01*
X248673Y765915D01*
X248570Y766222D01*
X248311Y766452D01*
X247846Y766682D01*
G01X249758Y768938D02*
X249086Y769015D01*
X248518Y769130D01*
X248001Y769283D01*
X247433Y769475D01*
X246658Y769782D01*
Y768248D01*
G01X258743Y760558D02*
X258588Y760328D01*
X258485Y760060D01*
Y759753D01*
X258640Y759408D01*
X258898Y759140D01*
X259208Y758948D01*
X259725Y758795D01*
X260190Y758757D01*
X260655Y758833D01*
X260965Y758948D01*
X261275Y759178D01*
X261482Y759447D01*
X261585Y759715D01*
Y759983D01*
X261482Y760252D01*
X261327Y760482D01*
X261120Y760673D01*
G01X260293Y762087D02*
X259932Y762355D01*
X259725Y762585D01*
X259622Y762892D01*
X259725Y763160D01*
X259932Y763352D01*
X260242Y763505D01*
X260603Y763543D01*
X260913Y763505D01*
X261223Y763352D01*
X261482Y763122D01*
X261585Y762853D01*
X261482Y762547D01*
X261172Y762278D01*
X260707Y762125D01*
X260190Y762087D01*
X259518Y762163D01*
X259157Y762278D01*
X258795Y762470D01*
X258537Y762738D01*
X258485Y763007D01*
X258588Y763275D01*
X258847Y763467D01*
G01X261585Y766375D02*
X258485D01*
X260707Y764957D01*
Y766873D01*
G01X258485Y769015D02*
X258588Y768708D01*
X258847Y768478D01*
X259157Y768325D01*
X259570Y768210D01*
X260035Y768172D01*
X260500Y768210D01*
X260913Y768325D01*
X261223Y768478D01*
X261482Y768708D01*
X261585Y769015D01*
X261482Y769322D01*
X261223Y769552D01*
X260913Y769705D01*
X260500Y769820D01*
X260035Y769858D01*
X259570Y769820D01*
X259157Y769705D01*
X258847Y769552D01*
X258588Y769322D01*
X258485Y769015D01*
G01X253758Y758948D02*
X250658D01*
Y759907D01*
X250813Y760213D01*
X251020Y760405D01*
X251433Y760482D01*
X251846Y760405D01*
X252105Y760175D01*
X252260Y759907D01*
Y758948D01*
G01Y759907D02*
X253758Y760482D01*
G01X253396Y762163D02*
X253655Y762432D01*
X253758Y762738D01*
X253655Y763045D01*
X253345Y763313D01*
X252880Y763505D01*
X252415Y763582D01*
X251846D01*
X251381Y763505D01*
X250968Y763313D01*
X250761Y763083D01*
X250658Y762815D01*
X250761Y762508D01*
X250968Y762278D01*
X251278Y762125D01*
X251691Y762048D01*
X252053Y762125D01*
X252415Y762317D01*
X252621Y762547D01*
X252673Y762815D01*
X252570Y763122D01*
X252311Y763352D01*
X251846Y763582D01*
G01X253138Y765072D02*
X253500Y765302D01*
X253706Y765608D01*
X253758Y765953D01*
X253706Y766260D01*
X253448Y766567D01*
X253138Y766758D01*
X252828Y766797D01*
X252466Y766720D01*
X252208Y766452D01*
X252105Y766183D01*
Y765838D01*
G01Y766183D02*
X251950Y766413D01*
X251691Y766605D01*
X251381Y766682D01*
X251071Y766605D01*
X250813Y766413D01*
X250658Y766068D01*
X250710Y765723D01*
X250916Y765378D01*
G01X253758Y769015D02*
X250658D01*
X251278Y768555D01*
G01X253758D02*
Y769475D01*
G01X269021Y14691D02*
Y8491D01*
G01D02*
X265821D01*
G01D02*
Y14691D01*
G01X269821Y8491D02*
Y14691D01*
G01X273021D02*
Y8491D01*
G01D02*
X269821D01*
G01X273131Y1143D02*
Y4243D01*
X274090D01*
X274396Y4088D01*
X274588Y3881D01*
X274665Y3468D01*
X274588Y3055D01*
X274358Y2796D01*
X274090Y2641D01*
X273131D01*
G01X274090D02*
X274665Y1143D01*
G01X276998D02*
Y4243D01*
X276538Y3623D01*
G01Y1143D02*
X277458D01*
G01X279370Y3726D02*
X279600Y4036D01*
X279868Y4191D01*
X280175Y4243D01*
X280558Y4140D01*
X280826Y3881D01*
X280903Y3571D01*
X280865Y3261D01*
X280711Y3003D01*
X279945Y2486D01*
X279600Y2125D01*
X279370Y1608D01*
X279293Y1143D01*
X280903D01*
G01X282355Y1763D02*
X282585Y1401D01*
X282891Y1195D01*
X283236Y1143D01*
X283543Y1195D01*
X283850Y1453D01*
X284041Y1763D01*
X284080Y2073D01*
X284003Y2435D01*
X283735Y2693D01*
X283466Y2796D01*
X283121D01*
G01X283466D02*
X283696Y2951D01*
X283888Y3210D01*
X283965Y3520D01*
X283888Y3830D01*
X283696Y4088D01*
X283351Y4243D01*
X283006Y4191D01*
X282661Y3985D01*
G01X286221Y1143D02*
X286298Y1815D01*
X286413Y2383D01*
X286566Y2900D01*
X286758Y3468D01*
X287065Y4243D01*
X285531D01*
G01X273978Y8236D02*
X280178D01*
G01X273978Y5036D02*
Y8236D01*
G01X280178Y5036D02*
X273978D01*
G01X265300Y1183D02*
X262200D01*
Y2103D01*
X262355Y2410D01*
X262717Y2640D01*
X263130Y2717D01*
X263543Y2640D01*
X263853Y2448D01*
X264008Y2103D01*
Y1183D01*
G01X264680Y4283D02*
X264990Y4475D01*
X265197Y4705D01*
X265300Y4973D01*
X265197Y5280D01*
X264990Y5510D01*
X264680Y5740D01*
X264267Y5817D01*
X262200D01*
G01X264835Y7307D02*
X265093Y7537D01*
X265248Y7805D01*
X265300Y8150D01*
X265197Y8495D01*
X264990Y8763D01*
X264628Y8955D01*
X264215Y8993D01*
X263802Y8917D01*
X263543Y8725D01*
X263337Y8457D01*
X263285Y8188D01*
X263337Y7920D01*
X263543Y7575D01*
X262200Y7690D01*
Y8725D01*
G01X270423Y16258D02*
X270583Y16050D01*
X270770Y15925D01*
X271010Y15883D01*
X271250Y15966D01*
X271437Y16133D01*
X271570Y16425D01*
X271597Y16758D01*
X271543Y17091D01*
X271410Y17300D01*
X271223Y17466D01*
X271037Y17508D01*
X270850Y17466D01*
X270610Y17300D01*
X270690Y18383D01*
X271410D01*
G01X269773Y21079D02*
Y19178D01*
G01D02*
X271674D01*
G01X273021Y17332D02*
Y16132D01*
G01X269773Y31580D02*
Y29479D01*
G01X264785Y26532D02*
Y23332D01*
G01X261685Y23432D02*
Y26432D01*
G01X264889Y21216D02*
Y15016D01*
G01D02*
X261689D01*
G01D02*
Y21216D01*
G01D02*
X264889D01*
G01X261789Y18116D02*
X264789D01*
G01X264348Y30829D02*
Y27629D01*
G01X265821Y14691D02*
X269021D01*
G01X269821D02*
X273021D01*
G01X268762Y31878D02*
Y34378D01*
X268442Y33878D01*
G01Y31878D02*
X269082D01*
G01X270455Y32920D02*
X270642Y33211D01*
X270802Y33378D01*
X271015Y33461D01*
X271202Y33378D01*
X271335Y33211D01*
X271442Y32961D01*
X271469Y32670D01*
X271442Y32420D01*
X271335Y32170D01*
X271175Y31961D01*
X270989Y31878D01*
X270775Y31961D01*
X270589Y32211D01*
X270482Y32586D01*
X270455Y33003D01*
X270509Y33545D01*
X270589Y33836D01*
X270722Y34128D01*
X270909Y34336D01*
X271095Y34378D01*
X271282Y34295D01*
X271415Y34086D01*
G01X271774Y31580D02*
X269773D01*
G01X264877Y35072D02*
Y31872D01*
G01D02*
X258677D01*
G01D02*
Y35072D01*
G01D02*
X264877D01*
G01X261777Y34972D02*
Y31972D01*
G01X271924Y42234D02*
X268824D01*
Y43154D01*
X268979Y43461D01*
X269341Y43691D01*
X269754Y43768D01*
X270167Y43691D01*
X270477Y43499D01*
X270632Y43154D01*
Y42234D01*
G01X269082Y46944D02*
X268927Y46714D01*
X268824Y46446D01*
Y46139D01*
X268979Y45794D01*
X269237Y45526D01*
X269547Y45334D01*
X270064Y45181D01*
X270529Y45143D01*
X270994Y45219D01*
X271304Y45334D01*
X271614Y45564D01*
X271821Y45833D01*
X271924Y46101D01*
Y46369D01*
X271821Y46638D01*
X271666Y46868D01*
X271459Y47059D01*
G01X271924Y49661D02*
X268824D01*
X271046Y48243D01*
Y50159D01*
G01X270632Y51573D02*
X270271Y51841D01*
X270064Y52071D01*
X269961Y52378D01*
X270064Y52646D01*
X270271Y52838D01*
X270581Y52991D01*
X270942Y53029D01*
X271252Y52991D01*
X271562Y52838D01*
X271821Y52608D01*
X271924Y52339D01*
X271821Y52033D01*
X271511Y51764D01*
X271046Y51611D01*
X270529Y51573D01*
X269857Y51649D01*
X269496Y51764D01*
X269134Y51956D01*
X268876Y52224D01*
X268824Y52493D01*
X268927Y52761D01*
X269186Y52953D01*
G01X266958Y35853D02*
Y39053D01*
G01X273158Y35853D02*
X266958D01*
G01X273158Y39053D02*
Y35853D01*
G01X266958Y39053D02*
X273158D01*
G01X270058Y35953D02*
Y38953D01*
G01X264877Y39029D02*
Y35829D01*
G01D02*
X258677D01*
G01D02*
Y39029D01*
G01D02*
X264877D01*
G01X262485Y63159D02*
X262330Y62929D01*
X262227Y62661D01*
Y62354D01*
X262382Y62009D01*
X262640Y61741D01*
X262950Y61549D01*
X263467Y61396D01*
X263932Y61358D01*
X264397Y61434D01*
X264707Y61549D01*
X265017Y61779D01*
X265224Y62048D01*
X265327Y62316D01*
Y62584D01*
X265224Y62853D01*
X265069Y63083D01*
X264862Y63274D01*
G01X265327Y65416D02*
X262227D01*
X262847Y64956D01*
G01X265327D02*
Y65876D01*
G01X264035Y67788D02*
X263674Y68056D01*
X263467Y68286D01*
X263364Y68593D01*
X263467Y68861D01*
X263674Y69053D01*
X263984Y69206D01*
X264345Y69244D01*
X264655Y69206D01*
X264965Y69053D01*
X265224Y68823D01*
X265327Y68554D01*
X265224Y68248D01*
X264914Y67979D01*
X264449Y67826D01*
X263932Y67788D01*
X263260Y67864D01*
X262899Y67979D01*
X262537Y68171D01*
X262279Y68439D01*
X262227Y68708D01*
X262330Y68976D01*
X262589Y69168D01*
G01X265327Y71616D02*
X262227D01*
X262847Y71156D01*
G01X265327D02*
Y72076D01*
G01X269587Y72704D02*
Y66504D01*
G01X266387Y72704D02*
X269587D01*
G01X269487Y69604D02*
X266487D01*
G01X266387Y66504D02*
Y72704D01*
G01X269587Y66504D02*
X266387D01*
G01X270387Y72704D02*
X273587D01*
G01X273487Y69604D02*
X270487D01*
G01X270387Y66504D02*
Y72704D01*
G01X273587D02*
Y66504D01*
G01D02*
X270387D01*
G01X272033Y168320D02*
X268933D01*
Y169279D01*
X269088Y169585D01*
X269295Y169777D01*
X269708Y169854D01*
X270121Y169777D01*
X270380Y169547D01*
X270535Y169279D01*
Y168320D01*
G01Y169279D02*
X272033Y169854D01*
G01X269450Y171459D02*
X269140Y171689D01*
X268985Y171957D01*
X268933Y172264D01*
X269036Y172647D01*
X269295Y172915D01*
X269605Y172992D01*
X269915Y172954D01*
X270173Y172800D01*
X270690Y172034D01*
X271051Y171689D01*
X271568Y171459D01*
X272033Y171382D01*
Y172992D01*
G01X271671Y174635D02*
X271930Y174904D01*
X272033Y175210D01*
X271930Y175517D01*
X271620Y175785D01*
X271155Y175977D01*
X270690Y176054D01*
X270121D01*
X269656Y175977D01*
X269243Y175785D01*
X269036Y175555D01*
X268933Y175287D01*
X269036Y174980D01*
X269243Y174750D01*
X269553Y174597D01*
X269966Y174520D01*
X270328Y174597D01*
X270690Y174789D01*
X270896Y175019D01*
X270948Y175287D01*
X270845Y175594D01*
X270586Y175824D01*
X270121Y176054D01*
G01X270741Y177659D02*
X270380Y177927D01*
X270173Y178157D01*
X270070Y178464D01*
X270173Y178732D01*
X270380Y178924D01*
X270690Y179077D01*
X271051Y179115D01*
X271361Y179077D01*
X271671Y178924D01*
X271930Y178694D01*
X272033Y178425D01*
X271930Y178119D01*
X271620Y177850D01*
X271155Y177697D01*
X270638Y177659D01*
X269966Y177735D01*
X269605Y177850D01*
X269243Y178042D01*
X268985Y178310D01*
X268933Y178579D01*
X269036Y178847D01*
X269295Y179039D01*
G01X264033Y168320D02*
X260933D01*
Y169279D01*
X261088Y169585D01*
X261295Y169777D01*
X261708Y169854D01*
X262121Y169777D01*
X262380Y169547D01*
X262535Y169279D01*
Y168320D01*
G01Y169279D02*
X264033Y169854D01*
G01X261450Y171459D02*
X261140Y171689D01*
X260985Y171957D01*
X260933Y172264D01*
X261036Y172647D01*
X261295Y172915D01*
X261605Y172992D01*
X261915Y172954D01*
X262173Y172800D01*
X262690Y172034D01*
X263051Y171689D01*
X263568Y171459D01*
X264033Y171382D01*
Y172992D01*
G01X263671Y174635D02*
X263930Y174904D01*
X264033Y175210D01*
X263930Y175517D01*
X263620Y175785D01*
X263155Y175977D01*
X262690Y176054D01*
X262121D01*
X261656Y175977D01*
X261243Y175785D01*
X261036Y175555D01*
X260933Y175287D01*
X261036Y174980D01*
X261243Y174750D01*
X261553Y174597D01*
X261966Y174520D01*
X262328Y174597D01*
X262690Y174789D01*
X262896Y175019D01*
X262948Y175287D01*
X262845Y175594D01*
X262586Y175824D01*
X262121Y176054D01*
G01X263568Y177544D02*
X263826Y177774D01*
X263981Y178042D01*
X264033Y178387D01*
X263930Y178732D01*
X263723Y179000D01*
X263361Y179192D01*
X262948Y179230D01*
X262535Y179154D01*
X262276Y178962D01*
X262070Y178694D01*
X262018Y178425D01*
X262070Y178157D01*
X262276Y177812D01*
X260933Y177927D01*
Y178962D01*
G01X268033Y168320D02*
X264933D01*
Y169279D01*
X265088Y169585D01*
X265295Y169777D01*
X265708Y169854D01*
X266121Y169777D01*
X266380Y169547D01*
X266535Y169279D01*
Y168320D01*
G01Y169279D02*
X268033Y169854D01*
G01X265450Y171459D02*
X265140Y171689D01*
X264985Y171957D01*
X264933Y172264D01*
X265036Y172647D01*
X265295Y172915D01*
X265605Y172992D01*
X265915Y172954D01*
X266173Y172800D01*
X266690Y172034D01*
X267051Y171689D01*
X267568Y171459D01*
X268033Y171382D01*
Y172992D01*
G01Y175287D02*
X267981Y175555D01*
X267826Y175862D01*
X267568Y176054D01*
X267206Y176130D01*
X266845Y176054D01*
X266535Y175824D01*
X266380Y175479D01*
Y175095D01*
X266276Y174865D01*
X266018Y174674D01*
X265656Y174597D01*
X265295Y174712D01*
X265036Y174980D01*
X264933Y175287D01*
X265036Y175594D01*
X265295Y175862D01*
X265656Y175977D01*
X266018Y175900D01*
X266276Y175709D01*
X266380Y175479D01*
Y175095D01*
X266535Y174750D01*
X266845Y174520D01*
X267206Y174444D01*
X267568Y174520D01*
X267826Y174712D01*
X267981Y175019D01*
X268033Y175287D01*
G01X267413Y177544D02*
X267775Y177774D01*
X267981Y178080D01*
X268033Y178425D01*
X267981Y178732D01*
X267723Y179039D01*
X267413Y179230D01*
X267103Y179269D01*
X266741Y179192D01*
X266483Y178924D01*
X266380Y178655D01*
Y178310D01*
G01Y178655D02*
X266225Y178885D01*
X265966Y179077D01*
X265656Y179154D01*
X265346Y179077D01*
X265088Y178885D01*
X264933Y178540D01*
X264985Y178195D01*
X265191Y177850D01*
G01X269968Y180329D02*
Y183429D01*
X270927D01*
X271233Y183274D01*
X271425Y183067D01*
X271502Y182654D01*
X271425Y182241D01*
X271195Y181982D01*
X270927Y181827D01*
X269968D01*
G01X270927D02*
X271502Y180329D01*
G01X273835D02*
Y183429D01*
X273375Y182809D01*
G01Y180329D02*
X274295D01*
G01X276207Y182912D02*
X276437Y183222D01*
X276705Y183377D01*
X277012Y183429D01*
X277395Y183326D01*
X277663Y183067D01*
X277740Y182757D01*
X277702Y182447D01*
X277548Y182189D01*
X276782Y181672D01*
X276437Y181311D01*
X276207Y180794D01*
X276130Y180329D01*
X277740D01*
G01X280035D02*
X280303Y180381D01*
X280610Y180536D01*
X280802Y180794D01*
X280878Y181156D01*
X280802Y181517D01*
X280572Y181827D01*
X280227Y181982D01*
X279843D01*
X279613Y182086D01*
X279422Y182344D01*
X279345Y182706D01*
X279460Y183067D01*
X279728Y183326D01*
X280035Y183429D01*
X280342Y183326D01*
X280610Y183067D01*
X280725Y182706D01*
X280648Y182344D01*
X280457Y182086D01*
X280227Y181982D01*
X279843D01*
X279498Y181827D01*
X279268Y181517D01*
X279192Y181156D01*
X279268Y180794D01*
X279460Y180536D01*
X279767Y180381D01*
X280035Y180329D01*
G01X283595D02*
Y183429D01*
X282177Y181207D01*
X284093D01*
G01X273088Y174439D02*
Y177539D01*
X274047D01*
X274353Y177384D01*
X274545Y177177D01*
X274622Y176764D01*
X274545Y176351D01*
X274315Y176092D01*
X274047Y175937D01*
X273088D01*
G01X274047D02*
X274622Y174439D01*
G01X276227Y177022D02*
X276457Y177332D01*
X276725Y177487D01*
X277032Y177539D01*
X277415Y177436D01*
X277683Y177177D01*
X277760Y176867D01*
X277722Y176557D01*
X277568Y176299D01*
X276802Y175782D01*
X276457Y175421D01*
X276227Y174904D01*
X276150Y174439D01*
X277760D01*
G01X279403Y174801D02*
X279672Y174542D01*
X279978Y174439D01*
X280285Y174542D01*
X280553Y174852D01*
X280745Y175317D01*
X280822Y175782D01*
Y176351D01*
X280745Y176816D01*
X280553Y177229D01*
X280323Y177436D01*
X280055Y177539D01*
X279748Y177436D01*
X279518Y177229D01*
X279365Y176919D01*
X279288Y176506D01*
X279365Y176144D01*
X279557Y175782D01*
X279787Y175576D01*
X280055Y175524D01*
X280362Y175627D01*
X280592Y175886D01*
X280822Y176351D01*
G01X283078Y174439D02*
X283155Y175111D01*
X283270Y175679D01*
X283423Y176196D01*
X283615Y176764D01*
X283922Y177539D01*
X282388D01*
G01X263399Y201254D02*
Y204354D01*
X264358D01*
X264664Y204199D01*
X264856Y203992D01*
X264933Y203579D01*
X264856Y203166D01*
X264626Y202907D01*
X264358Y202752D01*
X263399D01*
G01X264358D02*
X264933Y201254D01*
G01X266538Y202546D02*
X266806Y202907D01*
X267036Y203114D01*
X267343Y203217D01*
X267611Y203114D01*
X267803Y202907D01*
X267956Y202597D01*
X267994Y202236D01*
X267956Y201926D01*
X267803Y201616D01*
X267573Y201357D01*
X267304Y201254D01*
X266998Y201357D01*
X266729Y201667D01*
X266576Y202132D01*
X266538Y202649D01*
X266614Y203321D01*
X266729Y203682D01*
X266921Y204044D01*
X267189Y204302D01*
X267458Y204354D01*
X267726Y204251D01*
X267918Y203992D01*
G01X270826Y201254D02*
Y204354D01*
X269408Y202132D01*
X271324D01*
G01X273466Y201254D02*
X273734Y201306D01*
X274041Y201461D01*
X274233Y201719D01*
X274309Y202081D01*
X274233Y202442D01*
X274003Y202752D01*
X273658Y202907D01*
X273274D01*
X273044Y203011D01*
X272853Y203269D01*
X272776Y203631D01*
X272891Y203992D01*
X273159Y204251D01*
X273466Y204354D01*
X273773Y204251D01*
X274041Y203992D01*
X274156Y203631D01*
X274079Y203269D01*
X273888Y203011D01*
X273658Y202907D01*
X273274D01*
X272929Y202752D01*
X272699Y202442D01*
X272623Y202081D01*
X272699Y201719D01*
X272891Y201461D01*
X273198Y201306D01*
X273466Y201254D01*
G01X259112Y188623D02*
X261334D01*
X261799Y188776D01*
X262109Y189083D01*
X262212Y189466D01*
X262109Y189849D01*
X261799Y190156D01*
X261334Y190309D01*
X259112D01*
G01X262212Y192566D02*
X259112D01*
X259732Y192106D01*
G01X262212D02*
Y193026D01*
G01Y195666D02*
X259112D01*
X259732Y195206D01*
G01X262212D02*
Y196126D01*
G01X260920Y198038D02*
X260559Y198306D01*
X260352Y198536D01*
X260249Y198843D01*
X260352Y199111D01*
X260559Y199303D01*
X260869Y199456D01*
X261230Y199494D01*
X261540Y199456D01*
X261850Y199303D01*
X262109Y199073D01*
X262212Y198804D01*
X262109Y198498D01*
X261799Y198229D01*
X261334Y198076D01*
X260817Y198038D01*
X260145Y198114D01*
X259784Y198229D01*
X259422Y198421D01*
X259164Y198689D01*
X259112Y198958D01*
X259215Y199226D01*
X259474Y199418D01*
G01X268766Y189582D02*
X270988D01*
X271453Y189735D01*
X271763Y190042D01*
X271866Y190425D01*
X271763Y190808D01*
X271453Y191115D01*
X270988Y191268D01*
X268766D01*
G01X271866Y193525D02*
X268766D01*
X269386Y193065D01*
G01X271866D02*
Y193985D01*
G01X271246Y195782D02*
X271608Y196012D01*
X271814Y196318D01*
X271866Y196663D01*
X271814Y196970D01*
X271556Y197277D01*
X271246Y197468D01*
X270936Y197507D01*
X270574Y197430D01*
X270316Y197162D01*
X270213Y196893D01*
Y196548D01*
G01Y196893D02*
X270058Y197123D01*
X269799Y197315D01*
X269489Y197392D01*
X269179Y197315D01*
X268921Y197123D01*
X268766Y196778D01*
X268818Y196433D01*
X269024Y196088D01*
G01X271504Y199073D02*
X271763Y199342D01*
X271866Y199648D01*
X271763Y199955D01*
X271453Y200223D01*
X270988Y200415D01*
X270523Y200492D01*
X269954D01*
X269489Y200415D01*
X269076Y200223D01*
X268869Y199993D01*
X268766Y199725D01*
X268869Y199418D01*
X269076Y199188D01*
X269386Y199035D01*
X269799Y198958D01*
X270161Y199035D01*
X270523Y199227D01*
X270729Y199457D01*
X270781Y199725D01*
X270678Y200032D01*
X270419Y200262D01*
X269954Y200492D01*
G01X263529Y205045D02*
Y208145D01*
X264488D01*
X264794Y207990D01*
X264986Y207783D01*
X265063Y207370D01*
X264986Y206957D01*
X264756Y206698D01*
X264488Y206543D01*
X263529D01*
G01X264488D02*
X265063Y205045D01*
G01X266668Y206337D02*
X266936Y206698D01*
X267166Y206905D01*
X267473Y207008D01*
X267741Y206905D01*
X267933Y206698D01*
X268086Y206388D01*
X268124Y206027D01*
X268086Y205717D01*
X267933Y205407D01*
X267703Y205148D01*
X267434Y205045D01*
X267128Y205148D01*
X266859Y205458D01*
X266706Y205923D01*
X266668Y206440D01*
X266744Y207112D01*
X266859Y207473D01*
X267051Y207835D01*
X267319Y208093D01*
X267588Y208145D01*
X267856Y208042D01*
X268048Y207783D01*
G01X269768Y206337D02*
X270036Y206698D01*
X270266Y206905D01*
X270573Y207008D01*
X270841Y206905D01*
X271033Y206698D01*
X271186Y206388D01*
X271224Y206027D01*
X271186Y205717D01*
X271033Y205407D01*
X270803Y205148D01*
X270534Y205045D01*
X270228Y205148D01*
X269959Y205458D01*
X269806Y205923D01*
X269768Y206440D01*
X269844Y207112D01*
X269959Y207473D01*
X270151Y207835D01*
X270419Y208093D01*
X270688Y208145D01*
X270956Y208042D01*
X271148Y207783D01*
G01X272944Y205407D02*
X273213Y205148D01*
X273519Y205045D01*
X273826Y205148D01*
X274094Y205458D01*
X274286Y205923D01*
X274363Y206388D01*
Y206957D01*
X274286Y207422D01*
X274094Y207835D01*
X273864Y208042D01*
X273596Y208145D01*
X273289Y208042D01*
X273059Y207835D01*
X272906Y207525D01*
X272829Y207112D01*
X272906Y206750D01*
X273098Y206388D01*
X273328Y206182D01*
X273596Y206130D01*
X273903Y206233D01*
X274133Y206492D01*
X274363Y206957D01*
G01X258903Y360600D02*
X259063Y360392D01*
X259250Y360267D01*
X259490Y360225D01*
X259730Y360308D01*
X259917Y360475D01*
X260050Y360767D01*
X260077Y361100D01*
X260023Y361433D01*
X259890Y361642D01*
X259703Y361808D01*
X259517Y361850D01*
X259330Y361808D01*
X259090Y361642D01*
X259170Y362725D01*
X259890D01*
G01X261690D02*
X261477Y362642D01*
X261317Y362433D01*
X261210Y362183D01*
X261130Y361850D01*
X261103Y361475D01*
X261130Y361100D01*
X261210Y360767D01*
X261317Y360517D01*
X261477Y360308D01*
X261690Y360225D01*
X261903Y360308D01*
X262063Y360517D01*
X262170Y360767D01*
X262250Y361100D01*
X262277Y361475D01*
X262250Y361850D01*
X262170Y362183D01*
X262063Y362433D01*
X261903Y362642D01*
X261690Y362725D01*
G01X261162Y357131D02*
X261322Y356923D01*
X261509Y356798D01*
X261749Y356756D01*
X261989Y356839D01*
X262176Y357006D01*
X262309Y357298D01*
X262336Y357631D01*
X262282Y357964D01*
X262149Y358173D01*
X261962Y358339D01*
X261776Y358381D01*
X261589Y358339D01*
X261349Y358173D01*
X261429Y359256D01*
X262149D01*
G01X263949Y356756D02*
Y359256D01*
X263629Y358756D01*
G01Y356756D02*
X264269D01*
G01X263143Y360276D02*
X263303Y360068D01*
X263490Y359943D01*
X263730Y359901D01*
X263970Y359984D01*
X264157Y360151D01*
X264290Y360443D01*
X264317Y360776D01*
X264263Y361109D01*
X264130Y361318D01*
X263943Y361484D01*
X263757Y361526D01*
X263570Y361484D01*
X263330Y361318D01*
X263410Y362401D01*
X264130D01*
G01X265423Y361984D02*
X265583Y362234D01*
X265770Y362359D01*
X265983Y362401D01*
X266250Y362318D01*
X266437Y362109D01*
X266490Y361859D01*
X266463Y361609D01*
X266357Y361401D01*
X265823Y360984D01*
X265583Y360693D01*
X265423Y360276D01*
X265370Y359901D01*
X266490D01*
G01X264662Y357131D02*
X264822Y356923D01*
X265009Y356798D01*
X265249Y356756D01*
X265489Y356839D01*
X265676Y357006D01*
X265809Y357298D01*
X265836Y357631D01*
X265782Y357964D01*
X265649Y358173D01*
X265462Y358339D01*
X265276Y358381D01*
X265089Y358339D01*
X264849Y358173D01*
X264929Y359256D01*
X265649D01*
G01X266862Y357256D02*
X267022Y356964D01*
X267236Y356798D01*
X267476Y356756D01*
X267689Y356798D01*
X267902Y357006D01*
X268036Y357256D01*
X268062Y357506D01*
X268009Y357798D01*
X267822Y358006D01*
X267636Y358089D01*
X267396D01*
G01X267636D02*
X267796Y358214D01*
X267929Y358423D01*
X267982Y358673D01*
X267929Y358923D01*
X267796Y359131D01*
X267556Y359256D01*
X267316Y359214D01*
X267076Y359048D01*
G01X266992Y360724D02*
X267152Y360516D01*
X267339Y360391D01*
X267579Y360349D01*
X267819Y360432D01*
X268006Y360599D01*
X268139Y360891D01*
X268166Y361224D01*
X268112Y361557D01*
X267979Y361766D01*
X267792Y361932D01*
X267606Y361974D01*
X267419Y361932D01*
X267179Y361766D01*
X267259Y362849D01*
X267979D01*
G01X270099Y360349D02*
Y362849D01*
X269112Y361057D01*
X270446D01*
G01X268662Y357131D02*
X268822Y356923D01*
X269009Y356798D01*
X269249Y356756D01*
X269489Y356839D01*
X269676Y357006D01*
X269809Y357298D01*
X269836Y357631D01*
X269782Y357964D01*
X269649Y358173D01*
X269462Y358339D01*
X269276Y358381D01*
X269089Y358339D01*
X268849Y358173D01*
X268929Y359256D01*
X269649D01*
G01X270862Y357131D02*
X271022Y356923D01*
X271209Y356798D01*
X271449Y356756D01*
X271689Y356839D01*
X271876Y357006D01*
X272009Y357298D01*
X272036Y357631D01*
X271982Y357964D01*
X271849Y358173D01*
X271662Y358339D01*
X271476Y358381D01*
X271289Y358339D01*
X271049Y358173D01*
X271129Y359256D01*
X271849D01*
G01X270992Y360724D02*
X271152Y360516D01*
X271339Y360391D01*
X271579Y360349D01*
X271819Y360432D01*
X272006Y360599D01*
X272139Y360891D01*
X272166Y361224D01*
X272112Y361557D01*
X271979Y361766D01*
X271792Y361932D01*
X271606Y361974D01*
X271419Y361932D01*
X271179Y361766D01*
X271259Y362849D01*
X271979D01*
G01X273272Y361391D02*
X273459Y361682D01*
X273619Y361849D01*
X273832Y361932D01*
X274019Y361849D01*
X274152Y361682D01*
X274259Y361432D01*
X274286Y361141D01*
X274259Y360891D01*
X274152Y360641D01*
X273992Y360432D01*
X273806Y360349D01*
X273592Y360432D01*
X273406Y360682D01*
X273299Y361057D01*
X273272Y361474D01*
X273326Y362016D01*
X273406Y362307D01*
X273539Y362599D01*
X273726Y362807D01*
X273912Y362849D01*
X274099Y362766D01*
X274232Y362557D01*
G01X272162Y357131D02*
X272322Y356923D01*
X272509Y356798D01*
X272749Y356756D01*
X272989Y356839D01*
X273176Y357006D01*
X273309Y357298D01*
X273336Y357631D01*
X273282Y357964D01*
X273149Y358173D01*
X272962Y358339D01*
X272776Y358381D01*
X272589Y358339D01*
X272349Y358173D01*
X272429Y359256D01*
X273149D01*
G01X274896Y356756D02*
X274949Y357298D01*
X275029Y357756D01*
X275136Y358173D01*
X275269Y358631D01*
X275482Y359256D01*
X274416D01*
G01X267360Y384840D02*
X295320D01*
G01X267360Y392510D02*
Y384840D01*
G01X259250Y390960D02*
Y392750D01*
G01X258806Y390264D02*
Y385664D01*
G01X259129Y377648D02*
Y383848D01*
G01D02*
X262329D01*
G01D02*
Y377648D01*
G01D02*
X259129D01*
G01X274329Y383848D02*
Y377648D01*
G01X271129D02*
Y383848D01*
G01D02*
X274329D01*
G01Y377648D02*
X271129D01*
G01X266429Y392471D02*
Y389271D01*
G01D02*
X260229D01*
G01D02*
Y392471D01*
G01X266329Y383848D02*
Y377648D01*
G01D02*
X263129D01*
G01D02*
Y383848D01*
G01D02*
X266329D01*
G01X270329D02*
Y377648D01*
G01D02*
X267129D01*
G01D02*
Y383848D01*
G01D02*
X270329D01*
G01X269917Y391524D02*
X270450D01*
Y390774D01*
X270290Y390524D01*
X270104Y390357D01*
X269837Y390274D01*
X269570Y390357D01*
X269384Y390524D01*
X269224Y390774D01*
X269117Y391066D01*
X269064Y391399D01*
Y391691D01*
X269117Y391941D01*
X269224Y392232D01*
X269384Y392482D01*
X269544Y392649D01*
X269757Y392774D01*
X269944D01*
X270157Y392691D01*
X270317Y392524D01*
G01X273100Y404803D02*
X279300D01*
G01Y401603D02*
X273100D01*
G01D02*
Y404803D01*
G01X271870Y405973D02*
Y409073D01*
X272829D01*
X273135Y408918D01*
X273327Y408711D01*
X273404Y408298D01*
X273327Y407885D01*
X273097Y407626D01*
X272829Y407471D01*
X271870D01*
G01X272829D02*
X273404Y405973D01*
G01X275737D02*
Y409073D01*
X275277Y408453D01*
G01Y405973D02*
X276197D01*
G01X278837Y409073D02*
X278530Y408970D01*
X278300Y408711D01*
X278147Y408401D01*
X278032Y407988D01*
X277994Y407523D01*
X278032Y407058D01*
X278147Y406645D01*
X278300Y406335D01*
X278530Y406076D01*
X278837Y405973D01*
X279144Y406076D01*
X279374Y406335D01*
X279527Y406645D01*
X279642Y407058D01*
X279680Y407523D01*
X279642Y407988D01*
X279527Y408401D01*
X279374Y408711D01*
X279144Y408970D01*
X278837Y409073D01*
G01X281285Y406335D02*
X281554Y406076D01*
X281860Y405973D01*
X282167Y406076D01*
X282435Y406386D01*
X282627Y406851D01*
X282704Y407316D01*
Y407885D01*
X282627Y408350D01*
X282435Y408763D01*
X282205Y408970D01*
X281937Y409073D01*
X281630Y408970D01*
X281400Y408763D01*
X281247Y408453D01*
X281170Y408040D01*
X281247Y407678D01*
X281439Y407316D01*
X281669Y407110D01*
X281937Y407058D01*
X282244Y407161D01*
X282474Y407420D01*
X282704Y407885D01*
G01X284309Y408556D02*
X284539Y408866D01*
X284807Y409021D01*
X285114Y409073D01*
X285497Y408970D01*
X285765Y408711D01*
X285842Y408401D01*
X285804Y408091D01*
X285650Y407833D01*
X284884Y407316D01*
X284539Y406955D01*
X284309Y406438D01*
X284232Y405973D01*
X285842D01*
G01X279300Y393103D02*
X273100D01*
G01D02*
Y396303D01*
G01D02*
X279300D01*
G01Y397603D02*
X273100D01*
G01D02*
Y400803D01*
G01D02*
X279300D01*
G01X260229Y392471D02*
X266429D01*
G01X268778Y406541D02*
X268991Y406333D01*
X269231Y406208D01*
X269445D01*
X269658Y406333D01*
X269818Y406541D01*
X269898Y406833D01*
X269845Y407125D01*
X269711Y407375D01*
X269471Y407541D01*
X269151Y407625D01*
X268965Y407791D01*
X268885Y408083D01*
X268938Y408375D01*
X269071Y408583D01*
X269258Y408708D01*
X269445D01*
X269631Y408625D01*
X269791Y408416D01*
G01X271136Y405356D02*
Y393544D01*
G01X264298Y422504D02*
X261298D01*
G01X264398Y419404D02*
X261198D01*
G01X264398Y425604D02*
Y419404D01*
G01X261198D02*
Y425604D01*
G01X273589Y417098D02*
X273359Y417253D01*
X273091Y417356D01*
X272784D01*
X272439Y417201D01*
X272171Y416943D01*
X271979Y416633D01*
X271826Y416116D01*
X271788Y415651D01*
X271864Y415186D01*
X271979Y414876D01*
X272209Y414566D01*
X272478Y414359D01*
X272746Y414256D01*
X273014D01*
X273283Y414359D01*
X273513Y414514D01*
X273704Y414721D01*
G01X275846Y414256D02*
X276114Y414308D01*
X276421Y414463D01*
X276613Y414721D01*
X276689Y415083D01*
X276613Y415444D01*
X276383Y415754D01*
X276038Y415909D01*
X275654D01*
X275424Y416013D01*
X275233Y416271D01*
X275156Y416633D01*
X275271Y416994D01*
X275539Y417253D01*
X275846Y417356D01*
X276153Y417253D01*
X276421Y416994D01*
X276536Y416633D01*
X276459Y416271D01*
X276268Y416013D01*
X276038Y415909D01*
X275654D01*
X275309Y415754D01*
X275079Y415444D01*
X275003Y415083D01*
X275079Y414721D01*
X275271Y414463D01*
X275578Y414308D01*
X275846Y414256D01*
G01X278218Y416839D02*
X278448Y417149D01*
X278716Y417304D01*
X279023Y417356D01*
X279406Y417253D01*
X279674Y416994D01*
X279751Y416684D01*
X279713Y416374D01*
X279559Y416116D01*
X278793Y415599D01*
X278448Y415238D01*
X278218Y414721D01*
X278141Y414256D01*
X279751D01*
G01X281318Y415548D02*
X281586Y415909D01*
X281816Y416116D01*
X282123Y416219D01*
X282391Y416116D01*
X282583Y415909D01*
X282736Y415599D01*
X282774Y415238D01*
X282736Y414928D01*
X282583Y414618D01*
X282353Y414359D01*
X282084Y414256D01*
X281778Y414359D01*
X281509Y414669D01*
X281356Y415134D01*
X281318Y415651D01*
X281394Y416323D01*
X281509Y416684D01*
X281701Y417046D01*
X281969Y417304D01*
X282238Y417356D01*
X282506Y417253D01*
X282698Y416994D01*
G01X260398Y425604D02*
Y419404D01*
G01X265132Y421618D02*
X268332D01*
G01X265132Y415418D02*
Y421618D01*
G01X268332Y415418D02*
X265132D01*
G01X268332Y421618D02*
Y415418D01*
G01X271979Y410038D02*
Y413138D01*
X272938D01*
X273244Y412983D01*
X273436Y412776D01*
X273513Y412363D01*
X273436Y411950D01*
X273206Y411691D01*
X272938Y411536D01*
X271979D01*
G01X272938D02*
X273513Y410038D01*
G01X275846D02*
Y413138D01*
X275386Y412518D01*
G01Y410038D02*
X276306D01*
G01X278946Y413138D02*
X278639Y413035D01*
X278409Y412776D01*
X278256Y412466D01*
X278141Y412053D01*
X278103Y411588D01*
X278141Y411123D01*
X278256Y410710D01*
X278409Y410400D01*
X278639Y410141D01*
X278946Y410038D01*
X279253Y410141D01*
X279483Y410400D01*
X279636Y410710D01*
X279751Y411123D01*
X279789Y411588D01*
X279751Y412053D01*
X279636Y412466D01*
X279483Y412776D01*
X279253Y413035D01*
X278946Y413138D01*
G01X281394Y410400D02*
X281663Y410141D01*
X281969Y410038D01*
X282276Y410141D01*
X282544Y410451D01*
X282736Y410916D01*
X282813Y411381D01*
Y411950D01*
X282736Y412415D01*
X282544Y412828D01*
X282314Y413035D01*
X282046Y413138D01*
X281739Y413035D01*
X281509Y412828D01*
X281356Y412518D01*
X281279Y412105D01*
X281356Y411743D01*
X281548Y411381D01*
X281778Y411175D01*
X282046Y411123D01*
X282353Y411226D01*
X282583Y411485D01*
X282813Y411950D01*
G01X285146Y410038D02*
Y413138D01*
X284686Y412518D01*
G01Y410038D02*
X285606D01*
G01X261198Y425604D02*
X264398D01*
G01X265985Y436050D02*
Y440556D01*
G01X266690Y428745D02*
X265985D01*
G01D02*
Y433250D01*
G01X268859Y424938D02*
X269067Y425151D01*
X269192Y425391D01*
Y425605D01*
X269067Y425818D01*
X268859Y425978D01*
X268567Y426058D01*
X268275Y426005D01*
X268025Y425871D01*
X267859Y425631D01*
X267775Y425311D01*
X267609Y425125D01*
X267317Y425045D01*
X267025Y425098D01*
X266817Y425231D01*
X266692Y425418D01*
Y425605D01*
X266775Y425791D01*
X266984Y425951D01*
G01X264459Y440694D02*
Y428070D01*
G01X263573Y453089D02*
X263343Y453244D01*
X263075Y453347D01*
X262768D01*
X262423Y453192D01*
X262155Y452934D01*
X261963Y452624D01*
X261810Y452107D01*
X261772Y451642D01*
X261848Y451177D01*
X261963Y450867D01*
X262193Y450557D01*
X262462Y450350D01*
X262730Y450247D01*
X262998D01*
X263267Y450350D01*
X263497Y450505D01*
X263688Y450712D01*
G01X265830Y450247D02*
X266098Y450299D01*
X266405Y450454D01*
X266597Y450712D01*
X266673Y451074D01*
X266597Y451435D01*
X266367Y451745D01*
X266022Y451900D01*
X265638D01*
X265408Y452004D01*
X265217Y452262D01*
X265140Y452624D01*
X265255Y452985D01*
X265523Y453244D01*
X265830Y453347D01*
X266137Y453244D01*
X266405Y452985D01*
X266520Y452624D01*
X266443Y452262D01*
X266252Y452004D01*
X266022Y451900D01*
X265638D01*
X265293Y451745D01*
X265063Y451435D01*
X264987Y451074D01*
X265063Y450712D01*
X265255Y450454D01*
X265562Y450299D01*
X265830Y450247D01*
G01X269390D02*
Y453347D01*
X267972Y451125D01*
X269888D01*
G01X271953Y450247D02*
X272030Y450919D01*
X272145Y451487D01*
X272298Y452004D01*
X272490Y452572D01*
X272797Y453347D01*
X271263D01*
G01X273696Y449236D02*
Y444636D01*
G01X263496Y449236D02*
X273696D01*
G01Y444636D02*
X263496D01*
G01D02*
Y449236D01*
G01X268596Y444636D02*
Y449236D01*
G01X260002Y445192D02*
Y441992D01*
G01X265985Y440556D02*
X266690D01*
G01X264692Y442411D02*
X262192D01*
Y442945D01*
X262317Y443158D01*
X262484Y443318D01*
X262734Y443451D01*
X263025Y443558D01*
X263442Y443585D01*
X263859Y443558D01*
X264150Y443451D01*
X264400Y443318D01*
X264567Y443158D01*
X264692Y442945D01*
Y442411D01*
G01X276058Y458658D02*
X272958D01*
Y459617D01*
X273113Y459923D01*
X273320Y460115D01*
X273733Y460192D01*
X274146Y460115D01*
X274405Y459885D01*
X274560Y459617D01*
Y458658D01*
G01Y459617D02*
X276058Y460192D01*
G01X275438Y461682D02*
X275800Y461912D01*
X276006Y462218D01*
X276058Y462563D01*
X276006Y462870D01*
X275748Y463177D01*
X275438Y463368D01*
X275128Y463407D01*
X274766Y463330D01*
X274508Y463062D01*
X274405Y462793D01*
Y462448D01*
G01Y462793D02*
X274250Y463023D01*
X273991Y463215D01*
X273681Y463292D01*
X273371Y463215D01*
X273113Y463023D01*
X272958Y462678D01*
X273010Y462333D01*
X273216Y461988D01*
G01X273475Y464897D02*
X273165Y465127D01*
X273010Y465395D01*
X272958Y465702D01*
X273061Y466085D01*
X273320Y466353D01*
X273630Y466430D01*
X273940Y466392D01*
X274198Y466238D01*
X274715Y465472D01*
X275076Y465127D01*
X275593Y464897D01*
X276058Y464820D01*
Y466430D01*
G01X275438Y467882D02*
X275800Y468112D01*
X276006Y468418D01*
X276058Y468763D01*
X276006Y469070D01*
X275748Y469377D01*
X275438Y469568D01*
X275128Y469607D01*
X274766Y469530D01*
X274508Y469262D01*
X274405Y468993D01*
Y468648D01*
G01Y468993D02*
X274250Y469223D01*
X273991Y469415D01*
X273681Y469492D01*
X273371Y469415D01*
X273113Y469223D01*
X272958Y468878D01*
X273010Y468533D01*
X273216Y468188D01*
G01X271996Y458658D02*
X268896D01*
Y459617D01*
X269051Y459923D01*
X269258Y460115D01*
X269671Y460192D01*
X270084Y460115D01*
X270343Y459885D01*
X270498Y459617D01*
Y458658D01*
G01Y459617D02*
X271996Y460192D01*
G01X271376Y461682D02*
X271738Y461912D01*
X271944Y462218D01*
X271996Y462563D01*
X271944Y462870D01*
X271686Y463177D01*
X271376Y463368D01*
X271066Y463407D01*
X270704Y463330D01*
X270446Y463062D01*
X270343Y462793D01*
Y462448D01*
G01Y462793D02*
X270188Y463023D01*
X269929Y463215D01*
X269619Y463292D01*
X269309Y463215D01*
X269051Y463023D01*
X268896Y462678D01*
X268948Y462333D01*
X269154Y461988D01*
G01X271996Y465625D02*
X268896D01*
X269516Y465165D01*
G01X271996D02*
Y466085D01*
G01Y468725D02*
X271944Y468993D01*
X271789Y469300D01*
X271531Y469492D01*
X271169Y469568D01*
X270808Y469492D01*
X270498Y469262D01*
X270343Y468917D01*
Y468533D01*
X270239Y468303D01*
X269981Y468112D01*
X269619Y468035D01*
X269258Y468150D01*
X268999Y468418D01*
X268896Y468725D01*
X268999Y469032D01*
X269258Y469300D01*
X269619Y469415D01*
X269981Y469338D01*
X270239Y469147D01*
X270343Y468917D01*
Y468533D01*
X270498Y468188D01*
X270808Y467958D01*
X271169Y467882D01*
X271531Y467958D01*
X271789Y468150D01*
X271944Y468457D01*
X271996Y468725D01*
G01X268058Y458658D02*
X264958D01*
Y459617D01*
X265113Y459923D01*
X265320Y460115D01*
X265733Y460192D01*
X266146Y460115D01*
X266405Y459885D01*
X266560Y459617D01*
Y458658D01*
G01Y459617D02*
X268058Y460192D01*
G01X267438Y461682D02*
X267800Y461912D01*
X268006Y462218D01*
X268058Y462563D01*
X268006Y462870D01*
X267748Y463177D01*
X267438Y463368D01*
X267128Y463407D01*
X266766Y463330D01*
X266508Y463062D01*
X266405Y462793D01*
Y462448D01*
G01Y462793D02*
X266250Y463023D01*
X265991Y463215D01*
X265681Y463292D01*
X265371Y463215D01*
X265113Y463023D01*
X264958Y462678D01*
X265010Y462333D01*
X265216Y461988D01*
G01X268058Y466085D02*
X264958D01*
X267180Y464667D01*
Y466583D01*
G01X264958Y468725D02*
X265061Y468418D01*
X265320Y468188D01*
X265630Y468035D01*
X266043Y467920D01*
X266508Y467882D01*
X266973Y467920D01*
X267386Y468035D01*
X267696Y468188D01*
X267955Y468418D01*
X268058Y468725D01*
X267955Y469032D01*
X267696Y469262D01*
X267386Y469415D01*
X266973Y469530D01*
X266508Y469568D01*
X266043Y469530D01*
X265630Y469415D01*
X265320Y469262D01*
X265061Y469032D01*
X264958Y468725D01*
G01X262209Y464453D02*
X259009D01*
G01X262209Y470653D02*
Y464453D01*
G01X259009D02*
Y470653D01*
G01D02*
X262209D01*
G01X259009Y479653D02*
X262209D01*
G01X259009Y473453D02*
Y479653D01*
G01X262209Y473453D02*
X259009D01*
G01X262209Y479653D02*
Y473453D01*
G01X267509Y479653D02*
X270709D01*
G01X267509Y473453D02*
Y479653D01*
G01X270709Y473453D02*
X267509D01*
G01X270709Y479653D02*
Y473453D01*
G01X259767Y577220D02*
X262867D01*
Y578754D01*
G01X266017Y570845D02*
X262917D01*
G01Y572301D02*
X264829Y570845D01*
G01X266017Y572531D02*
X263950Y571496D01*
G01X272316Y570883D02*
X269216D01*
G01Y572493D02*
X272316D01*
G01X270766D02*
Y570883D01*
G01X266818Y577506D02*
X267128Y577698D01*
X267335Y577928D01*
X267438Y578196D01*
X267335Y578503D01*
X267128Y578733D01*
X266818Y578963D01*
X266405Y579040D01*
X264338D01*
G01X273916Y578217D02*
Y578984D01*
X274846D01*
X275156Y578754D01*
X275363Y578485D01*
X275466Y578102D01*
X275363Y577719D01*
X275156Y577450D01*
X274846Y577220D01*
X274484Y577067D01*
X274071Y576990D01*
X273709D01*
X273399Y577067D01*
X273038Y577220D01*
X272728Y577450D01*
X272521Y577680D01*
X272366Y577987D01*
Y578255D01*
X272469Y578562D01*
X272676Y578792D01*
G01X264501Y581546D02*
X261401D01*
Y582505D01*
X261556Y582811D01*
X261763Y583003D01*
X262176Y583080D01*
X262589Y583003D01*
X262848Y582773D01*
X263003Y582505D01*
Y581546D01*
G01Y582505D02*
X264501Y583080D01*
G01X263881Y584570D02*
X264243Y584800D01*
X264449Y585106D01*
X264501Y585451D01*
X264449Y585758D01*
X264191Y586065D01*
X263881Y586256D01*
X263571Y586295D01*
X263209Y586218D01*
X262951Y585950D01*
X262848Y585681D01*
Y585336D01*
G01Y585681D02*
X262693Y585911D01*
X262434Y586103D01*
X262124Y586180D01*
X261814Y586103D01*
X261556Y585911D01*
X261401Y585566D01*
X261453Y585221D01*
X261659Y584876D01*
G01X264501Y588513D02*
X261401D01*
X262021Y588053D01*
G01X264501D02*
Y588973D01*
G01X263881Y590770D02*
X264243Y591000D01*
X264449Y591306D01*
X264501Y591651D01*
X264449Y591958D01*
X264191Y592265D01*
X263881Y592456D01*
X263571Y592495D01*
X263209Y592418D01*
X262951Y592150D01*
X262848Y591881D01*
Y591536D01*
G01Y591881D02*
X262693Y592111D01*
X262434Y592303D01*
X262124Y592380D01*
X261814Y592303D01*
X261556Y592111D01*
X261401Y591766D01*
X261453Y591421D01*
X261659Y591076D01*
G01X258709Y587653D02*
Y581453D01*
G01X275008Y589794D02*
X271908D01*
Y590753D01*
X272063Y591059D01*
X272270Y591251D01*
X272683Y591328D01*
X273096Y591251D01*
X273355Y591021D01*
X273510Y590753D01*
Y589794D01*
G01Y590753D02*
X275008Y591328D01*
G01X274388Y592818D02*
X274750Y593048D01*
X274956Y593354D01*
X275008Y593699D01*
X274956Y594006D01*
X274698Y594313D01*
X274388Y594504D01*
X274078Y594543D01*
X273716Y594466D01*
X273458Y594198D01*
X273355Y593929D01*
Y593584D01*
G01Y593929D02*
X273200Y594159D01*
X272941Y594351D01*
X272631Y594428D01*
X272321Y594351D01*
X272063Y594159D01*
X271908Y593814D01*
X271960Y593469D01*
X272166Y593124D01*
G01X271908Y596761D02*
X272011Y596454D01*
X272270Y596224D01*
X272580Y596071D01*
X272993Y595956D01*
X273458Y595918D01*
X273923Y595956D01*
X274336Y596071D01*
X274646Y596224D01*
X274905Y596454D01*
X275008Y596761D01*
X274905Y597068D01*
X274646Y597298D01*
X274336Y597451D01*
X273923Y597566D01*
X273458Y597604D01*
X272993Y597566D01*
X272580Y597451D01*
X272270Y597298D01*
X272011Y597068D01*
X271908Y596761D01*
G01Y599861D02*
X272011Y599554D01*
X272270Y599324D01*
X272580Y599171D01*
X272993Y599056D01*
X273458Y599018D01*
X273923Y599056D01*
X274336Y599171D01*
X274646Y599324D01*
X274905Y599554D01*
X275008Y599861D01*
X274905Y600168D01*
X274646Y600398D01*
X274336Y600551D01*
X273923Y600666D01*
X273458Y600704D01*
X272993Y600666D01*
X272580Y600551D01*
X272270Y600398D01*
X272011Y600168D01*
X271908Y599861D01*
G01X275409Y581453D02*
X272209D01*
G01Y587653D02*
X275409D01*
G01X272209Y581453D02*
Y587653D01*
G01X270951Y589794D02*
X267851D01*
Y590753D01*
X268006Y591059D01*
X268213Y591251D01*
X268626Y591328D01*
X269039Y591251D01*
X269298Y591021D01*
X269453Y590753D01*
Y589794D01*
G01Y590753D02*
X270951Y591328D01*
G01X270331Y592818D02*
X270693Y593048D01*
X270899Y593354D01*
X270951Y593699D01*
X270899Y594006D01*
X270641Y594313D01*
X270331Y594504D01*
X270021Y594543D01*
X269659Y594466D01*
X269401Y594198D01*
X269298Y593929D01*
Y593584D01*
G01Y593929D02*
X269143Y594159D01*
X268884Y594351D01*
X268574Y594428D01*
X268264Y594351D01*
X268006Y594159D01*
X267851Y593814D01*
X267903Y593469D01*
X268109Y593124D01*
G01X267851Y596761D02*
X267954Y596454D01*
X268213Y596224D01*
X268523Y596071D01*
X268936Y595956D01*
X269401Y595918D01*
X269866Y595956D01*
X270279Y596071D01*
X270589Y596224D01*
X270848Y596454D01*
X270951Y596761D01*
X270848Y597068D01*
X270589Y597298D01*
X270279Y597451D01*
X269866Y597566D01*
X269401Y597604D01*
X268936Y597566D01*
X268523Y597451D01*
X268213Y597298D01*
X267954Y597068D01*
X267851Y596761D01*
G01X268368Y599133D02*
X268058Y599363D01*
X267903Y599631D01*
X267851Y599938D01*
X267954Y600321D01*
X268213Y600589D01*
X268523Y600666D01*
X268833Y600628D01*
X269091Y600474D01*
X269608Y599708D01*
X269969Y599363D01*
X270486Y599133D01*
X270951Y599056D01*
Y600666D01*
G01X271209Y581453D02*
X268009D01*
G01X271209Y587653D02*
Y581453D01*
G01X268009Y587653D02*
X271209D01*
G01X268009Y581453D02*
Y587653D01*
G01X261640Y603490D02*
Y598460D01*
G01X262490Y603490D02*
X261640D01*
G01X261918Y611463D02*
Y604663D01*
G01X263186Y601356D02*
Y627734D01*
G01X295986Y601356D02*
X263186D01*
G01X261918Y619271D02*
Y612471D01*
G01X262490Y627990D02*
Y627710D01*
G01X261943Y627116D02*
Y620316D01*
G01X263186Y627734D02*
X295986D01*
G01X265775Y642736D02*
X270280D01*
G01D02*
Y642030D01*
G01Y630925D02*
X265775D01*
G01X270280Y631630D02*
Y630925D01*
G01X280540Y654056D02*
X268340D01*
G01X271526Y658091D02*
X277726D01*
G01X271526Y654891D02*
Y658091D01*
G01X277726Y654891D02*
X271526D01*
G01Y653814D02*
X277726D01*
G01X271526Y650614D02*
Y653814D01*
G01X277726Y650614D02*
X271526D01*
G01Y649717D02*
X277726D01*
G01X271526Y646517D02*
Y649717D01*
G01X277726Y646517D02*
X271526D01*
G01X266430Y716000D02*
Y669340D01*
G01X280540Y673656D02*
X268340D01*
G01X271526Y662556D02*
Y665756D01*
G01X277726Y662556D02*
X271526D01*
G01Y665756D02*
X277726D01*
G01X261470Y670272D02*
Y673272D01*
G01X264570Y673372D02*
Y670172D01*
G01X267509Y666495D02*
Y671095D01*
G01X277709Y666495D02*
X267509D01*
G01Y671095D02*
X277709D01*
G01X272609D02*
Y666495D01*
G01X263835Y691179D02*
Y675179D01*
G01X270113Y686563D02*
X269883Y686718D01*
X269615Y686821D01*
X269308D01*
X268963Y686666D01*
X268695Y686408D01*
X268503Y686098D01*
X268350Y685581D01*
X268312Y685116D01*
X268388Y684651D01*
X268503Y684341D01*
X268733Y684031D01*
X269002Y683824D01*
X269270Y683721D01*
X269538D01*
X269807Y683824D01*
X270037Y683979D01*
X270228Y684186D01*
G01X271527D02*
X271757Y683928D01*
X272025Y683773D01*
X272370Y683721D01*
X272715Y683824D01*
X272983Y684031D01*
X273175Y684393D01*
X273213Y684806D01*
X273137Y685219D01*
X272945Y685478D01*
X272677Y685684D01*
X272408Y685736D01*
X272140Y685684D01*
X271795Y685478D01*
X271910Y686821D01*
X272945D01*
G01X275470Y683721D02*
X275738Y683773D01*
X276045Y683928D01*
X276237Y684186D01*
X276313Y684548D01*
X276237Y684909D01*
X276007Y685219D01*
X275662Y685374D01*
X275278D01*
X275048Y685478D01*
X274857Y685736D01*
X274780Y686098D01*
X274895Y686459D01*
X275163Y686718D01*
X275470Y686821D01*
X275777Y686718D01*
X276045Y686459D01*
X276160Y686098D01*
X276083Y685736D01*
X275892Y685478D01*
X275662Y685374D01*
X275278D01*
X274933Y685219D01*
X274703Y684909D01*
X274627Y684548D01*
X274703Y684186D01*
X274895Y683928D01*
X275202Y683773D01*
X275470Y683721D01*
G01X277727Y684341D02*
X277957Y683979D01*
X278263Y683773D01*
X278608Y683721D01*
X278915Y683773D01*
X279222Y684031D01*
X279413Y684341D01*
X279452Y684651D01*
X279375Y685013D01*
X279107Y685271D01*
X278838Y685374D01*
X278493D01*
G01X278838D02*
X279068Y685529D01*
X279260Y685788D01*
X279337Y686098D01*
X279260Y686408D01*
X279068Y686666D01*
X278723Y686821D01*
X278378Y686769D01*
X278033Y686563D01*
G01X271526Y689438D02*
Y692638D01*
G01X277726Y689438D02*
X271526D01*
G01X264051Y691912D02*
Y694412D01*
X263731Y693912D01*
G01Y691912D02*
X264371D01*
G01X280040Y693556D02*
X267840D01*
G01X273724Y705272D02*
Y706918D01*
G01X267935Y706844D02*
Y705044D01*
G01X272335Y706844D02*
Y705044D01*
G01X267935Y706844D02*
X272335D01*
G01Y706244D02*
X267935D01*
G01Y705644D02*
X272335D01*
G01Y705044D02*
Y694644D01*
G01X267935Y705044D02*
X272335D01*
G01X267935Y694644D02*
Y705044D01*
G01X272335Y694644D02*
X267935D01*
G01X271526Y692638D02*
X277726D01*
G01X260516Y695545D02*
Y692345D01*
G01X261648Y693218D02*
Y695718D01*
X262182D01*
X262395Y695593D01*
X262555Y695426D01*
X262688Y695176D01*
X262795Y694885D01*
X262822Y694468D01*
X262795Y694051D01*
X262688Y693760D01*
X262555Y693510D01*
X262395Y693343D01*
X262182Y693218D01*
X261648D01*
G01X265440Y711456D02*
Y696456D01*
G01X266430Y717330D02*
Y716000D01*
G01X273776Y708240D02*
X270676D01*
Y709006D01*
X270831Y709313D01*
X271038Y709543D01*
X271348Y709735D01*
X271709Y709888D01*
X272226Y709926D01*
X272743Y709888D01*
X273104Y709735D01*
X273414Y709543D01*
X273621Y709313D01*
X273776Y709006D01*
Y708240D01*
G01X271193Y711455D02*
X270883Y711685D01*
X270728Y711953D01*
X270676Y712260D01*
X270779Y712643D01*
X271038Y712911D01*
X271348Y712988D01*
X271658Y712950D01*
X271916Y712796D01*
X272433Y712030D01*
X272794Y711685D01*
X273311Y711455D01*
X273776Y711378D01*
Y712988D01*
G01X273311Y714440D02*
X273569Y714670D01*
X273724Y714938D01*
X273776Y715283D01*
X273673Y715628D01*
X273466Y715896D01*
X273104Y716088D01*
X272691Y716126D01*
X272278Y716050D01*
X272019Y715858D01*
X271813Y715590D01*
X271761Y715321D01*
X271813Y715053D01*
X272019Y714708D01*
X270676Y714823D01*
Y715858D01*
G01X265382Y717681D02*
Y720781D01*
X266341D01*
X266647Y720626D01*
X266839Y720419D01*
X266916Y720006D01*
X266839Y719593D01*
X266609Y719334D01*
X266341Y719179D01*
X265382D01*
G01X266341D02*
X266916Y717681D01*
G01X269249D02*
Y720781D01*
X268789Y720161D01*
G01Y717681D02*
X269709D01*
G01X272349Y720781D02*
X272042Y720678D01*
X271812Y720419D01*
X271659Y720109D01*
X271544Y719696D01*
X271506Y719231D01*
X271544Y718766D01*
X271659Y718353D01*
X271812Y718043D01*
X272042Y717784D01*
X272349Y717681D01*
X272656Y717784D01*
X272886Y718043D01*
X273039Y718353D01*
X273154Y718766D01*
X273192Y719231D01*
X273154Y719696D01*
X273039Y720109D01*
X272886Y720419D01*
X272656Y720678D01*
X272349Y720781D01*
G01X275372Y717681D02*
X275449Y718353D01*
X275564Y718921D01*
X275717Y719438D01*
X275909Y720006D01*
X276216Y720781D01*
X274682D01*
G01X279009Y717681D02*
Y720781D01*
X277591Y718559D01*
X279507D01*
G01X268098Y711873D02*
X268631D01*
Y711123D01*
X268471Y710873D01*
X268285Y710706D01*
X268018Y710623D01*
X267751Y710706D01*
X267565Y710873D01*
X267405Y711123D01*
X267298Y711415D01*
X267245Y711748D01*
Y712040D01*
X267298Y712290D01*
X267405Y712581D01*
X267565Y712831D01*
X267725Y712998D01*
X267938Y713123D01*
X268125D01*
X268338Y713040D01*
X268498Y712873D01*
G01X259040Y743756D02*
Y737556D01*
G01X263540D02*
X260340D01*
G01D02*
Y743756D01*
G01X263540D02*
Y737556D01*
G01X268040D02*
X264840D01*
G01X268040Y743756D02*
Y737556D01*
G01X264840D02*
Y743756D01*
G01X272540Y737556D02*
X269340D01*
G01X272540Y743756D02*
Y737556D01*
G01X269340D02*
Y743756D01*
G01X277040Y737556D02*
X273840D01*
G01D02*
Y743756D01*
G01X259040Y732256D02*
Y726056D01*
G01X264840Y732256D02*
X268040D01*
G01X264840Y726056D02*
Y732256D01*
G01X268040Y726056D02*
X264840D01*
G01X268040Y732256D02*
Y726056D01*
G01X269340Y732256D02*
X272540D01*
G01X269340Y726056D02*
Y732256D01*
G01X272540Y726056D02*
X269340D01*
G01X272540Y732256D02*
Y726056D01*
G01X260340Y732256D02*
X263540D01*
G01X260340Y726056D02*
Y732256D01*
G01X263540Y726056D02*
X260340D01*
G01X263540Y732256D02*
Y726056D01*
G01X273840Y732256D02*
X277040D01*
G01X273840Y726056D02*
Y732256D01*
G01X277040Y726056D02*
X273840D01*
G01X263440Y740656D02*
X260440D01*
G01X260340Y743756D02*
X263540D01*
G01X267940Y740656D02*
X264940D01*
G01X264840Y743756D02*
X268040D01*
G01X272440Y740656D02*
X269440D01*
G01X269340Y743756D02*
X272540D01*
G01X276940Y740656D02*
X273940D01*
G01X273840Y743756D02*
X277040D01*
G01X264737Y745311D02*
X261637D01*
Y746270D01*
X261792Y746576D01*
X261999Y746768D01*
X262412Y746845D01*
X262825Y746768D01*
X263084Y746538D01*
X263239Y746270D01*
Y745311D01*
G01Y746270D02*
X264737Y746845D01*
G01Y749178D02*
X264685Y749446D01*
X264530Y749753D01*
X264272Y749945D01*
X263910Y750021D01*
X263549Y749945D01*
X263239Y749715D01*
X263084Y749370D01*
Y748986D01*
X262980Y748756D01*
X262722Y748565D01*
X262360Y748488D01*
X261999Y748603D01*
X261740Y748871D01*
X261637Y749178D01*
X261740Y749485D01*
X261999Y749753D01*
X262360Y749868D01*
X262722Y749791D01*
X262980Y749600D01*
X263084Y749370D01*
Y748986D01*
X263239Y748641D01*
X263549Y748411D01*
X263910Y748335D01*
X264272Y748411D01*
X264530Y748603D01*
X264685Y748910D01*
X264737Y749178D01*
G01Y752201D02*
X264065Y752278D01*
X263497Y752393D01*
X262980Y752546D01*
X262412Y752738D01*
X261637Y753045D01*
Y751511D01*
G01X264737Y755838D02*
X261637D01*
X263859Y754420D01*
Y756336D01*
G01X269129Y745311D02*
X266029D01*
Y746270D01*
X266184Y746576D01*
X266391Y746768D01*
X266804Y746845D01*
X267217Y746768D01*
X267476Y746538D01*
X267631Y746270D01*
Y745311D01*
G01Y746270D02*
X269129Y746845D01*
G01Y749178D02*
X269077Y749446D01*
X268922Y749753D01*
X268664Y749945D01*
X268302Y750021D01*
X267941Y749945D01*
X267631Y749715D01*
X267476Y749370D01*
Y748986D01*
X267372Y748756D01*
X267114Y748565D01*
X266752Y748488D01*
X266391Y748603D01*
X266132Y748871D01*
X266029Y749178D01*
X266132Y749485D01*
X266391Y749753D01*
X266752Y749868D01*
X267114Y749791D01*
X267372Y749600D01*
X267476Y749370D01*
Y748986D01*
X267631Y748641D01*
X267941Y748411D01*
X268302Y748335D01*
X268664Y748411D01*
X268922Y748603D01*
X269077Y748910D01*
X269129Y749178D01*
G01Y752201D02*
X268457Y752278D01*
X267889Y752393D01*
X267372Y752546D01*
X266804Y752738D01*
X266029Y753045D01*
Y751511D01*
G01X269129Y755378D02*
X266029D01*
X266649Y754918D01*
G01X269129D02*
Y755838D01*
G01X273332Y745311D02*
X270232D01*
Y746270D01*
X270387Y746576D01*
X270594Y746768D01*
X271007Y746845D01*
X271420Y746768D01*
X271679Y746538D01*
X271834Y746270D01*
Y745311D01*
G01Y746270D02*
X273332Y746845D01*
G01X272970Y748526D02*
X273229Y748795D01*
X273332Y749101D01*
X273229Y749408D01*
X272919Y749676D01*
X272454Y749868D01*
X271989Y749945D01*
X271420D01*
X270955Y749868D01*
X270542Y749676D01*
X270335Y749446D01*
X270232Y749178D01*
X270335Y748871D01*
X270542Y748641D01*
X270852Y748488D01*
X271265Y748411D01*
X271627Y748488D01*
X271989Y748680D01*
X272195Y748910D01*
X272247Y749178D01*
X272144Y749485D01*
X271885Y749715D01*
X271420Y749945D01*
G01X272867Y751435D02*
X273125Y751665D01*
X273280Y751933D01*
X273332Y752278D01*
X273229Y752623D01*
X273022Y752891D01*
X272660Y753083D01*
X272247Y753121D01*
X271834Y753045D01*
X271575Y752853D01*
X271369Y752585D01*
X271317Y752316D01*
X271369Y752048D01*
X271575Y751703D01*
X270232Y751818D01*
Y752853D01*
G01X272712Y754535D02*
X273074Y754765D01*
X273280Y755071D01*
X273332Y755416D01*
X273280Y755723D01*
X273022Y756030D01*
X272712Y756221D01*
X272402Y756260D01*
X272040Y756183D01*
X271782Y755915D01*
X271679Y755646D01*
Y755301D01*
G01Y755646D02*
X271524Y755876D01*
X271265Y756068D01*
X270955Y756145D01*
X270645Y756068D01*
X270387Y755876D01*
X270232Y755531D01*
X270284Y755186D01*
X270490Y754841D01*
G01X262693Y760558D02*
X262538Y760328D01*
X262435Y760060D01*
Y759753D01*
X262590Y759408D01*
X262848Y759140D01*
X263158Y758948D01*
X263675Y758795D01*
X264140Y758757D01*
X264605Y758833D01*
X264915Y758948D01*
X265225Y759178D01*
X265432Y759447D01*
X265535Y759715D01*
Y759983D01*
X265432Y760252D01*
X265277Y760482D01*
X265070Y760673D01*
G01X264243Y762087D02*
X263882Y762355D01*
X263675Y762585D01*
X263572Y762892D01*
X263675Y763160D01*
X263882Y763352D01*
X264192Y763505D01*
X264553Y763543D01*
X264863Y763505D01*
X265173Y763352D01*
X265432Y763122D01*
X265535Y762853D01*
X265432Y762547D01*
X265122Y762278D01*
X264657Y762125D01*
X264140Y762087D01*
X263468Y762163D01*
X263107Y762278D01*
X262745Y762470D01*
X262487Y762738D01*
X262435Y763007D01*
X262538Y763275D01*
X262797Y763467D01*
G01X264915Y765072D02*
X265277Y765302D01*
X265483Y765608D01*
X265535Y765953D01*
X265483Y766260D01*
X265225Y766567D01*
X264915Y766758D01*
X264605Y766797D01*
X264243Y766720D01*
X263985Y766452D01*
X263882Y766183D01*
Y765838D01*
G01Y766183D02*
X263727Y766413D01*
X263468Y766605D01*
X263158Y766682D01*
X262848Y766605D01*
X262590Y766413D01*
X262435Y766068D01*
X262487Y765723D01*
X262693Y765378D01*
G01X265535Y768938D02*
X264863Y769015D01*
X264295Y769130D01*
X263778Y769283D01*
X263210Y769475D01*
X262435Y769782D01*
Y768248D01*
G01X266601Y760558D02*
X266446Y760328D01*
X266343Y760060D01*
Y759753D01*
X266498Y759408D01*
X266756Y759140D01*
X267066Y758948D01*
X267583Y758795D01*
X268048Y758757D01*
X268513Y758833D01*
X268823Y758948D01*
X269133Y759178D01*
X269340Y759447D01*
X269443Y759715D01*
Y759983D01*
X269340Y760252D01*
X269185Y760482D01*
X268978Y760673D01*
G01X268151Y762087D02*
X267790Y762355D01*
X267583Y762585D01*
X267480Y762892D01*
X267583Y763160D01*
X267790Y763352D01*
X268100Y763505D01*
X268461Y763543D01*
X268771Y763505D01*
X269081Y763352D01*
X269340Y763122D01*
X269443Y762853D01*
X269340Y762547D01*
X269030Y762278D01*
X268565Y762125D01*
X268048Y762087D01*
X267376Y762163D01*
X267015Y762278D01*
X266653Y762470D01*
X266395Y762738D01*
X266343Y763007D01*
X266446Y763275D01*
X266705Y763467D01*
G01X268823Y765072D02*
X269185Y765302D01*
X269391Y765608D01*
X269443Y765953D01*
X269391Y766260D01*
X269133Y766567D01*
X268823Y766758D01*
X268513Y766797D01*
X268151Y766720D01*
X267893Y766452D01*
X267790Y766183D01*
Y765838D01*
G01Y766183D02*
X267635Y766413D01*
X267376Y766605D01*
X267066Y766682D01*
X266756Y766605D01*
X266498Y766413D01*
X266343Y766068D01*
X266395Y765723D01*
X266601Y765378D01*
G01X269443Y769475D02*
X266343D01*
X268565Y768057D01*
Y769973D01*
G01X270651Y760558D02*
X270496Y760328D01*
X270393Y760060D01*
Y759753D01*
X270548Y759408D01*
X270806Y759140D01*
X271116Y758948D01*
X271633Y758795D01*
X272098Y758757D01*
X272563Y758833D01*
X272873Y758948D01*
X273183Y759178D01*
X273390Y759447D01*
X273493Y759715D01*
Y759983D01*
X273390Y760252D01*
X273235Y760482D01*
X273028Y760673D01*
G01X273493Y762738D02*
X272821Y762815D01*
X272253Y762930D01*
X271736Y763083D01*
X271168Y763275D01*
X270393Y763582D01*
Y762048D01*
G01X273493Y765915D02*
X270393D01*
X271013Y765455D01*
G01X273493D02*
Y766375D01*
G01X272201Y768287D02*
X271840Y768555D01*
X271633Y768785D01*
X271530Y769092D01*
X271633Y769360D01*
X271840Y769552D01*
X272150Y769705D01*
X272511Y769743D01*
X272821Y769705D01*
X273131Y769552D01*
X273390Y769322D01*
X273493Y769053D01*
X273390Y768747D01*
X273080Y768478D01*
X272615Y768325D01*
X272098Y768287D01*
X271426Y768363D01*
X271065Y768478D01*
X270703Y768670D01*
X270445Y768938D01*
X270393Y769207D01*
X270496Y769475D01*
X270755Y769667D01*
G01X290063Y6912D02*
Y33290D01*
G01X322863Y6912D02*
X290063D01*
G01X285368Y11340D02*
X282268D01*
Y12260D01*
X282423Y12567D01*
X282785Y12797D01*
X283198Y12874D01*
X283611Y12797D01*
X283921Y12605D01*
X284076Y12260D01*
Y11340D01*
G01X282268Y14364D02*
X284490D01*
X284955Y14517D01*
X285265Y14824D01*
X285368Y15207D01*
X285265Y15590D01*
X284955Y15897D01*
X284490Y16050D01*
X282268D01*
G01X284903Y17464D02*
X285161Y17694D01*
X285316Y17962D01*
X285368Y18307D01*
X285265Y18652D01*
X285058Y18920D01*
X284696Y19112D01*
X284283Y19150D01*
X283870Y19074D01*
X283611Y18882D01*
X283405Y18614D01*
X283353Y18345D01*
X283405Y18077D01*
X283611Y17732D01*
X282268Y17847D01*
Y18882D01*
G01X290155Y3884D02*
X289925Y4039D01*
X289657Y4142D01*
X289350D01*
X289005Y3987D01*
X288737Y3729D01*
X288545Y3419D01*
X288392Y2902D01*
X288354Y2437D01*
X288430Y1972D01*
X288545Y1662D01*
X288775Y1352D01*
X289044Y1145D01*
X289312Y1042D01*
X289580D01*
X289849Y1145D01*
X290079Y1300D01*
X290270Y1507D01*
G01X291760Y1404D02*
X292029Y1145D01*
X292335Y1042D01*
X292642Y1145D01*
X292910Y1455D01*
X293102Y1920D01*
X293179Y2385D01*
Y2954D01*
X293102Y3419D01*
X292910Y3832D01*
X292680Y4039D01*
X292412Y4142D01*
X292105Y4039D01*
X291875Y3832D01*
X291722Y3522D01*
X291645Y3109D01*
X291722Y2747D01*
X291914Y2385D01*
X292144Y2179D01*
X292412Y2127D01*
X292719Y2230D01*
X292949Y2489D01*
X293179Y2954D01*
G01X294669Y1662D02*
X294899Y1300D01*
X295205Y1094D01*
X295550Y1042D01*
X295857Y1094D01*
X296164Y1352D01*
X296355Y1662D01*
X296394Y1972D01*
X296317Y2334D01*
X296049Y2592D01*
X295780Y2695D01*
X295435D01*
G01X295780D02*
X296010Y2850D01*
X296202Y3109D01*
X296279Y3419D01*
X296202Y3729D01*
X296010Y3987D01*
X295665Y4142D01*
X295320Y4090D01*
X294975Y3884D01*
G01X297769Y1662D02*
X297999Y1300D01*
X298305Y1094D01*
X298650Y1042D01*
X298957Y1094D01*
X299264Y1352D01*
X299455Y1662D01*
X299494Y1972D01*
X299417Y2334D01*
X299149Y2592D01*
X298880Y2695D01*
X298535D01*
G01X298880D02*
X299110Y2850D01*
X299302Y3109D01*
X299379Y3419D01*
X299302Y3729D01*
X299110Y3987D01*
X298765Y4142D01*
X298420Y4090D01*
X298075Y3884D01*
G01X281028Y8270D02*
X287228D01*
G01X281028Y5070D02*
Y8270D01*
G01X287228Y5070D02*
X281028D01*
G01X284128Y8170D02*
Y5170D01*
G01X287228Y8270D02*
Y5070D01*
G01X289408Y12276D02*
X286308D01*
Y13196D01*
X286463Y13503D01*
X286825Y13733D01*
X287238Y13810D01*
X287651Y13733D01*
X287961Y13541D01*
X288116Y13196D01*
Y12276D01*
G01X286566Y16986D02*
X286411Y16756D01*
X286308Y16488D01*
Y16181D01*
X286463Y15836D01*
X286721Y15568D01*
X287031Y15376D01*
X287548Y15223D01*
X288013Y15185D01*
X288478Y15261D01*
X288788Y15376D01*
X289098Y15606D01*
X289305Y15875D01*
X289408Y16143D01*
Y16411D01*
X289305Y16680D01*
X289150Y16910D01*
X288943Y17101D01*
G01X289408Y19703D02*
X286308D01*
X288530Y18285D01*
Y20201D01*
G01X289408Y22266D02*
X288736Y22343D01*
X288168Y22458D01*
X287651Y22611D01*
X287083Y22803D01*
X286308Y23110D01*
Y21576D01*
G01X280178Y8236D02*
Y5036D01*
G01X283810Y21346D02*
X283996Y21137D01*
X284210Y21054D01*
X284423Y21137D01*
X284610Y21387D01*
X284743Y21762D01*
X284796Y22137D01*
Y22596D01*
X284743Y22971D01*
X284610Y23304D01*
X284450Y23471D01*
X284263Y23554D01*
X284050Y23471D01*
X283890Y23304D01*
X283783Y23054D01*
X283730Y22721D01*
X283783Y22429D01*
X283916Y22137D01*
X284076Y21971D01*
X284263Y21929D01*
X284476Y22012D01*
X284636Y22221D01*
X284796Y22596D01*
G01X280074Y19178D02*
X282175D01*
G01X284067Y24394D02*
X286067D01*
G01X282175Y19178D02*
Y20879D01*
G01Y29579D02*
Y31580D01*
G01X288833Y24183D02*
X285633D01*
G01X288833Y30383D02*
Y24183D01*
G01X285633D02*
Y30383D01*
G01X288733Y27283D02*
X285733D01*
G01X290063Y33290D02*
X322863D01*
G01X282312Y32116D02*
Y34616D01*
X281992Y34116D01*
G01Y32116D02*
X282632D01*
G01X284005Y34199D02*
X284165Y34449D01*
X284352Y34574D01*
X284565Y34616D01*
X284832Y34533D01*
X285019Y34324D01*
X285072Y34074D01*
X285045Y33824D01*
X284939Y33616D01*
X284405Y33199D01*
X284165Y32908D01*
X284005Y32491D01*
X283952Y32116D01*
X285072D01*
G01X282175Y31580D02*
X280074D01*
G01X274967Y34632D02*
Y33432D01*
G01X286126Y35187D02*
X279926D01*
G01D02*
Y38387D01*
G01D02*
X286126D01*
G01D02*
Y35187D01*
G01X283026Y38287D02*
Y35287D01*
G01X285633Y30383D02*
X288833D01*
G01X276737Y39186D02*
Y46586D01*
G01X294137Y39186D02*
X276737D01*
G01X285437D02*
Y46586D01*
G01X276737Y54990D02*
X294137D01*
G01X276737Y47590D02*
Y54990D01*
G01X294137Y47590D02*
X276737D01*
G01X285437D02*
Y54990D01*
G01X276737Y46586D02*
X294137D01*
G01X274387Y72704D02*
X277587D01*
G01X277487Y69604D02*
X274487D01*
G01X274387Y66504D02*
Y72704D01*
G01X277587D02*
Y66504D01*
G01D02*
X274387D01*
G01X285587Y72704D02*
Y66504D01*
G01X282387Y72704D02*
X285587D01*
G01X285487Y69604D02*
X282487D01*
G01X282387Y66504D02*
Y72704D01*
G01X285587Y66504D02*
X282387D01*
G01X278387Y72704D02*
X281587D01*
G01X281487Y69604D02*
X278487D01*
G01X278387Y66504D02*
Y72704D01*
G01X281587D02*
Y66504D01*
G01D02*
X278387D01*
G01X286387Y72704D02*
X289587D01*
G01X289487Y69604D02*
X286487D01*
G01X286387Y66504D02*
Y72704D01*
G01X289587D02*
Y66504D01*
G01D02*
X286387D01*
G01X288513Y173930D02*
X285413D01*
Y174889D01*
X285568Y175195D01*
X285775Y175387D01*
X286188Y175464D01*
X286601Y175387D01*
X286860Y175157D01*
X287015Y174889D01*
Y173930D01*
G01Y174889D02*
X288513Y175464D01*
G01X285930Y177069D02*
X285620Y177299D01*
X285465Y177567D01*
X285413Y177874D01*
X285516Y178257D01*
X285775Y178525D01*
X286085Y178602D01*
X286395Y178564D01*
X286653Y178410D01*
X287170Y177644D01*
X287531Y177299D01*
X288048Y177069D01*
X288513Y176992D01*
Y178602D01*
G01X288151Y180245D02*
X288410Y180514D01*
X288513Y180820D01*
X288410Y181127D01*
X288100Y181395D01*
X287635Y181587D01*
X287170Y181664D01*
X286601D01*
X286136Y181587D01*
X285723Y181395D01*
X285516Y181165D01*
X285413Y180897D01*
X285516Y180590D01*
X285723Y180360D01*
X286033Y180207D01*
X286446Y180130D01*
X286808Y180207D01*
X287170Y180399D01*
X287376Y180629D01*
X287428Y180897D01*
X287325Y181204D01*
X287066Y181434D01*
X286601Y181664D01*
G01X288151Y183345D02*
X288410Y183614D01*
X288513Y183920D01*
X288410Y184227D01*
X288100Y184495D01*
X287635Y184687D01*
X287170Y184764D01*
X286601D01*
X286136Y184687D01*
X285723Y184495D01*
X285516Y184265D01*
X285413Y183997D01*
X285516Y183690D01*
X285723Y183460D01*
X286033Y183307D01*
X286446Y183230D01*
X286808Y183307D01*
X287170Y183499D01*
X287376Y183729D01*
X287428Y183997D01*
X287325Y184304D01*
X287066Y184534D01*
X286601Y184764D01*
G01X287557Y203121D02*
X287402Y202891D01*
X287299Y202623D01*
Y202316D01*
X287454Y201971D01*
X287712Y201703D01*
X288022Y201511D01*
X288539Y201358D01*
X289004Y201320D01*
X289469Y201396D01*
X289779Y201511D01*
X290089Y201741D01*
X290296Y202010D01*
X290399Y202278D01*
Y202546D01*
X290296Y202815D01*
X290141Y203045D01*
X289934Y203236D01*
G01X290037Y204726D02*
X290296Y204995D01*
X290399Y205301D01*
X290296Y205608D01*
X289986Y205876D01*
X289521Y206068D01*
X289056Y206145D01*
X288487D01*
X288022Y206068D01*
X287609Y205876D01*
X287402Y205646D01*
X287299Y205378D01*
X287402Y205071D01*
X287609Y204841D01*
X287919Y204688D01*
X288332Y204611D01*
X288694Y204688D01*
X289056Y204880D01*
X289262Y205110D01*
X289314Y205378D01*
X289211Y205685D01*
X288952Y205915D01*
X288487Y206145D01*
G01X287299Y208478D02*
X287402Y208171D01*
X287661Y207941D01*
X287971Y207788D01*
X288384Y207673D01*
X288849Y207635D01*
X289314Y207673D01*
X289727Y207788D01*
X290037Y207941D01*
X290296Y208171D01*
X290399Y208478D01*
X290296Y208785D01*
X290037Y209015D01*
X289727Y209168D01*
X289314Y209283D01*
X288849Y209321D01*
X288384Y209283D01*
X287971Y209168D01*
X287661Y209015D01*
X287402Y208785D01*
X287299Y208478D01*
G01X289107Y210850D02*
X288746Y211118D01*
X288539Y211348D01*
X288436Y211655D01*
X288539Y211923D01*
X288746Y212115D01*
X289056Y212268D01*
X289417Y212306D01*
X289727Y212268D01*
X290037Y212115D01*
X290296Y211885D01*
X290399Y211616D01*
X290296Y211310D01*
X289986Y211041D01*
X289521Y210888D01*
X289004Y210850D01*
X288332Y210926D01*
X287971Y211041D01*
X287609Y211233D01*
X287351Y211501D01*
X287299Y211770D01*
X287402Y212038D01*
X287661Y212230D01*
G01X282959Y196135D02*
Y199235D01*
X283918D01*
X284224Y199080D01*
X284416Y198873D01*
X284493Y198460D01*
X284416Y198047D01*
X284186Y197788D01*
X283918Y197633D01*
X282959D01*
G01X283918D02*
X284493Y196135D01*
G01X286098Y197427D02*
X286366Y197788D01*
X286596Y197995D01*
X286903Y198098D01*
X287171Y197995D01*
X287363Y197788D01*
X287516Y197478D01*
X287554Y197117D01*
X287516Y196807D01*
X287363Y196497D01*
X287133Y196238D01*
X286864Y196135D01*
X286558Y196238D01*
X286289Y196548D01*
X286136Y197013D01*
X286098Y197530D01*
X286174Y198202D01*
X286289Y198563D01*
X286481Y198925D01*
X286749Y199183D01*
X287018Y199235D01*
X287286Y199132D01*
X287478Y198873D01*
G01X290386Y196135D02*
Y199235D01*
X288968Y197013D01*
X290884D01*
G01X292949Y196135D02*
X293026Y196807D01*
X293141Y197375D01*
X293294Y197892D01*
X293486Y198460D01*
X293793Y199235D01*
X292259D01*
G01X283189Y191915D02*
Y195015D01*
X284148D01*
X284454Y194860D01*
X284646Y194653D01*
X284723Y194240D01*
X284646Y193827D01*
X284416Y193568D01*
X284148Y193413D01*
X283189D01*
G01X284148D02*
X284723Y191915D01*
G01X286328Y193207D02*
X286596Y193568D01*
X286826Y193775D01*
X287133Y193878D01*
X287401Y193775D01*
X287593Y193568D01*
X287746Y193258D01*
X287784Y192897D01*
X287746Y192587D01*
X287593Y192277D01*
X287363Y192018D01*
X287094Y191915D01*
X286788Y192018D01*
X286519Y192328D01*
X286366Y192793D01*
X286328Y193310D01*
X286404Y193982D01*
X286519Y194343D01*
X286711Y194705D01*
X286979Y194963D01*
X287248Y195015D01*
X287516Y194912D01*
X287708Y194653D01*
G01X290079Y191915D02*
X290156Y192587D01*
X290271Y193155D01*
X290424Y193672D01*
X290616Y194240D01*
X290923Y195015D01*
X289389D01*
G01X293256Y191915D02*
Y195015D01*
X292796Y194395D01*
G01Y191915D02*
X293716D01*
G01X278650Y190565D02*
X280872D01*
X281337Y190718D01*
X281647Y191025D01*
X281750Y191408D01*
X281647Y191791D01*
X281337Y192098D01*
X280872Y192251D01*
X278650D01*
G01X281750Y194508D02*
X278650D01*
X279270Y194048D01*
G01X281750D02*
Y194968D01*
G01X279167Y196880D02*
X278857Y197110D01*
X278702Y197378D01*
X278650Y197685D01*
X278753Y198068D01*
X279012Y198336D01*
X279322Y198413D01*
X279632Y198375D01*
X279890Y198221D01*
X280407Y197455D01*
X280768Y197110D01*
X281285Y196880D01*
X281750Y196803D01*
Y198413D01*
G01Y200631D02*
X281078Y200708D01*
X280510Y200823D01*
X279993Y200976D01*
X279425Y201168D01*
X278650Y201475D01*
Y199941D01*
G01X288474Y216288D02*
X314216D01*
Y191918D01*
G01X275429Y204445D02*
Y207545D01*
X276388D01*
X276694Y207390D01*
X276886Y207183D01*
X276963Y206770D01*
X276886Y206357D01*
X276656Y206098D01*
X276388Y205943D01*
X275429D01*
G01X276388D02*
X276963Y204445D01*
G01X279219D02*
X279296Y205117D01*
X279411Y205685D01*
X279564Y206202D01*
X279756Y206770D01*
X280063Y207545D01*
X278529D01*
G01X282319Y204445D02*
X282396Y205117D01*
X282511Y205685D01*
X282664Y206202D01*
X282856Y206770D01*
X283163Y207545D01*
X281629D01*
G01X284653Y204910D02*
X284883Y204652D01*
X285151Y204497D01*
X285496Y204445D01*
X285841Y204548D01*
X286109Y204755D01*
X286301Y205117D01*
X286339Y205530D01*
X286263Y205943D01*
X286071Y206202D01*
X285803Y206408D01*
X285534Y206460D01*
X285266Y206408D01*
X284921Y206202D01*
X285036Y207545D01*
X286071D01*
G01X274992Y360724D02*
X275152Y360516D01*
X275339Y360391D01*
X275579Y360349D01*
X275819Y360432D01*
X276006Y360599D01*
X276139Y360891D01*
X276166Y361224D01*
X276112Y361557D01*
X275979Y361766D01*
X275792Y361932D01*
X275606Y361974D01*
X275419Y361932D01*
X275179Y361766D01*
X275259Y362849D01*
X275979D01*
G01X277779Y360349D02*
X277966Y360391D01*
X278179Y360516D01*
X278312Y360724D01*
X278366Y361016D01*
X278312Y361307D01*
X278152Y361557D01*
X277912Y361682D01*
X277646D01*
X277486Y361766D01*
X277352Y361974D01*
X277299Y362266D01*
X277379Y362557D01*
X277566Y362766D01*
X277779Y362849D01*
X277992Y362766D01*
X278179Y362557D01*
X278259Y362266D01*
X278206Y361974D01*
X278072Y361766D01*
X277912Y361682D01*
X277646D01*
X277406Y361557D01*
X277246Y361307D01*
X277192Y361016D01*
X277246Y360724D01*
X277379Y360516D01*
X277592Y360391D01*
X277779Y360349D01*
G01X276162Y357131D02*
X276322Y356923D01*
X276509Y356798D01*
X276749Y356756D01*
X276989Y356839D01*
X277176Y357006D01*
X277309Y357298D01*
X277336Y357631D01*
X277282Y357964D01*
X277149Y358173D01*
X276962Y358339D01*
X276776Y358381D01*
X276589Y358339D01*
X276349Y358173D01*
X276429Y359256D01*
X277149D01*
G01X278496Y357048D02*
X278682Y356839D01*
X278896Y356756D01*
X279109Y356839D01*
X279296Y357089D01*
X279429Y357464D01*
X279482Y357839D01*
Y358298D01*
X279429Y358673D01*
X279296Y359006D01*
X279136Y359173D01*
X278949Y359256D01*
X278736Y359173D01*
X278576Y359006D01*
X278469Y358756D01*
X278416Y358423D01*
X278469Y358131D01*
X278602Y357839D01*
X278762Y357673D01*
X278949Y357631D01*
X279162Y357714D01*
X279322Y357923D01*
X279482Y358298D01*
G01X279072Y361391D02*
X279259Y361682D01*
X279419Y361849D01*
X279632Y361932D01*
X279819Y361849D01*
X279952Y361682D01*
X280059Y361432D01*
X280086Y361141D01*
X280059Y360891D01*
X279952Y360641D01*
X279792Y360432D01*
X279606Y360349D01*
X279392Y360432D01*
X279206Y360682D01*
X279099Y361057D01*
X279072Y361474D01*
X279126Y362016D01*
X279206Y362307D01*
X279339Y362599D01*
X279526Y362807D01*
X279712Y362849D01*
X279899Y362766D01*
X280032Y362557D01*
G01X281779Y362849D02*
X281566Y362766D01*
X281406Y362557D01*
X281299Y362307D01*
X281219Y361974D01*
X281192Y361599D01*
X281219Y361224D01*
X281299Y360891D01*
X281406Y360641D01*
X281566Y360432D01*
X281779Y360349D01*
X281992Y360432D01*
X282152Y360641D01*
X282259Y360891D01*
X282339Y361224D01*
X282366Y361599D01*
X282339Y361974D01*
X282259Y362307D01*
X282152Y362557D01*
X281992Y362766D01*
X281779Y362849D01*
G01X280242Y357798D02*
X280429Y358089D01*
X280589Y358256D01*
X280802Y358339D01*
X280989Y358256D01*
X281122Y358089D01*
X281229Y357839D01*
X281256Y357548D01*
X281229Y357298D01*
X281122Y357048D01*
X280962Y356839D01*
X280776Y356756D01*
X280562Y356839D01*
X280376Y357089D01*
X280269Y357464D01*
X280242Y357881D01*
X280296Y358423D01*
X280376Y358714D01*
X280509Y359006D01*
X280696Y359214D01*
X280882Y359256D01*
X281069Y359173D01*
X281202Y358964D01*
G01X282949Y356756D02*
Y359256D01*
X282629Y358756D01*
G01Y356756D02*
X283269D01*
G01X282742Y361229D02*
X282929Y361520D01*
X283089Y361687D01*
X283302Y361770D01*
X283489Y361687D01*
X283622Y361520D01*
X283729Y361270D01*
X283756Y360979D01*
X283729Y360729D01*
X283622Y360479D01*
X283462Y360270D01*
X283276Y360187D01*
X283062Y360270D01*
X282876Y360520D01*
X282769Y360895D01*
X282742Y361312D01*
X282796Y361854D01*
X282876Y362145D01*
X283009Y362437D01*
X283196Y362645D01*
X283382Y362687D01*
X283569Y362604D01*
X283702Y362395D01*
G01X284942Y362270D02*
X285102Y362520D01*
X285289Y362645D01*
X285502Y362687D01*
X285769Y362604D01*
X285956Y362395D01*
X286009Y362145D01*
X285982Y361895D01*
X285876Y361687D01*
X285342Y361270D01*
X285102Y360979D01*
X284942Y360562D01*
X284889Y360187D01*
X286009D01*
G01X284242Y357798D02*
X284429Y358089D01*
X284589Y358256D01*
X284802Y358339D01*
X284989Y358256D01*
X285122Y358089D01*
X285229Y357839D01*
X285256Y357548D01*
X285229Y357298D01*
X285122Y357048D01*
X284962Y356839D01*
X284776Y356756D01*
X284562Y356839D01*
X284376Y357089D01*
X284269Y357464D01*
X284242Y357881D01*
X284296Y358423D01*
X284376Y358714D01*
X284509Y359006D01*
X284696Y359214D01*
X284882Y359256D01*
X285069Y359173D01*
X285202Y358964D01*
G01X286362Y357256D02*
X286522Y356964D01*
X286736Y356798D01*
X286976Y356756D01*
X287189Y356798D01*
X287402Y357006D01*
X287536Y357256D01*
X287562Y357506D01*
X287509Y357798D01*
X287322Y358006D01*
X287136Y358089D01*
X286896D01*
G01X287136D02*
X287296Y358214D01*
X287429Y358423D01*
X287482Y358673D01*
X287429Y358923D01*
X287296Y359131D01*
X287056Y359256D01*
X286816Y359214D01*
X286576Y359048D01*
G01X286742Y361229D02*
X286929Y361520D01*
X287089Y361687D01*
X287302Y361770D01*
X287489Y361687D01*
X287622Y361520D01*
X287729Y361270D01*
X287756Y360979D01*
X287729Y360729D01*
X287622Y360479D01*
X287462Y360270D01*
X287276Y360187D01*
X287062Y360270D01*
X286876Y360520D01*
X286769Y360895D01*
X286742Y361312D01*
X286796Y361854D01*
X286876Y362145D01*
X287009Y362437D01*
X287196Y362645D01*
X287382Y362687D01*
X287569Y362604D01*
X287702Y362395D01*
G01X289769Y360187D02*
Y362687D01*
X288782Y360895D01*
X290116D01*
G01X288242Y357798D02*
X288429Y358089D01*
X288589Y358256D01*
X288802Y358339D01*
X288989Y358256D01*
X289122Y358089D01*
X289229Y357839D01*
X289256Y357548D01*
X289229Y357298D01*
X289122Y357048D01*
X288962Y356839D01*
X288776Y356756D01*
X288562Y356839D01*
X288376Y357089D01*
X288269Y357464D01*
X288242Y357881D01*
X288296Y358423D01*
X288376Y358714D01*
X288509Y359006D01*
X288696Y359214D01*
X288882Y359256D01*
X289069Y359173D01*
X289202Y358964D01*
G01X290362Y357131D02*
X290522Y356923D01*
X290709Y356798D01*
X290949Y356756D01*
X291189Y356839D01*
X291376Y357006D01*
X291509Y357298D01*
X291536Y357631D01*
X291482Y357964D01*
X291349Y358173D01*
X291162Y358339D01*
X290976Y358381D01*
X290789Y358339D01*
X290549Y358173D01*
X290629Y359256D01*
X291349D01*
G01X277847Y370703D02*
X279430Y375703D01*
X281013Y370703D01*
G01X280443Y372453D02*
X278417D01*
G01X277140Y370190D02*
X286510D01*
G01X277140Y376360D02*
Y370190D01*
G01X286590Y367430D02*
X286670D01*
G01X286590Y376440D02*
Y367430D01*
G01X287542Y373698D02*
X290742D01*
G01Y367498D02*
X287542D01*
G01D02*
Y373698D01*
G01X277180Y376360D02*
X277140D01*
G01X290329Y377648D02*
X287129D01*
G01D02*
Y383848D01*
G01D02*
X290329D01*
G01X279129Y377648D02*
Y383848D01*
G01D02*
X282329D01*
G01D02*
Y377648D01*
G01D02*
X279129D01*
G01X275129D02*
Y383848D01*
G01D02*
X278329D01*
G01D02*
Y377648D01*
G01D02*
X275129D01*
G01X286329Y383848D02*
Y377648D01*
G01D02*
X283129D01*
G01D02*
Y383848D01*
G01D02*
X286329D01*
G01X279300Y404803D02*
Y401603D01*
G01X276200Y404703D02*
Y401703D01*
G01X279300Y396303D02*
Y393103D01*
G01Y400803D02*
Y397603D01*
G01X290224Y404093D02*
X287124D01*
Y405052D01*
X287279Y405358D01*
X287486Y405550D01*
X287899Y405627D01*
X288312Y405550D01*
X288571Y405320D01*
X288726Y405052D01*
Y404093D01*
G01Y405052D02*
X290224Y405627D01*
G01Y407960D02*
X287124D01*
X287744Y407500D01*
G01X290224D02*
Y408420D01*
G01X287641Y410332D02*
X287331Y410562D01*
X287176Y410830D01*
X287124Y411137D01*
X287227Y411520D01*
X287486Y411788D01*
X287796Y411865D01*
X288106Y411827D01*
X288364Y411673D01*
X288881Y410907D01*
X289242Y410562D01*
X289759Y410332D01*
X290224Y410255D01*
Y411865D01*
G01X289604Y413317D02*
X289966Y413547D01*
X290172Y413853D01*
X290224Y414198D01*
X290172Y414505D01*
X289914Y414812D01*
X289604Y415003D01*
X289294Y415042D01*
X288932Y414965D01*
X288674Y414697D01*
X288571Y414428D01*
Y414083D01*
G01Y414428D02*
X288416Y414658D01*
X288157Y414850D01*
X287847Y414927D01*
X287537Y414850D01*
X287279Y414658D01*
X287124Y414313D01*
X287176Y413968D01*
X287382Y413623D01*
G01X290224Y417260D02*
X287124D01*
X287744Y416800D01*
G01X290224D02*
Y417720D01*
G01X285110Y400310D02*
X288310D01*
G01X285110Y394110D02*
Y400310D01*
G01X288310Y394110D02*
X285110D01*
G01X288310Y400310D02*
Y394110D01*
G01X286561Y418446D02*
X283461D01*
Y419405D01*
X283616Y419711D01*
X283823Y419903D01*
X284236Y419980D01*
X284649Y419903D01*
X284908Y419673D01*
X285063Y419405D01*
Y418446D01*
G01Y419405D02*
X286561Y419980D01*
G01Y422313D02*
X283461D01*
X284081Y421853D01*
G01X286561D02*
Y422773D01*
G01Y425413D02*
X283461D01*
X284081Y424953D01*
G01X286561D02*
Y425873D01*
G01Y428513D02*
X283461D01*
X284081Y428053D01*
G01X286561D02*
Y428973D01*
G01X285941Y430770D02*
X286303Y431000D01*
X286509Y431306D01*
X286561Y431651D01*
X286509Y431958D01*
X286251Y432265D01*
X285941Y432456D01*
X285631Y432495D01*
X285269Y432418D01*
X285011Y432150D01*
X284908Y431881D01*
Y431536D01*
G01Y431881D02*
X284753Y432111D01*
X284494Y432303D01*
X284184Y432380D01*
X283874Y432303D01*
X283616Y432111D01*
X283461Y431766D01*
X283513Y431421D01*
X283719Y431076D01*
G01X290820Y418483D02*
X287720D01*
Y419442D01*
X287875Y419748D01*
X288082Y419940D01*
X288495Y420017D01*
X288908Y419940D01*
X289167Y419710D01*
X289322Y419442D01*
Y418483D01*
G01Y419442D02*
X290820Y420017D01*
G01Y422350D02*
X287720D01*
X288340Y421890D01*
G01X290820D02*
Y422810D01*
G01Y425450D02*
X287720D01*
X288340Y424990D01*
G01X290820D02*
Y425910D01*
G01Y428550D02*
X287720D01*
X288340Y428090D01*
G01X290820D02*
Y429010D01*
G01X288237Y430922D02*
X287927Y431152D01*
X287772Y431420D01*
X287720Y431727D01*
X287823Y432110D01*
X288082Y432378D01*
X288392Y432455D01*
X288702Y432417D01*
X288960Y432263D01*
X289477Y431497D01*
X289838Y431152D01*
X290355Y430922D01*
X290820Y430845D01*
Y432455D01*
G01X282528Y431271D02*
X282476Y430964D01*
X282270Y430696D01*
X281960Y430466D01*
X281598Y430313D01*
X281185Y430236D01*
X280771D01*
X280358Y430313D01*
X279996Y430466D01*
X279686Y430696D01*
X279480Y430964D01*
X279428Y431271D01*
X279480Y431578D01*
X279686Y431846D01*
X279996Y432076D01*
X280358Y432229D01*
X280771Y432306D01*
X281185D01*
X281598Y432229D01*
X281960Y432076D01*
X282270Y431846D01*
X282476Y431578D01*
X282528Y431271D01*
G01X281701Y431578D02*
X282528Y432038D01*
G01X281908Y433528D02*
X282270Y433758D01*
X282476Y434064D01*
X282528Y434409D01*
X282476Y434716D01*
X282218Y435023D01*
X281908Y435214D01*
X281598Y435253D01*
X281236Y435176D01*
X280978Y434908D01*
X280875Y434639D01*
Y434294D01*
G01Y434639D02*
X280720Y434869D01*
X280461Y435061D01*
X280151Y435138D01*
X279841Y435061D01*
X279583Y434869D01*
X279428Y434524D01*
X279480Y434179D01*
X279686Y433834D01*
G01X282528Y437394D02*
X281856Y437471D01*
X281288Y437586D01*
X280771Y437739D01*
X280203Y437931D01*
X279428Y438238D01*
Y436704D01*
G01X277796Y440556D02*
Y436050D01*
G01Y433250D02*
Y428745D01*
G01D02*
X277090D01*
G01X281258Y452752D02*
X278158D01*
Y453711D01*
X278313Y454017D01*
X278520Y454209D01*
X278933Y454286D01*
X279346Y454209D01*
X279605Y453979D01*
X279760Y453711D01*
Y452752D01*
G01Y453711D02*
X281258Y454286D01*
G01X280638Y455776D02*
X281000Y456006D01*
X281206Y456312D01*
X281258Y456657D01*
X281206Y456964D01*
X280948Y457271D01*
X280638Y457462D01*
X280328Y457501D01*
X279966Y457424D01*
X279708Y457156D01*
X279605Y456887D01*
Y456542D01*
G01Y456887D02*
X279450Y457117D01*
X279191Y457309D01*
X278881Y457386D01*
X278571Y457309D01*
X278313Y457117D01*
X278158Y456772D01*
X278210Y456427D01*
X278416Y456082D01*
G01X280638Y458876D02*
X281000Y459106D01*
X281206Y459412D01*
X281258Y459757D01*
X281206Y460064D01*
X280948Y460371D01*
X280638Y460562D01*
X280328Y460601D01*
X279966Y460524D01*
X279708Y460256D01*
X279605Y459987D01*
Y459642D01*
G01Y459987D02*
X279450Y460217D01*
X279191Y460409D01*
X278881Y460486D01*
X278571Y460409D01*
X278313Y460217D01*
X278158Y459872D01*
X278210Y459527D01*
X278416Y459182D01*
G01X279966Y462091D02*
X279605Y462359D01*
X279398Y462589D01*
X279295Y462896D01*
X279398Y463164D01*
X279605Y463356D01*
X279915Y463509D01*
X280276Y463547D01*
X280586Y463509D01*
X280896Y463356D01*
X281155Y463126D01*
X281258Y462857D01*
X281155Y462551D01*
X280845Y462282D01*
X280380Y462129D01*
X279863Y462091D01*
X279191Y462167D01*
X278830Y462282D01*
X278468Y462474D01*
X278210Y462742D01*
X278158Y463011D01*
X278261Y463279D01*
X278520Y463471D01*
G01X289258Y452752D02*
X286158D01*
Y453711D01*
X286313Y454017D01*
X286520Y454209D01*
X286933Y454286D01*
X287346Y454209D01*
X287605Y453979D01*
X287760Y453711D01*
Y452752D01*
G01Y453711D02*
X289258Y454286D01*
G01X288638Y455776D02*
X289000Y456006D01*
X289206Y456312D01*
X289258Y456657D01*
X289206Y456964D01*
X288948Y457271D01*
X288638Y457462D01*
X288328Y457501D01*
X287966Y457424D01*
X287708Y457156D01*
X287605Y456887D01*
Y456542D01*
G01Y456887D02*
X287450Y457117D01*
X287191Y457309D01*
X286881Y457386D01*
X286571Y457309D01*
X286313Y457117D01*
X286158Y456772D01*
X286210Y456427D01*
X286416Y456082D01*
G01X288638Y458876D02*
X289000Y459106D01*
X289206Y459412D01*
X289258Y459757D01*
X289206Y460064D01*
X288948Y460371D01*
X288638Y460562D01*
X288328Y460601D01*
X287966Y460524D01*
X287708Y460256D01*
X287605Y459987D01*
Y459642D01*
G01Y459987D02*
X287450Y460217D01*
X287191Y460409D01*
X286881Y460486D01*
X286571Y460409D01*
X286313Y460217D01*
X286158Y459872D01*
X286210Y459527D01*
X286416Y459182D01*
G01X289258Y462819D02*
X286158D01*
X286778Y462359D01*
G01X289258D02*
Y463279D01*
G01X285258Y452752D02*
X282158D01*
Y453711D01*
X282313Y454017D01*
X282520Y454209D01*
X282933Y454286D01*
X283346Y454209D01*
X283605Y453979D01*
X283760Y453711D01*
Y452752D01*
G01Y453711D02*
X285258Y454286D01*
G01X284638Y455776D02*
X285000Y456006D01*
X285206Y456312D01*
X285258Y456657D01*
X285206Y456964D01*
X284948Y457271D01*
X284638Y457462D01*
X284328Y457501D01*
X283966Y457424D01*
X283708Y457156D01*
X283605Y456887D01*
Y456542D01*
G01Y456887D02*
X283450Y457117D01*
X283191Y457309D01*
X282881Y457386D01*
X282571Y457309D01*
X282313Y457117D01*
X282158Y456772D01*
X282210Y456427D01*
X282416Y456082D01*
G01X282675Y458991D02*
X282365Y459221D01*
X282210Y459489D01*
X282158Y459796D01*
X282261Y460179D01*
X282520Y460447D01*
X282830Y460524D01*
X283140Y460486D01*
X283398Y460332D01*
X283915Y459566D01*
X284276Y459221D01*
X284793Y458991D01*
X285258Y458914D01*
Y460524D01*
G01Y462742D02*
X284586Y462819D01*
X284018Y462934D01*
X283501Y463087D01*
X282933Y463279D01*
X282158Y463586D01*
Y462052D01*
G01X278753Y447027D02*
Y450127D01*
X279712D01*
X280018Y449972D01*
X280210Y449765D01*
X280287Y449352D01*
X280210Y448939D01*
X279980Y448680D01*
X279712Y448525D01*
X278753D01*
G01X279712D02*
X280287Y447027D01*
G01X282620D02*
Y450127D01*
X282160Y449507D01*
G01Y447027D02*
X283080D01*
G01X285720D02*
Y450127D01*
X285260Y449507D01*
G01Y447027D02*
X286180D01*
G01X288820D02*
Y450127D01*
X288360Y449507D01*
G01Y447027D02*
X289280D01*
G01X292380D02*
Y450127D01*
X290962Y447905D01*
X292878D01*
G01X277947Y446901D02*
X274747D01*
G01X277947Y453101D02*
Y446901D01*
G01X274747D02*
Y453101D01*
G01D02*
X277947D01*
G01X276990Y440556D02*
X277796D01*
G01X280068Y472469D02*
X279838Y472624D01*
X279570Y472727D01*
X279263D01*
X278918Y472572D01*
X278650Y472314D01*
X278458Y472004D01*
X278305Y471487D01*
X278267Y471022D01*
X278343Y470557D01*
X278458Y470247D01*
X278688Y469937D01*
X278957Y469730D01*
X279225Y469627D01*
X279493D01*
X279762Y469730D01*
X279992Y469885D01*
X280183Y470092D01*
G01X281597Y472210D02*
X281827Y472520D01*
X282095Y472675D01*
X282402Y472727D01*
X282785Y472624D01*
X283053Y472365D01*
X283130Y472055D01*
X283092Y471745D01*
X282938Y471487D01*
X282172Y470970D01*
X281827Y470609D01*
X281597Y470092D01*
X281520Y469627D01*
X283130D01*
G01X285425Y472727D02*
X285118Y472624D01*
X284888Y472365D01*
X284735Y472055D01*
X284620Y471642D01*
X284582Y471177D01*
X284620Y470712D01*
X284735Y470299D01*
X284888Y469989D01*
X285118Y469730D01*
X285425Y469627D01*
X285732Y469730D01*
X285962Y469989D01*
X286115Y470299D01*
X286230Y470712D01*
X286268Y471177D01*
X286230Y471642D01*
X286115Y472055D01*
X285962Y472365D01*
X285732Y472624D01*
X285425Y472727D01*
G01X287797Y472210D02*
X288027Y472520D01*
X288295Y472675D01*
X288602Y472727D01*
X288985Y472624D01*
X289253Y472365D01*
X289330Y472055D01*
X289292Y471745D01*
X289138Y471487D01*
X288372Y470970D01*
X288027Y470609D01*
X287797Y470092D01*
X287720Y469627D01*
X289330D01*
G01X280027Y476776D02*
X279797Y476931D01*
X279529Y477034D01*
X279222D01*
X278877Y476879D01*
X278609Y476621D01*
X278417Y476311D01*
X278264Y475794D01*
X278226Y475329D01*
X278302Y474864D01*
X278417Y474554D01*
X278647Y474244D01*
X278916Y474037D01*
X279184Y473934D01*
X279452D01*
X279721Y474037D01*
X279951Y474192D01*
X280142Y474399D01*
G01X281556Y476517D02*
X281786Y476827D01*
X282054Y476982D01*
X282361Y477034D01*
X282744Y476931D01*
X283012Y476672D01*
X283089Y476362D01*
X283051Y476052D01*
X282897Y475794D01*
X282131Y475277D01*
X281786Y474916D01*
X281556Y474399D01*
X281479Y473934D01*
X283089D01*
G01X285384Y477034D02*
X285077Y476931D01*
X284847Y476672D01*
X284694Y476362D01*
X284579Y475949D01*
X284541Y475484D01*
X284579Y475019D01*
X284694Y474606D01*
X284847Y474296D01*
X285077Y474037D01*
X285384Y473934D01*
X285691Y474037D01*
X285921Y474296D01*
X286074Y474606D01*
X286189Y475019D01*
X286227Y475484D01*
X286189Y475949D01*
X286074Y476362D01*
X285921Y476672D01*
X285691Y476931D01*
X285384Y477034D01*
G01X287641Y474554D02*
X287871Y474192D01*
X288177Y473986D01*
X288522Y473934D01*
X288829Y473986D01*
X289136Y474244D01*
X289327Y474554D01*
X289366Y474864D01*
X289289Y475226D01*
X289021Y475484D01*
X288752Y475587D01*
X288407D01*
G01X288752D02*
X288982Y475742D01*
X289174Y476001D01*
X289251Y476311D01*
X289174Y476621D01*
X288982Y476879D01*
X288637Y477034D01*
X288292Y476982D01*
X287947Y476776D01*
G01X278615Y570960D02*
X275515D01*
Y572416D01*
G01X277013Y571880D02*
Y570960D01*
G01X284915Y570845D02*
X281815D01*
Y571611D01*
X281970Y571918D01*
X282177Y572148D01*
X282487Y572340D01*
X282848Y572493D01*
X283365Y572531D01*
X283882Y572493D01*
X284243Y572340D01*
X284553Y572148D01*
X284760Y571918D01*
X284915Y571611D01*
Y570845D01*
G01X285222Y578830D02*
X285067Y578600D01*
X284964Y578332D01*
Y578025D01*
X285119Y577680D01*
X285377Y577412D01*
X285687Y577220D01*
X286204Y577067D01*
X286669Y577029D01*
X287134Y577105D01*
X287444Y577220D01*
X287754Y577450D01*
X287961Y577719D01*
X288064Y577987D01*
Y578255D01*
X287961Y578524D01*
X287806Y578754D01*
X287599Y578945D01*
G01X283938Y579040D02*
Y577506D01*
X280838D01*
Y579040D01*
G01X282336Y578426D02*
Y577506D01*
G01X289561Y571995D02*
X289406Y572148D01*
X289147Y572263D01*
X288786Y572340D01*
X288476Y572263D01*
X288269Y572110D01*
X288114Y571841D01*
Y570806D01*
X291214D01*
Y572071D01*
X291007Y572340D01*
X290697Y572493D01*
X290336Y572570D01*
X289974Y572493D01*
X289664Y572263D01*
X289561Y571995D01*
Y570806D01*
G01X288330Y597045D02*
Y600145D01*
X289250D01*
X289557Y599990D01*
X289787Y599628D01*
X289864Y599215D01*
X289787Y598802D01*
X289595Y598492D01*
X289250Y598337D01*
X288330D01*
G01X293040Y599887D02*
X292810Y600042D01*
X292542Y600145D01*
X292235D01*
X291890Y599990D01*
X291622Y599732D01*
X291430Y599422D01*
X291277Y598905D01*
X291239Y598440D01*
X291315Y597975D01*
X291430Y597665D01*
X291660Y597355D01*
X291929Y597148D01*
X292197Y597045D01*
X292465D01*
X292734Y597148D01*
X292964Y597303D01*
X293155Y597510D01*
G01X294569Y599628D02*
X294799Y599938D01*
X295067Y600093D01*
X295374Y600145D01*
X295757Y600042D01*
X296025Y599783D01*
X296102Y599473D01*
X296064Y599163D01*
X295910Y598905D01*
X295144Y598388D01*
X294799Y598027D01*
X294569Y597510D01*
X294492Y597045D01*
X296102D01*
G01X275409Y587653D02*
Y581453D01*
G01X279008Y589794D02*
X275908D01*
Y590753D01*
X276063Y591059D01*
X276270Y591251D01*
X276683Y591328D01*
X277096Y591251D01*
X277355Y591021D01*
X277510Y590753D01*
Y589794D01*
G01Y590753D02*
X279008Y591328D01*
G01X278388Y592818D02*
X278750Y593048D01*
X278956Y593354D01*
X279008Y593699D01*
X278956Y594006D01*
X278698Y594313D01*
X278388Y594504D01*
X278078Y594543D01*
X277716Y594466D01*
X277458Y594198D01*
X277355Y593929D01*
Y593584D01*
G01Y593929D02*
X277200Y594159D01*
X276941Y594351D01*
X276631Y594428D01*
X276321Y594351D01*
X276063Y594159D01*
X275908Y593814D01*
X275960Y593469D01*
X276166Y593124D01*
G01X275908Y596761D02*
X276011Y596454D01*
X276270Y596224D01*
X276580Y596071D01*
X276993Y595956D01*
X277458Y595918D01*
X277923Y595956D01*
X278336Y596071D01*
X278646Y596224D01*
X278905Y596454D01*
X279008Y596761D01*
X278905Y597068D01*
X278646Y597298D01*
X278336Y597451D01*
X277923Y597566D01*
X277458Y597604D01*
X276993Y597566D01*
X276580Y597451D01*
X276270Y597298D01*
X276011Y597068D01*
X275908Y596761D01*
G01X279008Y600321D02*
X275908D01*
X278130Y598903D01*
Y600819D01*
G01X279709Y581453D02*
X276509D01*
G01X279709Y587653D02*
Y581453D01*
G01X276509Y587653D02*
X279709D01*
G01X276509Y581453D02*
Y587653D01*
G01X283008Y589794D02*
X279908D01*
Y590753D01*
X280063Y591059D01*
X280270Y591251D01*
X280683Y591328D01*
X281096Y591251D01*
X281355Y591021D01*
X281510Y590753D01*
Y589794D01*
G01Y590753D02*
X283008Y591328D01*
G01X280425Y592933D02*
X280115Y593163D01*
X279960Y593431D01*
X279908Y593738D01*
X280011Y594121D01*
X280270Y594389D01*
X280580Y594466D01*
X280890Y594428D01*
X281148Y594274D01*
X281665Y593508D01*
X282026Y593163D01*
X282543Y592933D01*
X283008Y592856D01*
Y594466D01*
G01X282646Y596109D02*
X282905Y596378D01*
X283008Y596684D01*
X282905Y596991D01*
X282595Y597259D01*
X282130Y597451D01*
X281665Y597528D01*
X281096D01*
X280631Y597451D01*
X280218Y597259D01*
X280011Y597029D01*
X279908Y596761D01*
X280011Y596454D01*
X280218Y596224D01*
X280528Y596071D01*
X280941Y595994D01*
X281303Y596071D01*
X281665Y596263D01*
X281871Y596493D01*
X281923Y596761D01*
X281820Y597068D01*
X281561Y597298D01*
X281096Y597528D01*
G01X283008Y599861D02*
X282956Y600129D01*
X282801Y600436D01*
X282543Y600628D01*
X282181Y600704D01*
X281820Y600628D01*
X281510Y600398D01*
X281355Y600053D01*
Y599669D01*
X281251Y599439D01*
X280993Y599248D01*
X280631Y599171D01*
X280270Y599286D01*
X280011Y599554D01*
X279908Y599861D01*
X280011Y600168D01*
X280270Y600436D01*
X280631Y600551D01*
X280993Y600474D01*
X281251Y600283D01*
X281355Y600053D01*
Y599669D01*
X281510Y599324D01*
X281820Y599094D01*
X282181Y599018D01*
X282543Y599094D01*
X282801Y599286D01*
X282956Y599593D01*
X283008Y599861D01*
G01X283909Y581453D02*
X280709D01*
G01X283909Y587653D02*
Y581453D01*
G01X280709Y587653D02*
X283909D01*
G01X280709Y581453D02*
Y587653D01*
G01X283823Y628397D02*
Y631497D01*
X284743D01*
X285050Y631342D01*
X285280Y630980D01*
X285357Y630567D01*
X285280Y630154D01*
X285088Y629844D01*
X284743Y629689D01*
X283823D01*
G01X286923Y631497D02*
Y628397D01*
X288457D01*
G01X290790D02*
Y631497D01*
X290330Y630877D01*
G01Y628397D02*
X291250D01*
G01X293162Y630980D02*
X293392Y631290D01*
X293660Y631445D01*
X293967Y631497D01*
X294350Y631394D01*
X294618Y631135D01*
X294695Y630825D01*
X294657Y630515D01*
X294503Y630257D01*
X293737Y629740D01*
X293392Y629379D01*
X293162Y628862D01*
X293085Y628397D01*
X294695D01*
G01X287294Y642232D02*
X287454Y642024D01*
X287641Y641899D01*
X287881Y641857D01*
X288121Y641940D01*
X288308Y642107D01*
X288441Y642399D01*
X288468Y642732D01*
X288414Y643065D01*
X288281Y643274D01*
X288094Y643440D01*
X287908Y643482D01*
X287721Y643440D01*
X287481Y643274D01*
X287561Y644357D01*
X288281D01*
G01X290081Y641857D02*
Y644357D01*
X289761Y643857D01*
G01Y641857D02*
X290401D01*
G01X283782Y634256D02*
X283627Y634026D01*
X283524Y633758D01*
Y633451D01*
X283679Y633106D01*
X283937Y632838D01*
X284247Y632646D01*
X284764Y632493D01*
X285229Y632455D01*
X285694Y632531D01*
X286004Y632646D01*
X286314Y632876D01*
X286521Y633145D01*
X286624Y633413D01*
Y633681D01*
X286521Y633950D01*
X286366Y634180D01*
X286159Y634371D01*
G01X286624Y636513D02*
X286572Y636781D01*
X286417Y637088D01*
X286159Y637280D01*
X285797Y637356D01*
X285436Y637280D01*
X285126Y637050D01*
X284971Y636705D01*
Y636321D01*
X284867Y636091D01*
X284609Y635900D01*
X284247Y635823D01*
X283886Y635938D01*
X283627Y636206D01*
X283524Y636513D01*
X283627Y636820D01*
X283886Y637088D01*
X284247Y637203D01*
X284609Y637126D01*
X284867Y636935D01*
X284971Y636705D01*
Y636321D01*
X285126Y635976D01*
X285436Y635746D01*
X285797Y635670D01*
X286159Y635746D01*
X286417Y635938D01*
X286572Y636245D01*
X286624Y636513D01*
G01Y640073D02*
X283524D01*
X285746Y638655D01*
Y640571D01*
G01X286159Y641870D02*
X286417Y642100D01*
X286572Y642368D01*
X286624Y642713D01*
X286521Y643058D01*
X286314Y643326D01*
X285952Y643518D01*
X285539Y643556D01*
X285126Y643480D01*
X284867Y643288D01*
X284661Y643020D01*
X284609Y642751D01*
X284661Y642483D01*
X284867Y642138D01*
X283524Y642253D01*
Y643288D01*
G01X278526Y632646D02*
X275426D01*
Y633605D01*
X275581Y633911D01*
X275788Y634103D01*
X276201Y634180D01*
X276614Y634103D01*
X276873Y633873D01*
X277028Y633605D01*
Y632646D01*
G01Y633605D02*
X278526Y634180D01*
G01X278061Y635670D02*
X278319Y635900D01*
X278474Y636168D01*
X278526Y636513D01*
X278423Y636858D01*
X278216Y637126D01*
X277854Y637318D01*
X277441Y637356D01*
X277028Y637280D01*
X276769Y637088D01*
X276563Y636820D01*
X276511Y636551D01*
X276563Y636283D01*
X276769Y635938D01*
X275426Y636053D01*
Y637088D01*
G01X278526Y640073D02*
X275426D01*
X277648Y638655D01*
Y640571D01*
G01X278526Y642636D02*
X277854Y642713D01*
X277286Y642828D01*
X276769Y642981D01*
X276201Y643173D01*
X275426Y643480D01*
Y641946D01*
G01X290807Y633413D02*
X290755Y633106D01*
X290549Y632838D01*
X290239Y632608D01*
X289877Y632455D01*
X289464Y632378D01*
X289050D01*
X288637Y632455D01*
X288275Y632608D01*
X287965Y632838D01*
X287759Y633106D01*
X287707Y633413D01*
X287759Y633720D01*
X287965Y633988D01*
X288275Y634218D01*
X288637Y634371D01*
X289050Y634448D01*
X289464D01*
X289877Y634371D01*
X290239Y634218D01*
X290549Y633988D01*
X290755Y633720D01*
X290807Y633413D01*
G01X289980Y633720D02*
X290807Y634180D01*
G01X290187Y635670D02*
X290549Y635900D01*
X290755Y636206D01*
X290807Y636551D01*
X290755Y636858D01*
X290497Y637165D01*
X290187Y637356D01*
X289877Y637395D01*
X289515Y637318D01*
X289257Y637050D01*
X289154Y636781D01*
Y636436D01*
G01Y636781D02*
X288999Y637011D01*
X288740Y637203D01*
X288430Y637280D01*
X288120Y637203D01*
X287862Y637011D01*
X287707Y636666D01*
X287759Y636321D01*
X287965Y635976D01*
G01X290342Y638770D02*
X290600Y639000D01*
X290755Y639268D01*
X290807Y639613D01*
X290704Y639958D01*
X290497Y640226D01*
X290135Y640418D01*
X289722Y640456D01*
X289309Y640380D01*
X289050Y640188D01*
X288844Y639920D01*
X288792Y639651D01*
X288844Y639383D01*
X289050Y639038D01*
X287707Y639153D01*
Y640188D01*
G01X282591Y633413D02*
X282539Y633106D01*
X282333Y632838D01*
X282023Y632608D01*
X281661Y632455D01*
X281248Y632378D01*
X280834D01*
X280421Y632455D01*
X280059Y632608D01*
X279749Y632838D01*
X279543Y633106D01*
X279491Y633413D01*
X279543Y633720D01*
X279749Y633988D01*
X280059Y634218D01*
X280421Y634371D01*
X280834Y634448D01*
X281248D01*
X281661Y634371D01*
X282023Y634218D01*
X282333Y633988D01*
X282539Y633720D01*
X282591Y633413D01*
G01X281764Y633720D02*
X282591Y634180D01*
G01X281971Y635670D02*
X282333Y635900D01*
X282539Y636206D01*
X282591Y636551D01*
X282539Y636858D01*
X282281Y637165D01*
X281971Y637356D01*
X281661Y637395D01*
X281299Y637318D01*
X281041Y637050D01*
X280938Y636781D01*
Y636436D01*
G01Y636781D02*
X280783Y637011D01*
X280524Y637203D01*
X280214Y637280D01*
X279904Y637203D01*
X279646Y637011D01*
X279491Y636666D01*
X279543Y636321D01*
X279749Y635976D01*
G01X281299Y638885D02*
X280938Y639153D01*
X280731Y639383D01*
X280628Y639690D01*
X280731Y639958D01*
X280938Y640150D01*
X281248Y640303D01*
X281609Y640341D01*
X281919Y640303D01*
X282229Y640150D01*
X282488Y639920D01*
X282591Y639651D01*
X282488Y639345D01*
X282178Y639076D01*
X281713Y638923D01*
X281196Y638885D01*
X280524Y638961D01*
X280163Y639076D01*
X279801Y639268D01*
X279543Y639536D01*
X279491Y639805D01*
X279594Y640073D01*
X279853Y640265D01*
G01X282107Y650356D02*
X282267Y650148D01*
X282454Y650023D01*
X282694Y649981D01*
X282934Y650064D01*
X283121Y650231D01*
X283254Y650523D01*
X283281Y650856D01*
X283227Y651189D01*
X283094Y651398D01*
X282907Y651564D01*
X282721Y651606D01*
X282534Y651564D01*
X282294Y651398D01*
X282374Y652481D01*
X283094D01*
G01X284894D02*
X284681Y652398D01*
X284521Y652189D01*
X284414Y651939D01*
X284334Y651606D01*
X284307Y651231D01*
X284334Y650856D01*
X284414Y650523D01*
X284521Y650273D01*
X284681Y650064D01*
X284894Y649981D01*
X285107Y650064D01*
X285267Y650273D01*
X285374Y650523D01*
X285454Y650856D01*
X285481Y651231D01*
X285454Y651606D01*
X285374Y651939D01*
X285267Y652189D01*
X285107Y652398D01*
X284894Y652481D01*
G01X277726Y658091D02*
Y654891D01*
G01Y653814D02*
Y650614D01*
G01Y649717D02*
Y646517D01*
G01X274626Y662656D02*
Y665656D01*
G01X277726Y665756D02*
Y662556D01*
G01X277709Y671095D02*
Y666495D01*
G01X280140Y683556D02*
X275140D01*
G01X274626Y689538D02*
Y692538D01*
G01X277726Y692638D02*
Y689438D01*
G01X275782Y696999D02*
X278882Y697536D01*
X275782Y698149D01*
X278882Y698762D01*
X275782Y699299D01*
G01X278882Y700406D02*
X275782D01*
Y701172D01*
X275937Y701479D01*
X276144Y701709D01*
X276454Y701901D01*
X276815Y702054D01*
X277332Y702092D01*
X277849Y702054D01*
X278210Y701901D01*
X278520Y701709D01*
X278727Y701479D01*
X278882Y701172D01*
Y700406D01*
G01X275782Y704349D02*
X278882D01*
G01X275782Y703467D02*
Y705231D01*
G01X279915Y706299D02*
Y708599D01*
G01X278882Y711316D02*
Y709782D01*
X275782D01*
Y711316D01*
G01X277280Y710702D02*
Y709782D01*
G01X278882Y712767D02*
X275782D01*
X278882Y714531D01*
X275782D01*
G01X282026Y704650D02*
X282186Y704900D01*
X282373Y705025D01*
X282586Y705067D01*
X282853Y704984D01*
X283040Y704775D01*
X283093Y704525D01*
X283066Y704275D01*
X282960Y704067D01*
X282426Y703650D01*
X282186Y703359D01*
X282026Y702942D01*
X281973Y702567D01*
X283093D01*
G01X284226Y703609D02*
X284413Y703900D01*
X284573Y704067D01*
X284786Y704150D01*
X284973Y704067D01*
X285106Y703900D01*
X285213Y703650D01*
X285240Y703359D01*
X285213Y703109D01*
X285106Y702859D01*
X284946Y702650D01*
X284760Y702567D01*
X284546Y702650D01*
X284360Y702900D01*
X284253Y703275D01*
X284226Y703692D01*
X284280Y704234D01*
X284360Y704525D01*
X284493Y704817D01*
X284680Y705025D01*
X284866Y705067D01*
X285053Y704984D01*
X285186Y704775D01*
G01X286487Y709147D02*
X286647Y709397D01*
X286834Y709522D01*
X287047Y709564D01*
X287314Y709481D01*
X287501Y709272D01*
X287554Y709022D01*
X287527Y708772D01*
X287421Y708564D01*
X286887Y708147D01*
X286647Y707856D01*
X286487Y707439D01*
X286434Y707064D01*
X287554D01*
G01X288607Y707439D02*
X288767Y707231D01*
X288954Y707106D01*
X289194Y707064D01*
X289434Y707147D01*
X289621Y707314D01*
X289754Y707606D01*
X289781Y707939D01*
X289727Y708272D01*
X289594Y708481D01*
X289407Y708647D01*
X289221Y708689D01*
X289034Y708647D01*
X288794Y708481D01*
X288874Y709564D01*
X289594D01*
G01X287191Y718869D02*
Y715669D01*
G01X280991Y718869D02*
X287191D01*
G01Y715669D02*
X280991D01*
G01D02*
Y718869D01*
G01X283866Y711922D02*
Y715022D01*
X284825D01*
X285131Y714867D01*
X285323Y714660D01*
X285400Y714247D01*
X285323Y713834D01*
X285093Y713575D01*
X284825Y713420D01*
X283866D01*
G01X284825D02*
X285400Y711922D01*
G01X287733D02*
Y715022D01*
X287273Y714402D01*
G01Y711922D02*
X288193D01*
G01X290833Y715022D02*
X290526Y714919D01*
X290296Y714660D01*
X290143Y714350D01*
X290028Y713937D01*
X289990Y713472D01*
X290028Y713007D01*
X290143Y712594D01*
X290296Y712284D01*
X290526Y712025D01*
X290833Y711922D01*
X291140Y712025D01*
X291370Y712284D01*
X291523Y712594D01*
X291638Y713007D01*
X291676Y713472D01*
X291638Y713937D01*
X291523Y714350D01*
X291370Y714660D01*
X291140Y714919D01*
X290833Y715022D01*
G01X293856Y711922D02*
X293933Y712594D01*
X294048Y713162D01*
X294201Y713679D01*
X294393Y714247D01*
X294700Y715022D01*
X293166D01*
G01X296190Y712387D02*
X296420Y712129D01*
X296688Y711974D01*
X297033Y711922D01*
X297378Y712025D01*
X297646Y712232D01*
X297838Y712594D01*
X297876Y713007D01*
X297800Y713420D01*
X297608Y713679D01*
X297340Y713885D01*
X297071Y713937D01*
X296803Y713885D01*
X296458Y713679D01*
X296573Y715022D01*
X297608D01*
G01X280204Y720718D02*
Y723818D01*
X281163D01*
X281469Y723663D01*
X281661Y723456D01*
X281738Y723043D01*
X281661Y722630D01*
X281431Y722371D01*
X281163Y722216D01*
X280204D01*
G01X281163D02*
X281738Y720718D01*
G01X284071D02*
Y723818D01*
X283611Y723198D01*
G01Y720718D02*
X284531D01*
G01X287171Y723818D02*
X286864Y723715D01*
X286634Y723456D01*
X286481Y723146D01*
X286366Y722733D01*
X286328Y722268D01*
X286366Y721803D01*
X286481Y721390D01*
X286634Y721080D01*
X286864Y720821D01*
X287171Y720718D01*
X287478Y720821D01*
X287708Y721080D01*
X287861Y721390D01*
X287976Y721803D01*
X288014Y722268D01*
X287976Y722733D01*
X287861Y723146D01*
X287708Y723456D01*
X287478Y723715D01*
X287171Y723818D01*
G01X290194Y720718D02*
X290271Y721390D01*
X290386Y721958D01*
X290539Y722475D01*
X290731Y723043D01*
X291038Y723818D01*
X289504D01*
G01X292643Y722010D02*
X292911Y722371D01*
X293141Y722578D01*
X293448Y722681D01*
X293716Y722578D01*
X293908Y722371D01*
X294061Y722061D01*
X294099Y721700D01*
X294061Y721390D01*
X293908Y721080D01*
X293678Y720821D01*
X293409Y720718D01*
X293103Y720821D01*
X292834Y721131D01*
X292681Y721596D01*
X292643Y722113D01*
X292719Y722785D01*
X292834Y723146D01*
X293026Y723508D01*
X293294Y723766D01*
X293563Y723818D01*
X293831Y723715D01*
X294023Y723456D01*
G01X277040Y743756D02*
Y737556D01*
G01X281440Y729156D02*
X278440D01*
G01X281540Y726056D02*
X278340D01*
G01X281540Y732256D02*
Y726056D01*
G01X278340Y732256D02*
X281540D01*
G01X278340Y726056D02*
Y732256D01*
G01X286040Y737556D02*
X282840D01*
G01X286040Y743756D02*
Y737556D01*
G01X282840D02*
Y743756D01*
G01X290440Y729156D02*
X287440D01*
G01X290540Y726056D02*
X287340D01*
G01Y732256D02*
X290540D01*
G01X287340Y726056D02*
Y732256D01*
G01X277040D02*
Y726056D01*
G01X278340Y737556D02*
Y743756D01*
G01X281540Y737556D02*
X278340D01*
G01X281540Y743756D02*
Y737556D01*
G01X287340D02*
Y743756D01*
G01X290540Y737556D02*
X287340D01*
G01X282840Y732256D02*
X286040D01*
G01X282840Y726056D02*
Y732256D01*
G01X286040Y726056D02*
X282840D01*
G01X286040Y732256D02*
Y726056D01*
G01X274773Y746921D02*
X274618Y746691D01*
X274515Y746423D01*
Y746116D01*
X274670Y745771D01*
X274928Y745503D01*
X275238Y745311D01*
X275755Y745158D01*
X276220Y745120D01*
X276685Y745196D01*
X276995Y745311D01*
X277305Y745541D01*
X277512Y745810D01*
X277615Y746078D01*
Y746346D01*
X277512Y746615D01*
X277357Y746845D01*
X277150Y747036D01*
G01X277615Y749101D02*
X276943Y749178D01*
X276375Y749293D01*
X275858Y749446D01*
X275290Y749638D01*
X274515Y749945D01*
Y748411D01*
G01X277615Y752278D02*
X274515D01*
X275135Y751818D01*
G01X277615D02*
Y752738D01*
G01X276995Y754535D02*
X277357Y754765D01*
X277563Y755071D01*
X277615Y755416D01*
X277563Y755723D01*
X277305Y756030D01*
X276995Y756221D01*
X276685Y756260D01*
X276323Y756183D01*
X276065Y755915D01*
X275962Y755646D01*
Y755301D01*
G01Y755646D02*
X275807Y755876D01*
X275548Y756068D01*
X275238Y756145D01*
X274928Y756068D01*
X274670Y755876D01*
X274515Y755531D01*
X274567Y755186D01*
X274773Y754841D01*
G01X285940Y740656D02*
X282940D01*
G01X282840Y743756D02*
X286040D01*
G01X282866Y746921D02*
X282711Y746691D01*
X282608Y746423D01*
Y746116D01*
X282763Y745771D01*
X283021Y745503D01*
X283331Y745311D01*
X283848Y745158D01*
X284313Y745120D01*
X284778Y745196D01*
X285088Y745311D01*
X285398Y745541D01*
X285605Y745810D01*
X285708Y746078D01*
Y746346D01*
X285605Y746615D01*
X285450Y746845D01*
X285243Y747036D01*
G01X285708Y749101D02*
X285036Y749178D01*
X284468Y749293D01*
X283951Y749446D01*
X283383Y749638D01*
X282608Y749945D01*
Y748411D01*
G01Y752278D02*
X282711Y751971D01*
X282970Y751741D01*
X283280Y751588D01*
X283693Y751473D01*
X284158Y751435D01*
X284623Y751473D01*
X285036Y751588D01*
X285346Y751741D01*
X285605Y751971D01*
X285708Y752278D01*
X285605Y752585D01*
X285346Y752815D01*
X285036Y752968D01*
X284623Y753083D01*
X284158Y753121D01*
X283693Y753083D01*
X283280Y752968D01*
X282970Y752815D01*
X282711Y752585D01*
X282608Y752278D01*
G01X285708Y755301D02*
X285036Y755378D01*
X284468Y755493D01*
X283951Y755646D01*
X283383Y755838D01*
X282608Y756145D01*
Y754611D01*
G01X278340Y743756D02*
X281540D01*
G01X287340D02*
X290540D01*
G01X281615Y745311D02*
X278515D01*
Y746270D01*
X278670Y746576D01*
X278877Y746768D01*
X279290Y746845D01*
X279703Y746768D01*
X279962Y746538D01*
X280117Y746270D01*
Y745311D01*
G01Y746270D02*
X281615Y746845D01*
G01X281253Y748526D02*
X281512Y748795D01*
X281615Y749101D01*
X281512Y749408D01*
X281202Y749676D01*
X280737Y749868D01*
X280272Y749945D01*
X279703D01*
X279238Y749868D01*
X278825Y749676D01*
X278618Y749446D01*
X278515Y749178D01*
X278618Y748871D01*
X278825Y748641D01*
X279135Y748488D01*
X279548Y748411D01*
X279910Y748488D01*
X280272Y748680D01*
X280478Y748910D01*
X280530Y749178D01*
X280427Y749485D01*
X280168Y749715D01*
X279703Y749945D01*
G01X281615Y752738D02*
X278515D01*
X280737Y751320D01*
Y753236D01*
G01X281615Y755301D02*
X280943Y755378D01*
X280375Y755493D01*
X279858Y755646D01*
X279290Y755838D01*
X278515Y756145D01*
Y754611D01*
G01X289708Y745311D02*
X286608D01*
Y746270D01*
X286763Y746576D01*
X286970Y746768D01*
X287383Y746845D01*
X287796Y746768D01*
X288055Y746538D01*
X288210Y746270D01*
Y745311D01*
G01Y746270D02*
X289708Y746845D01*
G01X289346Y748526D02*
X289605Y748795D01*
X289708Y749101D01*
X289605Y749408D01*
X289295Y749676D01*
X288830Y749868D01*
X288365Y749945D01*
X287796D01*
X287331Y749868D01*
X286918Y749676D01*
X286711Y749446D01*
X286608Y749178D01*
X286711Y748871D01*
X286918Y748641D01*
X287228Y748488D01*
X287641Y748411D01*
X288003Y748488D01*
X288365Y748680D01*
X288571Y748910D01*
X288623Y749178D01*
X288520Y749485D01*
X288261Y749715D01*
X287796Y749945D01*
G01X289708Y752738D02*
X286608D01*
X288830Y751320D01*
Y753236D01*
G01X289708Y755378D02*
X286608D01*
X287228Y754918D01*
G01X289708D02*
Y755838D01*
G01X278916Y760558D02*
X278761Y760328D01*
X278658Y760060D01*
Y759753D01*
X278813Y759408D01*
X279071Y759140D01*
X279381Y758948D01*
X279898Y758795D01*
X280363Y758757D01*
X280828Y758833D01*
X281138Y758948D01*
X281448Y759178D01*
X281655Y759447D01*
X281758Y759715D01*
Y759983D01*
X281655Y760252D01*
X281500Y760482D01*
X281293Y760673D01*
G01X281758Y762738D02*
X281086Y762815D01*
X280518Y762930D01*
X280001Y763083D01*
X279433Y763275D01*
X278658Y763582D01*
Y762048D01*
G01X281758Y765915D02*
X278658D01*
X279278Y765455D01*
G01X281758D02*
Y766375D01*
G01X278658Y769015D02*
X278761Y768708D01*
X279020Y768478D01*
X279330Y768325D01*
X279743Y768210D01*
X280208Y768172D01*
X280673Y768210D01*
X281086Y768325D01*
X281396Y768478D01*
X281655Y768708D01*
X281758Y769015D01*
X281655Y769322D01*
X281396Y769552D01*
X281086Y769705D01*
X280673Y769820D01*
X280208Y769858D01*
X279743Y769820D01*
X279330Y769705D01*
X279020Y769552D01*
X278761Y769322D01*
X278658Y769015D01*
G01X287406Y760558D02*
X287251Y760328D01*
X287148Y760060D01*
Y759753D01*
X287303Y759408D01*
X287561Y759140D01*
X287871Y758948D01*
X288388Y758795D01*
X288853Y758757D01*
X289318Y758833D01*
X289628Y758948D01*
X289938Y759178D01*
X290145Y759447D01*
X290248Y759715D01*
Y759983D01*
X290145Y760252D01*
X289990Y760482D01*
X289783Y760673D01*
G01X290248Y762738D02*
X289576Y762815D01*
X289008Y762930D01*
X288491Y763083D01*
X287923Y763275D01*
X287148Y763582D01*
Y762048D01*
G01Y765915D02*
X287251Y765608D01*
X287510Y765378D01*
X287820Y765225D01*
X288233Y765110D01*
X288698Y765072D01*
X289163Y765110D01*
X289576Y765225D01*
X289886Y765378D01*
X290145Y765608D01*
X290248Y765915D01*
X290145Y766222D01*
X289886Y766452D01*
X289576Y766605D01*
X289163Y766720D01*
X288698Y766758D01*
X288233Y766720D01*
X287820Y766605D01*
X287510Y766452D01*
X287251Y766222D01*
X287148Y765915D01*
G01X290248Y769475D02*
X287148D01*
X289370Y768057D01*
Y769973D01*
G01X277758Y758948D02*
X274658D01*
Y759907D01*
X274813Y760213D01*
X275020Y760405D01*
X275433Y760482D01*
X275846Y760405D01*
X276105Y760175D01*
X276260Y759907D01*
Y758948D01*
G01Y759907D02*
X277758Y760482D01*
G01X277396Y762163D02*
X277655Y762432D01*
X277758Y762738D01*
X277655Y763045D01*
X277345Y763313D01*
X276880Y763505D01*
X276415Y763582D01*
X275846D01*
X275381Y763505D01*
X274968Y763313D01*
X274761Y763083D01*
X274658Y762815D01*
X274761Y762508D01*
X274968Y762278D01*
X275278Y762125D01*
X275691Y762048D01*
X276053Y762125D01*
X276415Y762317D01*
X276621Y762547D01*
X276673Y762815D01*
X276570Y763122D01*
X276311Y763352D01*
X275846Y763582D01*
G01X277293Y765072D02*
X277551Y765302D01*
X277706Y765570D01*
X277758Y765915D01*
X277655Y766260D01*
X277448Y766528D01*
X277086Y766720D01*
X276673Y766758D01*
X276260Y766682D01*
X276001Y766490D01*
X275795Y766222D01*
X275743Y765953D01*
X275795Y765685D01*
X276001Y765340D01*
X274658Y765455D01*
Y766490D01*
G01Y769015D02*
X274761Y768708D01*
X275020Y768478D01*
X275330Y768325D01*
X275743Y768210D01*
X276208Y768172D01*
X276673Y768210D01*
X277086Y768325D01*
X277396Y768478D01*
X277655Y768708D01*
X277758Y769015D01*
X277655Y769322D01*
X277396Y769552D01*
X277086Y769705D01*
X276673Y769820D01*
X276208Y769858D01*
X275743Y769820D01*
X275330Y769705D01*
X275020Y769552D01*
X274761Y769322D01*
X274658Y769015D01*
G01X286248Y758948D02*
X283148D01*
Y759907D01*
X283303Y760213D01*
X283510Y760405D01*
X283923Y760482D01*
X284336Y760405D01*
X284595Y760175D01*
X284750Y759907D01*
Y758948D01*
G01Y759907D02*
X286248Y760482D01*
G01X285886Y762163D02*
X286145Y762432D01*
X286248Y762738D01*
X286145Y763045D01*
X285835Y763313D01*
X285370Y763505D01*
X284905Y763582D01*
X284336D01*
X283871Y763505D01*
X283458Y763313D01*
X283251Y763083D01*
X283148Y762815D01*
X283251Y762508D01*
X283458Y762278D01*
X283768Y762125D01*
X284181Y762048D01*
X284543Y762125D01*
X284905Y762317D01*
X285111Y762547D01*
X285163Y762815D01*
X285060Y763122D01*
X284801Y763352D01*
X284336Y763582D01*
G01X286248Y766375D02*
X283148D01*
X285370Y764957D01*
Y766873D01*
G01X286248Y769475D02*
X283148D01*
X285370Y768057D01*
Y769973D01*
G01X297171Y35668D02*
Y38768D01*
X298091D01*
X298398Y38613D01*
X298628Y38251D01*
X298705Y37838D01*
X298628Y37425D01*
X298436Y37115D01*
X298091Y36960D01*
X297171D01*
G01X301881Y38510D02*
X301651Y38665D01*
X301383Y38768D01*
X301076D01*
X300731Y38613D01*
X300463Y38355D01*
X300271Y38045D01*
X300118Y37528D01*
X300080Y37063D01*
X300156Y36598D01*
X300271Y36288D01*
X300501Y35978D01*
X300770Y35771D01*
X301038Y35668D01*
X301306D01*
X301575Y35771D01*
X301805Y35926D01*
X301996Y36133D01*
G01X304598Y35668D02*
Y38768D01*
X303180Y36546D01*
X305096D01*
G01X307698Y35668D02*
Y38768D01*
X306280Y36546D01*
X308196D01*
G01X297057Y42956D02*
Y46056D01*
X297977D01*
X298284Y45901D01*
X298514Y45539D01*
X298591Y45126D01*
X298514Y44713D01*
X298322Y44403D01*
X297977Y44248D01*
X297057D01*
G01X301767Y45798D02*
X301537Y45953D01*
X301269Y46056D01*
X300962D01*
X300617Y45901D01*
X300349Y45643D01*
X300157Y45333D01*
X300004Y44816D01*
X299966Y44351D01*
X300042Y43886D01*
X300157Y43576D01*
X300387Y43266D01*
X300656Y43059D01*
X300924Y42956D01*
X301192D01*
X301461Y43059D01*
X301691Y43214D01*
X301882Y43421D01*
G01X304484Y42956D02*
Y46056D01*
X303066Y43834D01*
X304982D01*
G01X306281Y43421D02*
X306511Y43163D01*
X306779Y43008D01*
X307124Y42956D01*
X307469Y43059D01*
X307737Y43266D01*
X307929Y43628D01*
X307967Y44041D01*
X307891Y44454D01*
X307699Y44713D01*
X307431Y44919D01*
X307162Y44971D01*
X306894Y44919D01*
X306549Y44713D01*
X306664Y46056D01*
X307699D01*
G01X297171Y39794D02*
Y42894D01*
X298091D01*
X298398Y42739D01*
X298628Y42377D01*
X298705Y41964D01*
X298628Y41551D01*
X298436Y41241D01*
X298091Y41086D01*
X297171D01*
G01X301881Y42636D02*
X301651Y42791D01*
X301383Y42894D01*
X301076D01*
X300731Y42739D01*
X300463Y42481D01*
X300271Y42171D01*
X300118Y41654D01*
X300080Y41189D01*
X300156Y40724D01*
X300271Y40414D01*
X300501Y40104D01*
X300770Y39897D01*
X301038Y39794D01*
X301306D01*
X301575Y39897D01*
X301805Y40052D01*
X301996Y40259D01*
G01X304598Y39794D02*
Y42894D01*
X303180Y40672D01*
X305096D01*
G01X306395Y40414D02*
X306625Y40052D01*
X306931Y39846D01*
X307276Y39794D01*
X307583Y39846D01*
X307890Y40104D01*
X308081Y40414D01*
X308120Y40724D01*
X308043Y41086D01*
X307775Y41344D01*
X307506Y41447D01*
X307161D01*
G01X307506D02*
X307736Y41602D01*
X307928Y41861D01*
X308005Y42171D01*
X307928Y42481D01*
X307736Y42739D01*
X307391Y42894D01*
X307046Y42842D01*
X306701Y42636D01*
G01X294137Y46586D02*
Y39186D01*
G01X299397Y52751D02*
X299242Y52521D01*
X299139Y52253D01*
Y51946D01*
X299294Y51601D01*
X299552Y51333D01*
X299862Y51141D01*
X300379Y50988D01*
X300844Y50950D01*
X301309Y51026D01*
X301619Y51141D01*
X301929Y51371D01*
X302136Y51640D01*
X302239Y51908D01*
Y52176D01*
X302136Y52445D01*
X301981Y52675D01*
X301774Y52866D01*
G01X302239Y55008D02*
X299139D01*
X299759Y54548D01*
G01X302239D02*
Y55468D01*
G01X301774Y57265D02*
X302032Y57495D01*
X302187Y57763D01*
X302239Y58108D01*
X302136Y58453D01*
X301929Y58721D01*
X301567Y58913D01*
X301154Y58951D01*
X300741Y58875D01*
X300482Y58683D01*
X300276Y58415D01*
X300224Y58146D01*
X300276Y57878D01*
X300482Y57533D01*
X299139Y57648D01*
Y58683D01*
G01X299656Y60480D02*
X299346Y60710D01*
X299191Y60978D01*
X299139Y61285D01*
X299242Y61668D01*
X299501Y61936D01*
X299811Y62013D01*
X300121Y61975D01*
X300379Y61821D01*
X300896Y61055D01*
X301257Y60710D01*
X301774Y60480D01*
X302239Y60403D01*
Y62013D01*
G01X303408Y52709D02*
X303253Y52479D01*
X303150Y52211D01*
Y51904D01*
X303305Y51559D01*
X303563Y51291D01*
X303873Y51099D01*
X304390Y50946D01*
X304855Y50908D01*
X305320Y50984D01*
X305630Y51099D01*
X305940Y51329D01*
X306147Y51598D01*
X306250Y51866D01*
Y52134D01*
X306147Y52403D01*
X305992Y52633D01*
X305785Y52824D01*
G01X306250Y54966D02*
X303150D01*
X303770Y54506D01*
G01X306250D02*
Y55426D01*
G01X304958Y57338D02*
X304597Y57606D01*
X304390Y57836D01*
X304287Y58143D01*
X304390Y58411D01*
X304597Y58603D01*
X304907Y58756D01*
X305268Y58794D01*
X305578Y58756D01*
X305888Y58603D01*
X306147Y58373D01*
X306250Y58104D01*
X306147Y57798D01*
X305837Y57529D01*
X305372Y57376D01*
X304855Y57338D01*
X304183Y57414D01*
X303822Y57529D01*
X303460Y57721D01*
X303202Y57989D01*
X303150Y58258D01*
X303253Y58526D01*
X303512Y58718D01*
G01X303150Y61166D02*
X303253Y60859D01*
X303512Y60629D01*
X303822Y60476D01*
X304235Y60361D01*
X304700Y60323D01*
X305165Y60361D01*
X305578Y60476D01*
X305888Y60629D01*
X306147Y60859D01*
X306250Y61166D01*
X306147Y61473D01*
X305888Y61703D01*
X305578Y61856D01*
X305165Y61971D01*
X304700Y62009D01*
X304235Y61971D01*
X303822Y61856D01*
X303512Y61703D01*
X303253Y61473D01*
X303150Y61166D01*
G01X294137Y54990D02*
Y47590D01*
G01X290593Y74644D02*
X295193D01*
G01X290593Y69544D02*
X295193D01*
G01Y74644D02*
Y64444D01*
G01X290593D02*
Y74644D01*
G01X295193Y64444D02*
X290593D01*
G01X300593Y74644D02*
Y64444D01*
G01X295993Y74644D02*
X300593D01*
G01X295993Y69544D02*
X300593D01*
G01X295993Y64444D02*
Y74644D01*
G01X300593Y64444D02*
X295993D01*
G01X301393Y74644D02*
X305993D01*
G01X301393Y69544D02*
X305993D01*
G01X301393Y64444D02*
Y74644D01*
G01X305993Y64444D02*
X301393D01*
G01X298906Y186533D02*
Y189633D01*
X299865D01*
X300171Y189478D01*
X300363Y189271D01*
X300440Y188858D01*
X300363Y188445D01*
X300133Y188186D01*
X299865Y188031D01*
X298906D01*
G01X299865D02*
X300440Y186533D01*
G01X302773D02*
Y189633D01*
X302313Y189013D01*
G01Y186533D02*
X303233D01*
G01X305145Y189116D02*
X305375Y189426D01*
X305643Y189581D01*
X305950Y189633D01*
X306333Y189530D01*
X306601Y189271D01*
X306678Y188961D01*
X306640Y188651D01*
X306486Y188393D01*
X305720Y187876D01*
X305375Y187515D01*
X305145Y186998D01*
X305068Y186533D01*
X306678D01*
G01X308245Y189116D02*
X308475Y189426D01*
X308743Y189581D01*
X309050Y189633D01*
X309433Y189530D01*
X309701Y189271D01*
X309778Y188961D01*
X309740Y188651D01*
X309586Y188393D01*
X308820Y187876D01*
X308475Y187515D01*
X308245Y186998D01*
X308168Y186533D01*
X309778D01*
G01X311345Y187825D02*
X311613Y188186D01*
X311843Y188393D01*
X312150Y188496D01*
X312418Y188393D01*
X312610Y188186D01*
X312763Y187876D01*
X312801Y187515D01*
X312763Y187205D01*
X312610Y186895D01*
X312380Y186636D01*
X312111Y186533D01*
X311805Y186636D01*
X311536Y186946D01*
X311383Y187411D01*
X311345Y187928D01*
X311421Y188600D01*
X311536Y188961D01*
X311728Y189323D01*
X311996Y189581D01*
X312265Y189633D01*
X312533Y189530D01*
X312725Y189271D01*
G01X302709Y173725D02*
X299609D01*
Y174684D01*
X299764Y174990D01*
X299971Y175182D01*
X300384Y175259D01*
X300797Y175182D01*
X301056Y174952D01*
X301211Y174684D01*
Y173725D01*
G01Y174684D02*
X302709Y175259D01*
G01X300126Y176864D02*
X299816Y177094D01*
X299661Y177362D01*
X299609Y177669D01*
X299712Y178052D01*
X299971Y178320D01*
X300281Y178397D01*
X300591Y178359D01*
X300849Y178205D01*
X301366Y177439D01*
X301727Y177094D01*
X302244Y176864D01*
X302709Y176787D01*
Y178397D01*
G01Y180692D02*
X302657Y180960D01*
X302502Y181267D01*
X302244Y181459D01*
X301882Y181535D01*
X301521Y181459D01*
X301211Y181229D01*
X301056Y180884D01*
Y180500D01*
X300952Y180270D01*
X300694Y180079D01*
X300332Y180002D01*
X299971Y180117D01*
X299712Y180385D01*
X299609Y180692D01*
X299712Y180999D01*
X299971Y181267D01*
X300332Y181382D01*
X300694Y181305D01*
X300952Y181114D01*
X301056Y180884D01*
Y180500D01*
X301211Y180155D01*
X301521Y179925D01*
X301882Y179849D01*
X302244Y179925D01*
X302502Y180117D01*
X302657Y180424D01*
X302709Y180692D01*
G01Y183715D02*
X302037Y183792D01*
X301469Y183907D01*
X300952Y184060D01*
X300384Y184252D01*
X299609Y184559D01*
Y183025D01*
G01X306664Y173925D02*
X303564D01*
Y174884D01*
X303719Y175190D01*
X303926Y175382D01*
X304339Y175459D01*
X304752Y175382D01*
X305011Y175152D01*
X305166Y174884D01*
Y173925D01*
G01Y174884D02*
X306664Y175459D01*
G01X304081Y177064D02*
X303771Y177294D01*
X303616Y177562D01*
X303564Y177869D01*
X303667Y178252D01*
X303926Y178520D01*
X304236Y178597D01*
X304546Y178559D01*
X304804Y178405D01*
X305321Y177639D01*
X305682Y177294D01*
X306199Y177064D01*
X306664Y176987D01*
Y178597D01*
G01Y180815D02*
X305992Y180892D01*
X305424Y181007D01*
X304907Y181160D01*
X304339Y181352D01*
X303564Y181659D01*
Y180125D01*
G01X306302Y183340D02*
X306561Y183609D01*
X306664Y183915D01*
X306561Y184222D01*
X306251Y184490D01*
X305786Y184682D01*
X305321Y184759D01*
X304752D01*
X304287Y184682D01*
X303874Y184490D01*
X303667Y184260D01*
X303564Y183992D01*
X303667Y183685D01*
X303874Y183455D01*
X304184Y183302D01*
X304597Y183225D01*
X304959Y183302D01*
X305321Y183494D01*
X305527Y183724D01*
X305579Y183992D01*
X305476Y184299D01*
X305217Y184529D01*
X304752Y184759D01*
G01X298290Y173753D02*
X295190D01*
Y174712D01*
X295345Y175018D01*
X295552Y175210D01*
X295965Y175287D01*
X296378Y175210D01*
X296637Y174980D01*
X296792Y174712D01*
Y173753D01*
G01Y174712D02*
X298290Y175287D01*
G01X295707Y176892D02*
X295397Y177122D01*
X295242Y177390D01*
X295190Y177697D01*
X295293Y178080D01*
X295552Y178348D01*
X295862Y178425D01*
X296172Y178387D01*
X296430Y178233D01*
X296947Y177467D01*
X297308Y177122D01*
X297825Y176892D01*
X298290Y176815D01*
Y178425D01*
G01X297670Y179877D02*
X298032Y180107D01*
X298238Y180413D01*
X298290Y180758D01*
X298238Y181065D01*
X297980Y181372D01*
X297670Y181563D01*
X297360Y181602D01*
X296998Y181525D01*
X296740Y181257D01*
X296637Y180988D01*
Y180643D01*
G01Y180988D02*
X296482Y181218D01*
X296223Y181410D01*
X295913Y181487D01*
X295603Y181410D01*
X295345Y181218D01*
X295190Y180873D01*
X295242Y180528D01*
X295448Y180183D01*
G01X298290Y183820D02*
X295190D01*
X295810Y183360D01*
G01X298290D02*
Y184280D01*
G01X294143Y173680D02*
X291043D01*
Y174639D01*
X291198Y174945D01*
X291405Y175137D01*
X291818Y175214D01*
X292231Y175137D01*
X292490Y174907D01*
X292645Y174639D01*
Y173680D01*
G01Y174639D02*
X294143Y175214D01*
G01X291560Y176819D02*
X291250Y177049D01*
X291095Y177317D01*
X291043Y177624D01*
X291146Y178007D01*
X291405Y178275D01*
X291715Y178352D01*
X292025Y178314D01*
X292283Y178160D01*
X292800Y177394D01*
X293161Y177049D01*
X293678Y176819D01*
X294143Y176742D01*
Y178352D01*
G01X293523Y179804D02*
X293885Y180034D01*
X294091Y180340D01*
X294143Y180685D01*
X294091Y180992D01*
X293833Y181299D01*
X293523Y181490D01*
X293213Y181529D01*
X292851Y181452D01*
X292593Y181184D01*
X292490Y180915D01*
Y180570D01*
G01Y180915D02*
X292335Y181145D01*
X292076Y181337D01*
X291766Y181414D01*
X291456Y181337D01*
X291198Y181145D01*
X291043Y180800D01*
X291095Y180455D01*
X291301Y180110D01*
G01X294143Y184207D02*
X291043D01*
X293265Y182789D01*
Y184705D01*
G01X298310Y196578D02*
X298258Y196271D01*
X298052Y196003D01*
X297742Y195773D01*
X297380Y195620D01*
X296967Y195543D01*
X296553D01*
X296140Y195620D01*
X295778Y195773D01*
X295468Y196003D01*
X295262Y196271D01*
X295210Y196578D01*
X295262Y196885D01*
X295468Y197153D01*
X295778Y197383D01*
X296140Y197536D01*
X296553Y197613D01*
X296967D01*
X297380Y197536D01*
X297742Y197383D01*
X298052Y197153D01*
X298258Y196885D01*
X298310Y196578D01*
G01X297897Y198873D02*
X298155Y199180D01*
X298310Y199525D01*
Y199831D01*
X298155Y200138D01*
X297897Y200368D01*
X297535Y200483D01*
X297173Y200406D01*
X296863Y200215D01*
X296657Y199870D01*
X296553Y199410D01*
X296347Y199141D01*
X295985Y199026D01*
X295623Y199103D01*
X295365Y199295D01*
X295210Y199563D01*
Y199831D01*
X295313Y200100D01*
X295572Y200330D01*
G01X295468Y203621D02*
X295313Y203391D01*
X295210Y203123D01*
Y202816D01*
X295365Y202471D01*
X295623Y202203D01*
X295933Y202011D01*
X296450Y201858D01*
X296915Y201820D01*
X297380Y201896D01*
X297690Y202011D01*
X298000Y202241D01*
X298207Y202510D01*
X298310Y202778D01*
Y203046D01*
X298207Y203315D01*
X298052Y203545D01*
X297845Y203736D01*
G01X297018Y205150D02*
X296657Y205418D01*
X296450Y205648D01*
X296347Y205955D01*
X296450Y206223D01*
X296657Y206415D01*
X296967Y206568D01*
X297328Y206606D01*
X297638Y206568D01*
X297948Y206415D01*
X298207Y206185D01*
X298310Y205916D01*
X298207Y205610D01*
X297897Y205341D01*
X297432Y205188D01*
X296915Y205150D01*
X296243Y205226D01*
X295882Y205341D01*
X295520Y205533D01*
X295262Y205801D01*
X295210Y206070D01*
X295313Y206338D01*
X295572Y206530D01*
G01X294154Y201608D02*
X291054D01*
Y202567D01*
X291209Y202873D01*
X291416Y203065D01*
X291829Y203142D01*
X292242Y203065D01*
X292501Y202835D01*
X292656Y202567D01*
Y201608D01*
G01Y202567D02*
X294154Y203142D01*
G01Y205475D02*
X291054D01*
X291674Y205015D01*
G01X294154D02*
Y205935D01*
G01X291054Y208575D02*
X291157Y208268D01*
X291416Y208038D01*
X291726Y207885D01*
X292139Y207770D01*
X292604Y207732D01*
X293069Y207770D01*
X293482Y207885D01*
X293792Y208038D01*
X294051Y208268D01*
X294154Y208575D01*
X294051Y208882D01*
X293792Y209112D01*
X293482Y209265D01*
X293069Y209380D01*
X292604Y209418D01*
X292139Y209380D01*
X291726Y209265D01*
X291416Y209112D01*
X291157Y208882D01*
X291054Y208575D01*
G01X293689Y210832D02*
X293947Y211062D01*
X294102Y211330D01*
X294154Y211675D01*
X294051Y212020D01*
X293844Y212288D01*
X293482Y212480D01*
X293069Y212518D01*
X292656Y212442D01*
X292397Y212250D01*
X292191Y211982D01*
X292139Y211713D01*
X292191Y211445D01*
X292397Y211100D01*
X291054Y211215D01*
Y212250D01*
G01X293689Y213932D02*
X293947Y214162D01*
X294102Y214430D01*
X294154Y214775D01*
X294051Y215120D01*
X293844Y215388D01*
X293482Y215580D01*
X293069Y215618D01*
X292656Y215542D01*
X292397Y215350D01*
X292191Y215082D01*
X292139Y214813D01*
X292191Y214545D01*
X292397Y214200D01*
X291054Y214315D01*
Y215350D01*
G01X302264Y195175D02*
X299164D01*
Y196134D01*
X299319Y196440D01*
X299526Y196632D01*
X299939Y196709D01*
X300352Y196632D01*
X300611Y196402D01*
X300766Y196134D01*
Y195175D01*
G01Y196134D02*
X302264Y196709D01*
G01Y199042D02*
X299164D01*
X299784Y198582D01*
G01X302264D02*
Y199502D01*
G01X299164Y202142D02*
X299267Y201835D01*
X299526Y201605D01*
X299836Y201452D01*
X300249Y201337D01*
X300714Y201299D01*
X301179Y201337D01*
X301592Y201452D01*
X301902Y201605D01*
X302161Y201835D01*
X302264Y202142D01*
X302161Y202449D01*
X301902Y202679D01*
X301592Y202832D01*
X301179Y202947D01*
X300714Y202985D01*
X300249Y202947D01*
X299836Y202832D01*
X299526Y202679D01*
X299267Y202449D01*
X299164Y202142D01*
G01X301799Y204399D02*
X302057Y204629D01*
X302212Y204897D01*
X302264Y205242D01*
X302161Y205587D01*
X301954Y205855D01*
X301592Y206047D01*
X301179Y206085D01*
X300766Y206009D01*
X300507Y205817D01*
X300301Y205549D01*
X300249Y205280D01*
X300301Y205012D01*
X300507Y204667D01*
X299164Y204782D01*
Y205817D01*
G01X302264Y208265D02*
X301592Y208342D01*
X301024Y208457D01*
X300507Y208610D01*
X299939Y208802D01*
X299164Y209109D01*
Y207575D01*
G01X304855Y216223D02*
X305689D01*
Y204425D01*
X314091D01*
G01X290742Y361229D02*
X290929Y361520D01*
X291089Y361687D01*
X291302Y361770D01*
X291489Y361687D01*
X291622Y361520D01*
X291729Y361270D01*
X291756Y360979D01*
X291729Y360729D01*
X291622Y360479D01*
X291462Y360270D01*
X291276Y360187D01*
X291062Y360270D01*
X290876Y360520D01*
X290769Y360895D01*
X290742Y361312D01*
X290796Y361854D01*
X290876Y362145D01*
X291009Y362437D01*
X291196Y362645D01*
X291382Y362687D01*
X291569Y362604D01*
X291702Y362395D01*
G01X292942Y361229D02*
X293129Y361520D01*
X293289Y361687D01*
X293502Y361770D01*
X293689Y361687D01*
X293822Y361520D01*
X293929Y361270D01*
X293956Y360979D01*
X293929Y360729D01*
X293822Y360479D01*
X293662Y360270D01*
X293476Y360187D01*
X293262Y360270D01*
X293076Y360520D01*
X292969Y360895D01*
X292942Y361312D01*
X292996Y361854D01*
X293076Y362145D01*
X293209Y362437D01*
X293396Y362645D01*
X293582Y362687D01*
X293769Y362604D01*
X293902Y362395D01*
G01X295320Y374940D02*
X306230D01*
G01X295320Y384840D02*
Y374940D01*
G01X290742Y373698D02*
Y367498D01*
G01X303542Y373698D02*
X306742D01*
G01Y367498D02*
X303542D01*
G01D02*
Y373698D01*
G01X295542D02*
X298742D01*
G01D02*
Y367498D01*
G01D02*
X295542D01*
G01D02*
Y373698D01*
G01X291542D02*
X294742D01*
G01D02*
Y367498D01*
G01D02*
X291542D01*
G01D02*
Y373698D01*
G01X299542D02*
X302742D01*
G01D02*
Y367498D01*
G01D02*
X299542D01*
G01D02*
Y373698D01*
G01X297519Y393004D02*
Y378543D01*
G01D02*
X309209D01*
G01X290329Y383848D02*
Y377648D01*
G01X294329Y383848D02*
Y377648D01*
G01D02*
X291129D01*
G01D02*
Y383848D01*
G01D02*
X294329D01*
G01X296510Y401336D02*
X296203Y401388D01*
X295935Y401594D01*
X295705Y401904D01*
X295552Y402266D01*
X295475Y402679D01*
Y403093D01*
X295552Y403506D01*
X295705Y403868D01*
X295935Y404178D01*
X296203Y404384D01*
X296510Y404436D01*
X296817Y404384D01*
X297085Y404178D01*
X297315Y403868D01*
X297468Y403506D01*
X297545Y403093D01*
Y402679D01*
X297468Y402266D01*
X297315Y401904D01*
X297085Y401594D01*
X296817Y401388D01*
X296510Y401336D01*
G01X298805Y401749D02*
X299112Y401491D01*
X299457Y401336D01*
X299763D01*
X300070Y401491D01*
X300300Y401749D01*
X300415Y402111D01*
X300338Y402473D01*
X300147Y402783D01*
X299802Y402989D01*
X299342Y403093D01*
X299073Y403299D01*
X298958Y403661D01*
X299035Y404023D01*
X299227Y404281D01*
X299495Y404436D01*
X299763D01*
X300032Y404333D01*
X300262Y404074D01*
G01X303553Y404178D02*
X303323Y404333D01*
X303055Y404436D01*
X302748D01*
X302403Y404281D01*
X302135Y404023D01*
X301943Y403713D01*
X301790Y403196D01*
X301752Y402731D01*
X301828Y402266D01*
X301943Y401956D01*
X302173Y401646D01*
X302442Y401439D01*
X302710Y401336D01*
X302978D01*
X303247Y401439D01*
X303477Y401594D01*
X303668Y401801D01*
G01X304967D02*
X305197Y401543D01*
X305465Y401388D01*
X305810Y401336D01*
X306155Y401439D01*
X306423Y401646D01*
X306615Y402008D01*
X306653Y402421D01*
X306577Y402834D01*
X306385Y403093D01*
X306117Y403299D01*
X305848Y403351D01*
X305580Y403299D01*
X305235Y403093D01*
X305350Y404436D01*
X306385D01*
G01X309209Y393004D02*
X297519D01*
G01X295703Y405117D02*
Y408217D01*
X296662D01*
X296968Y408062D01*
X297160Y407855D01*
X297237Y407442D01*
X297160Y407029D01*
X296930Y406770D01*
X296662Y406615D01*
X295703D01*
G01X296662D02*
X297237Y405117D01*
G01X299570D02*
Y408217D01*
X299110Y407597D01*
G01Y405117D02*
X300030D01*
G01X302670Y408217D02*
X302363Y408114D01*
X302133Y407855D01*
X301980Y407545D01*
X301865Y407132D01*
X301827Y406667D01*
X301865Y406202D01*
X301980Y405789D01*
X302133Y405479D01*
X302363Y405220D01*
X302670Y405117D01*
X302977Y405220D01*
X303207Y405479D01*
X303360Y405789D01*
X303475Y406202D01*
X303513Y406667D01*
X303475Y407132D01*
X303360Y407545D01*
X303207Y407855D01*
X302977Y408114D01*
X302670Y408217D01*
G01X304927Y405582D02*
X305157Y405324D01*
X305425Y405169D01*
X305770Y405117D01*
X306115Y405220D01*
X306383Y405427D01*
X306575Y405789D01*
X306613Y406202D01*
X306537Y406615D01*
X306345Y406874D01*
X306077Y407080D01*
X305808Y407132D01*
X305540Y407080D01*
X305195Y406874D01*
X305310Y408217D01*
X306345D01*
G01X308870Y405117D02*
Y408217D01*
X308410Y407597D01*
G01Y405117D02*
X309330D01*
G01X299662Y400029D02*
X305862D01*
G01Y396829D02*
X299662D01*
G01D02*
Y400029D01*
G01X291978Y420093D02*
X291823Y419863D01*
X291720Y419595D01*
Y419288D01*
X291875Y418943D01*
X292133Y418675D01*
X292443Y418483D01*
X292960Y418330D01*
X293425Y418292D01*
X293890Y418368D01*
X294200Y418483D01*
X294510Y418713D01*
X294717Y418982D01*
X294820Y419250D01*
Y419518D01*
X294717Y419787D01*
X294562Y420017D01*
X294355Y420208D01*
G01X294820Y422350D02*
X294768Y422618D01*
X294613Y422925D01*
X294355Y423117D01*
X293993Y423193D01*
X293632Y423117D01*
X293322Y422887D01*
X293167Y422542D01*
Y422158D01*
X293063Y421928D01*
X292805Y421737D01*
X292443Y421660D01*
X292082Y421775D01*
X291823Y422043D01*
X291720Y422350D01*
X291823Y422657D01*
X292082Y422925D01*
X292443Y423040D01*
X292805Y422963D01*
X293063Y422772D01*
X293167Y422542D01*
Y422158D01*
X293322Y421813D01*
X293632Y421583D01*
X293993Y421507D01*
X294355Y421583D01*
X294613Y421775D01*
X294768Y422082D01*
X294820Y422350D01*
G01Y425910D02*
X291720D01*
X293942Y424492D01*
Y426408D01*
G01X294820Y428550D02*
X294768Y428818D01*
X294613Y429125D01*
X294355Y429317D01*
X293993Y429393D01*
X293632Y429317D01*
X293322Y429087D01*
X293167Y428742D01*
Y428358D01*
X293063Y428128D01*
X292805Y427937D01*
X292443Y427860D01*
X292082Y427975D01*
X291823Y428243D01*
X291720Y428550D01*
X291823Y428857D01*
X292082Y429125D01*
X292443Y429240D01*
X292805Y429163D01*
X293063Y428972D01*
X293167Y428742D01*
Y428358D01*
X293322Y428013D01*
X293632Y427783D01*
X293993Y427707D01*
X294355Y427783D01*
X294613Y427975D01*
X294768Y428282D01*
X294820Y428550D01*
G01X298742Y418215D02*
X295642D01*
Y419174D01*
X295797Y419480D01*
X296004Y419672D01*
X296417Y419749D01*
X296830Y419672D01*
X297089Y419442D01*
X297244Y419174D01*
Y418215D01*
G01Y419174D02*
X298742Y419749D01*
G01Y422082D02*
X295642D01*
X296262Y421622D01*
G01X298742D02*
Y422542D01*
G01X296159Y424454D02*
X295849Y424684D01*
X295694Y424952D01*
X295642Y425259D01*
X295745Y425642D01*
X296004Y425910D01*
X296314Y425987D01*
X296624Y425949D01*
X296882Y425795D01*
X297399Y425029D01*
X297760Y424684D01*
X298277Y424454D01*
X298742Y424377D01*
Y425987D01*
G01X298122Y427439D02*
X298484Y427669D01*
X298690Y427975D01*
X298742Y428320D01*
X298690Y428627D01*
X298432Y428934D01*
X298122Y429125D01*
X297812Y429164D01*
X297450Y429087D01*
X297192Y428819D01*
X297089Y428550D01*
Y428205D01*
G01Y428550D02*
X296934Y428780D01*
X296675Y428972D01*
X296365Y429049D01*
X296055Y428972D01*
X295797Y428780D01*
X295642Y428435D01*
X295694Y428090D01*
X295900Y427745D01*
G01X298742Y431382D02*
X298690Y431650D01*
X298535Y431957D01*
X298277Y432149D01*
X297915Y432225D01*
X297554Y432149D01*
X297244Y431919D01*
X297089Y431574D01*
Y431190D01*
X296985Y430960D01*
X296727Y430769D01*
X296365Y430692D01*
X296004Y430807D01*
X295745Y431075D01*
X295642Y431382D01*
X295745Y431689D01*
X296004Y431957D01*
X296365Y432072D01*
X296727Y431995D01*
X296985Y431804D01*
X297089Y431574D01*
Y431190D01*
X297244Y430845D01*
X297554Y430615D01*
X297915Y430539D01*
X298277Y430615D01*
X298535Y430807D01*
X298690Y431114D01*
X298742Y431382D01*
G01X303102Y422503D02*
Y425603D01*
X304061D01*
X304367Y425448D01*
X304559Y425241D01*
X304636Y424828D01*
X304559Y424415D01*
X304329Y424156D01*
X304061Y424001D01*
X303102D01*
G01X304061D02*
X304636Y422503D01*
G01X306969D02*
Y425603D01*
X306509Y424983D01*
G01Y422503D02*
X307429D01*
G01X309341Y425086D02*
X309571Y425396D01*
X309839Y425551D01*
X310146Y425603D01*
X310529Y425500D01*
X310797Y425241D01*
X310874Y424931D01*
X310836Y424621D01*
X310682Y424363D01*
X309916Y423846D01*
X309571Y423485D01*
X309341Y422968D01*
X309264Y422503D01*
X310874D01*
G01X312326Y423123D02*
X312556Y422761D01*
X312862Y422555D01*
X313207Y422503D01*
X313514Y422555D01*
X313821Y422813D01*
X314012Y423123D01*
X314051Y423433D01*
X313974Y423795D01*
X313706Y424053D01*
X313437Y424156D01*
X313092D01*
G01X313437D02*
X313667Y424311D01*
X313859Y424570D01*
X313936Y424880D01*
X313859Y425190D01*
X313667Y425448D01*
X313322Y425603D01*
X312977Y425551D01*
X312632Y425345D01*
G01X315426Y422968D02*
X315656Y422710D01*
X315924Y422555D01*
X316269Y422503D01*
X316614Y422606D01*
X316882Y422813D01*
X317074Y423175D01*
X317112Y423588D01*
X317036Y424001D01*
X316844Y424260D01*
X316576Y424466D01*
X316307Y424518D01*
X316039Y424466D01*
X315694Y424260D01*
X315809Y425603D01*
X316844D01*
G01X304493Y433266D02*
X304263Y433421D01*
X303995Y433524D01*
X303688D01*
X303343Y433369D01*
X303075Y433111D01*
X302883Y432801D01*
X302730Y432284D01*
X302692Y431819D01*
X302768Y431354D01*
X302883Y431044D01*
X303113Y430734D01*
X303382Y430527D01*
X303650Y430424D01*
X303918D01*
X304187Y430527D01*
X304417Y430682D01*
X304608Y430889D01*
G01X306750Y430424D02*
X307018Y430476D01*
X307325Y430631D01*
X307517Y430889D01*
X307593Y431251D01*
X307517Y431612D01*
X307287Y431922D01*
X306942Y432077D01*
X306558D01*
X306328Y432181D01*
X306137Y432439D01*
X306060Y432801D01*
X306175Y433162D01*
X306443Y433421D01*
X306750Y433524D01*
X307057Y433421D01*
X307325Y433162D01*
X307440Y432801D01*
X307363Y432439D01*
X307172Y432181D01*
X306942Y432077D01*
X306558D01*
X306213Y431922D01*
X305983Y431612D01*
X305907Y431251D01*
X305983Y430889D01*
X306175Y430631D01*
X306482Y430476D01*
X306750Y430424D01*
G01X310310D02*
Y433524D01*
X308892Y431302D01*
X310808D01*
G01X312222Y433007D02*
X312452Y433317D01*
X312720Y433472D01*
X313027Y433524D01*
X313410Y433421D01*
X313678Y433162D01*
X313755Y432852D01*
X313717Y432542D01*
X313563Y432284D01*
X312797Y431767D01*
X312452Y431406D01*
X312222Y430889D01*
X312145Y430424D01*
X313755D01*
G01X303252Y426560D02*
Y429660D01*
X304211D01*
X304517Y429505D01*
X304709Y429298D01*
X304786Y428885D01*
X304709Y428472D01*
X304479Y428213D01*
X304211Y428058D01*
X303252D01*
G01X304211D02*
X304786Y426560D01*
G01X307119D02*
Y429660D01*
X306659Y429040D01*
G01Y426560D02*
X307579D01*
G01X310219D02*
Y429660D01*
X309759Y429040D01*
G01Y426560D02*
X310679D01*
G01X313319Y429660D02*
X313012Y429557D01*
X312782Y429298D01*
X312629Y428988D01*
X312514Y428575D01*
X312476Y428110D01*
X312514Y427645D01*
X312629Y427232D01*
X312782Y426922D01*
X313012Y426663D01*
X313319Y426560D01*
X313626Y426663D01*
X313856Y426922D01*
X314009Y427232D01*
X314124Y427645D01*
X314162Y428110D01*
X314124Y428575D01*
X314009Y428988D01*
X313856Y429298D01*
X313626Y429557D01*
X313319Y429660D01*
G01X316419D02*
X316112Y429557D01*
X315882Y429298D01*
X315729Y428988D01*
X315614Y428575D01*
X315576Y428110D01*
X315614Y427645D01*
X315729Y427232D01*
X315882Y426922D01*
X316112Y426663D01*
X316419Y426560D01*
X316726Y426663D01*
X316956Y426922D01*
X317109Y427232D01*
X317224Y427645D01*
X317262Y428110D01*
X317224Y428575D01*
X317109Y428988D01*
X316956Y429298D01*
X316726Y429557D01*
X316419Y429660D01*
G01X293258Y452752D02*
X290158D01*
Y453711D01*
X290313Y454017D01*
X290520Y454209D01*
X290933Y454286D01*
X291346Y454209D01*
X291605Y453979D01*
X291760Y453711D01*
Y452752D01*
G01Y453711D02*
X293258Y454286D01*
G01X292638Y455776D02*
X293000Y456006D01*
X293206Y456312D01*
X293258Y456657D01*
X293206Y456964D01*
X292948Y457271D01*
X292638Y457462D01*
X292328Y457501D01*
X291966Y457424D01*
X291708Y457156D01*
X291605Y456887D01*
Y456542D01*
G01Y456887D02*
X291450Y457117D01*
X291191Y457309D01*
X290881Y457386D01*
X290571Y457309D01*
X290313Y457117D01*
X290158Y456772D01*
X290210Y456427D01*
X290416Y456082D01*
G01X293258Y460179D02*
X290158D01*
X292380Y458761D01*
Y460677D01*
G01X291966Y462091D02*
X291605Y462359D01*
X291398Y462589D01*
X291295Y462896D01*
X291398Y463164D01*
X291605Y463356D01*
X291915Y463509D01*
X292276Y463547D01*
X292586Y463509D01*
X292896Y463356D01*
X293155Y463126D01*
X293258Y462857D01*
X293155Y462551D01*
X292845Y462282D01*
X292380Y462129D01*
X291863Y462091D01*
X291191Y462167D01*
X290830Y462282D01*
X290468Y462474D01*
X290210Y462742D01*
X290158Y463011D01*
X290261Y463279D01*
X290520Y463471D01*
G01X297306Y452752D02*
X294206D01*
Y453711D01*
X294361Y454017D01*
X294568Y454209D01*
X294981Y454286D01*
X295394Y454209D01*
X295653Y453979D01*
X295808Y453711D01*
Y452752D01*
G01Y453711D02*
X297306Y454286D01*
G01X294723Y455891D02*
X294413Y456121D01*
X294258Y456389D01*
X294206Y456696D01*
X294309Y457079D01*
X294568Y457347D01*
X294878Y457424D01*
X295188Y457386D01*
X295446Y457232D01*
X295963Y456466D01*
X296324Y456121D01*
X296841Y455891D01*
X297306Y455814D01*
Y457424D01*
G01X296841Y458876D02*
X297099Y459106D01*
X297254Y459374D01*
X297306Y459719D01*
X297203Y460064D01*
X296996Y460332D01*
X296634Y460524D01*
X296221Y460562D01*
X295808Y460486D01*
X295549Y460294D01*
X295343Y460026D01*
X295291Y459757D01*
X295343Y459489D01*
X295549Y459144D01*
X294206Y459259D01*
Y460294D01*
G01X296841Y461976D02*
X297099Y462206D01*
X297254Y462474D01*
X297306Y462819D01*
X297203Y463164D01*
X296996Y463432D01*
X296634Y463624D01*
X296221Y463662D01*
X295808Y463586D01*
X295549Y463394D01*
X295343Y463126D01*
X295291Y462857D01*
X295343Y462589D01*
X295549Y462244D01*
X294206Y462359D01*
Y463394D01*
G01X296005Y470432D02*
Y473432D01*
G01X292905Y470332D02*
Y473532D01*
G01X299105Y470332D02*
X292905D01*
G01X299105Y473532D02*
Y470332D01*
G01X292905Y473532D02*
X299105D01*
G01X295964Y474739D02*
Y477739D01*
G01X292864Y474639D02*
Y477839D01*
G01X299064Y474639D02*
X292864D01*
G01X299064Y477839D02*
Y474639D01*
G01X292864Y477839D02*
X299064D01*
G01X303879Y497069D02*
X303569Y497299D01*
X303414Y497567D01*
X303362Y497874D01*
X303465Y498257D01*
X303724Y498525D01*
X304034Y498602D01*
X304344Y498564D01*
X304602Y498410D01*
X305119Y497644D01*
X305480Y497299D01*
X305997Y497069D01*
X306462Y496992D01*
Y498602D01*
G01Y500897D02*
X303362D01*
X303982Y500437D01*
G01X306462D02*
Y501357D01*
G01X298855Y490045D02*
X298545Y490275D01*
X298390Y490543D01*
X298338Y490850D01*
X298441Y491233D01*
X298700Y491501D01*
X299010Y491578D01*
X299320Y491540D01*
X299578Y491386D01*
X300095Y490620D01*
X300456Y490275D01*
X300973Y490045D01*
X301438Y489968D01*
Y491578D01*
G01X298855Y493145D02*
X298545Y493375D01*
X298390Y493643D01*
X298338Y493950D01*
X298441Y494333D01*
X298700Y494601D01*
X299010Y494678D01*
X299320Y494640D01*
X299578Y494486D01*
X300095Y493720D01*
X300456Y493375D01*
X300973Y493145D01*
X301438Y493068D01*
Y494678D01*
G01X299154Y500219D02*
X298844Y500449D01*
X298689Y500717D01*
X298637Y501024D01*
X298740Y501407D01*
X298999Y501675D01*
X299309Y501752D01*
X299619Y501714D01*
X299877Y501560D01*
X300394Y500794D01*
X300755Y500449D01*
X301272Y500219D01*
X301737Y500142D01*
Y501752D01*
G01X298637Y504047D02*
X298740Y503740D01*
X298999Y503510D01*
X299309Y503357D01*
X299722Y503242D01*
X300187Y503204D01*
X300652Y503242D01*
X301065Y503357D01*
X301375Y503510D01*
X301634Y503740D01*
X301737Y504047D01*
X301634Y504354D01*
X301375Y504584D01*
X301065Y504737D01*
X300652Y504852D01*
X300187Y504890D01*
X299722Y504852D01*
X299309Y504737D01*
X298999Y504584D01*
X298740Y504354D01*
X298637Y504047D01*
G01X296424Y568541D02*
Y493345D01*
G01X306462Y505671D02*
X303362D01*
X303982Y505211D01*
G01X306462D02*
Y506131D01*
G01X306100Y508119D02*
X306359Y508388D01*
X306462Y508694D01*
X306359Y509001D01*
X306049Y509269D01*
X305584Y509461D01*
X305119Y509538D01*
X304550D01*
X304085Y509461D01*
X303672Y509269D01*
X303465Y509039D01*
X303362Y508771D01*
X303465Y508464D01*
X303672Y508234D01*
X303982Y508081D01*
X304395Y508004D01*
X304757Y508081D01*
X305119Y508273D01*
X305325Y508503D01*
X305377Y508771D01*
X305274Y509078D01*
X305015Y509308D01*
X304550Y509538D01*
G01X301737Y508821D02*
X298637D01*
X299257Y508361D01*
G01X301737D02*
Y509281D01*
G01Y511921D02*
X301685Y512189D01*
X301530Y512496D01*
X301272Y512688D01*
X300910Y512764D01*
X300549Y512688D01*
X300239Y512458D01*
X300084Y512113D01*
Y511729D01*
X299980Y511499D01*
X299722Y511308D01*
X299360Y511231D01*
X298999Y511346D01*
X298740Y511614D01*
X298637Y511921D01*
X298740Y512228D01*
X298999Y512496D01*
X299360Y512611D01*
X299722Y512534D01*
X299980Y512343D01*
X300084Y512113D01*
Y511729D01*
X300239Y511384D01*
X300549Y511154D01*
X300910Y511078D01*
X301272Y511154D01*
X301530Y511346D01*
X301685Y511653D01*
X301737Y511921D01*
G01X306462Y511970D02*
X303362D01*
X303982Y511510D01*
G01X306462D02*
Y512430D01*
G01Y514993D02*
X305790Y515070D01*
X305222Y515185D01*
X304705Y515338D01*
X304137Y515530D01*
X303362Y515837D01*
Y514303D01*
G01X306462Y518269D02*
X303362D01*
X303982Y517809D01*
G01X306462D02*
Y518729D01*
G01X305997Y520526D02*
X306255Y520756D01*
X306410Y521024D01*
X306462Y521369D01*
X306359Y521714D01*
X306152Y521982D01*
X305790Y522174D01*
X305377Y522212D01*
X304964Y522136D01*
X304705Y521944D01*
X304499Y521676D01*
X304447Y521407D01*
X304499Y521139D01*
X304705Y520794D01*
X303362Y520909D01*
Y521944D01*
G01X301737Y517120D02*
X298637D01*
X299257Y516660D01*
G01X301737D02*
Y517580D01*
G01X300445Y519492D02*
X300084Y519760D01*
X299877Y519990D01*
X299774Y520297D01*
X299877Y520565D01*
X300084Y520757D01*
X300394Y520910D01*
X300755Y520948D01*
X301065Y520910D01*
X301375Y520757D01*
X301634Y520527D01*
X301737Y520258D01*
X301634Y519952D01*
X301324Y519683D01*
X300859Y519530D01*
X300342Y519492D01*
X299670Y519568D01*
X299309Y519683D01*
X298947Y519875D01*
X298689Y520143D01*
X298637Y520412D01*
X298740Y520680D01*
X298999Y520872D01*
G01X306462Y524569D02*
X303362D01*
X303982Y524109D01*
G01X306462D02*
Y525029D01*
G01X305842Y526826D02*
X306204Y527056D01*
X306410Y527362D01*
X306462Y527707D01*
X306410Y528014D01*
X306152Y528321D01*
X305842Y528512D01*
X305532Y528551D01*
X305170Y528474D01*
X304912Y528206D01*
X304809Y527937D01*
Y527592D01*
G01Y527937D02*
X304654Y528167D01*
X304395Y528359D01*
X304085Y528436D01*
X303775Y528359D01*
X303517Y528167D01*
X303362Y527822D01*
X303414Y527477D01*
X303620Y527132D01*
G01X301737Y529718D02*
X298637D01*
X299257Y529258D01*
G01X301737D02*
Y530178D01*
G01X299154Y532090D02*
X298844Y532320D01*
X298689Y532588D01*
X298637Y532895D01*
X298740Y533278D01*
X298999Y533546D01*
X299309Y533623D01*
X299619Y533585D01*
X299877Y533431D01*
X300394Y532665D01*
X300755Y532320D01*
X301272Y532090D01*
X301737Y532013D01*
Y533623D01*
G01Y523419D02*
X298637D01*
X299257Y522959D01*
G01X301737D02*
Y523879D01*
G01Y526979D02*
X298637D01*
X300859Y525561D01*
Y527477D01*
G01X306462Y530868D02*
X303362D01*
X303982Y530408D01*
G01X306462D02*
Y531328D01*
G01Y533968D02*
X303362D01*
X303982Y533508D01*
G01X306462D02*
Y534428D01*
G01X300445Y544338D02*
X300084Y544606D01*
X299877Y544836D01*
X299774Y545143D01*
X299877Y545411D01*
X300084Y545603D01*
X300394Y545756D01*
X300755Y545794D01*
X301065Y545756D01*
X301375Y545603D01*
X301634Y545373D01*
X301737Y545104D01*
X301634Y544798D01*
X301324Y544529D01*
X300859Y544376D01*
X300342Y544338D01*
X299670Y544414D01*
X299309Y544529D01*
X298947Y544721D01*
X298689Y544989D01*
X298637Y545258D01*
X298740Y545526D01*
X298999Y545718D01*
G01X306100Y534965D02*
X306359Y535234D01*
X306462Y535540D01*
X306359Y535847D01*
X306049Y536115D01*
X305584Y536307D01*
X305119Y536384D01*
X304550D01*
X304085Y536307D01*
X303672Y536115D01*
X303465Y535885D01*
X303362Y535617D01*
X303465Y535310D01*
X303672Y535080D01*
X303982Y534927D01*
X304395Y534850D01*
X304757Y534927D01*
X305119Y535119D01*
X305325Y535349D01*
X305377Y535617D01*
X305274Y535924D01*
X305015Y536154D01*
X304550Y536384D01*
G01X301737Y538767D02*
X301685Y539035D01*
X301530Y539342D01*
X301272Y539534D01*
X300910Y539610D01*
X300549Y539534D01*
X300239Y539304D01*
X300084Y538959D01*
Y538575D01*
X299980Y538345D01*
X299722Y538154D01*
X299360Y538077D01*
X298999Y538192D01*
X298740Y538460D01*
X298637Y538767D01*
X298740Y539074D01*
X298999Y539342D01*
X299360Y539457D01*
X299722Y539380D01*
X299980Y539189D01*
X300084Y538959D01*
Y538575D01*
X300239Y538230D01*
X300549Y538000D01*
X300910Y537924D01*
X301272Y538000D01*
X301530Y538192D01*
X301685Y538499D01*
X301737Y538767D01*
G01X306462Y541839D02*
X305790Y541916D01*
X305222Y542031D01*
X304705Y542184D01*
X304137Y542376D01*
X303362Y542683D01*
Y541149D01*
G01X301737Y536017D02*
X298637D01*
X299257Y535557D01*
G01X301737D02*
Y536477D01*
G01X298637Y539117D02*
X298740Y538810D01*
X298999Y538580D01*
X299309Y538427D01*
X299722Y538312D01*
X300187Y538274D01*
X300652Y538312D01*
X301065Y538427D01*
X301375Y538580D01*
X301634Y538810D01*
X301737Y539117D01*
X301634Y539424D01*
X301375Y539654D01*
X301065Y539807D01*
X300652Y539922D01*
X300187Y539960D01*
X299722Y539922D01*
X299309Y539807D01*
X298999Y539654D01*
X298740Y539424D01*
X298637Y539117D01*
G01X305997Y547372D02*
X306255Y547602D01*
X306410Y547870D01*
X306462Y548215D01*
X306359Y548560D01*
X306152Y548828D01*
X305790Y549020D01*
X305377Y549058D01*
X304964Y548982D01*
X304705Y548790D01*
X304499Y548522D01*
X304447Y548253D01*
X304499Y547985D01*
X304705Y547640D01*
X303362Y547755D01*
Y548790D01*
G01X306462Y560814D02*
X303362D01*
X303982Y560354D01*
G01X306462D02*
Y561274D01*
G01X301737Y551825D02*
X298637D01*
X300859Y550407D01*
Y552323D01*
G01X305842Y553672D02*
X306204Y553902D01*
X306410Y554208D01*
X306462Y554553D01*
X306410Y554860D01*
X306152Y555167D01*
X305842Y555358D01*
X305532Y555397D01*
X305170Y555320D01*
X304912Y555052D01*
X304809Y554783D01*
Y554438D01*
G01Y554783D02*
X304654Y555013D01*
X304395Y555205D01*
X304085Y555282D01*
X303775Y555205D01*
X303517Y555013D01*
X303362Y554668D01*
X303414Y554323D01*
X303620Y553978D01*
G01X299154Y556936D02*
X298844Y557166D01*
X298689Y557434D01*
X298637Y557741D01*
X298740Y558124D01*
X298999Y558392D01*
X299309Y558469D01*
X299619Y558431D01*
X299877Y558277D01*
X300394Y557511D01*
X300755Y557166D01*
X301272Y556936D01*
X301737Y556859D01*
Y558469D01*
G01X294363Y577029D02*
X291263Y577987D01*
X294363Y578945D01*
G01X293278Y578600D02*
Y577374D01*
G01X300175Y596206D02*
Y599406D01*
G01X306375Y596206D02*
X300175D01*
G01X303275Y596306D02*
Y599306D01*
G01X296562Y583793D02*
Y586893D01*
X297482D01*
X297789Y586738D01*
X298019Y586376D01*
X298096Y585963D01*
X298019Y585550D01*
X297827Y585240D01*
X297482Y585085D01*
X296562D01*
G01X301272Y586635D02*
X301042Y586790D01*
X300774Y586893D01*
X300467D01*
X300122Y586738D01*
X299854Y586480D01*
X299662Y586170D01*
X299509Y585653D01*
X299471Y585188D01*
X299547Y584723D01*
X299662Y584413D01*
X299892Y584103D01*
X300161Y583896D01*
X300429Y583793D01*
X300697D01*
X300966Y583896D01*
X301196Y584051D01*
X301387Y584258D01*
G01X303529Y583793D02*
Y586893D01*
X303069Y586273D01*
G01Y583793D02*
X303989D01*
G01X300864Y595407D02*
Y588007D01*
G01X292164Y595407D02*
X309564D01*
G01X292164Y588007D02*
Y595407D01*
G01X309564Y588007D02*
X292164D01*
G01X295986Y627734D02*
Y601356D01*
G01X301324Y605194D02*
X303824D01*
X303324Y605514D01*
G01X301324D02*
Y604874D01*
G01X303407Y603501D02*
X303657Y603341D01*
X303782Y603154D01*
X303824Y602941D01*
X303741Y602674D01*
X303532Y602487D01*
X303282Y602434D01*
X303032Y602461D01*
X302824Y602567D01*
X302407Y603101D01*
X302116Y603341D01*
X301699Y603501D01*
X301324Y603554D01*
Y602434D01*
G01X304126Y603013D02*
X306227D01*
G01X304126Y605014D02*
Y603013D01*
G01X302234Y610199D02*
X300234D01*
G01X297472Y607064D02*
X300472D01*
G01X297372Y610164D02*
X300572D01*
G01X297372Y603964D02*
Y610164D01*
G01X300572Y603964D02*
X297372D01*
G01X300572Y610164D02*
Y603964D01*
G01X300175Y599406D02*
X306375D01*
G01X302490Y614320D02*
X302676Y614111D01*
X302890Y614028D01*
X303103Y614111D01*
X303290Y614361D01*
X303423Y614736D01*
X303476Y615111D01*
Y615570D01*
X303423Y615945D01*
X303290Y616278D01*
X303130Y616445D01*
X302943Y616528D01*
X302730Y616445D01*
X302570Y616278D01*
X302463Y616028D01*
X302410Y615695D01*
X302463Y615403D01*
X302596Y615111D01*
X302756Y614945D01*
X302943Y614903D01*
X303156Y614986D01*
X303316Y615195D01*
X303476Y615570D01*
G01X304126Y615415D02*
Y613714D01*
G01X306227Y615415D02*
X304126D01*
G01X297733Y626891D02*
Y629991D01*
X298653D01*
X298960Y629836D01*
X299190Y629474D01*
X299267Y629061D01*
X299190Y628648D01*
X298998Y628338D01*
X298653Y628183D01*
X297733D01*
G01X302443Y629733D02*
X302213Y629888D01*
X301945Y629991D01*
X301638D01*
X301293Y629836D01*
X301025Y629578D01*
X300833Y629268D01*
X300680Y628751D01*
X300642Y628286D01*
X300718Y627821D01*
X300833Y627511D01*
X301063Y627201D01*
X301332Y626994D01*
X301600Y626891D01*
X301868D01*
X302137Y626994D01*
X302367Y627149D01*
X302558Y627356D01*
G01X303972Y629474D02*
X304202Y629784D01*
X304470Y629939D01*
X304777Y629991D01*
X305160Y629888D01*
X305428Y629629D01*
X305505Y629319D01*
X305467Y629009D01*
X305313Y628751D01*
X304547Y628234D01*
X304202Y627873D01*
X303972Y627356D01*
X303895Y626891D01*
X305505D01*
G01X306957Y627356D02*
X307187Y627098D01*
X307455Y626943D01*
X307800Y626891D01*
X308145Y626994D01*
X308413Y627201D01*
X308605Y627563D01*
X308643Y627976D01*
X308567Y628389D01*
X308375Y628648D01*
X308107Y628854D01*
X307838Y628906D01*
X307570Y628854D01*
X307225Y628648D01*
X307340Y629991D01*
X308375D01*
G01X303611Y622377D02*
Y625377D01*
G01X300511Y622277D02*
Y625477D01*
G01X306711Y622277D02*
X300511D01*
G01Y625477D02*
X306711D01*
G01X299968Y613995D02*
X296868D01*
Y614915D01*
X297023Y615222D01*
X297385Y615452D01*
X297798Y615529D01*
X298211Y615452D01*
X298521Y615260D01*
X298676Y614915D01*
Y613995D01*
G01X297126Y618705D02*
X296971Y618475D01*
X296868Y618207D01*
Y617900D01*
X297023Y617555D01*
X297281Y617287D01*
X297591Y617095D01*
X298108Y616942D01*
X298573Y616904D01*
X299038Y616980D01*
X299348Y617095D01*
X299658Y617325D01*
X299865Y617594D01*
X299968Y617862D01*
Y618130D01*
X299865Y618399D01*
X299710Y618629D01*
X299503Y618820D01*
G01X299968Y621422D02*
X296868D01*
X299090Y620004D01*
Y621920D01*
G01X299240Y638456D02*
Y643456D01*
G01X301442Y632643D02*
X301287Y632413D01*
X301184Y632145D01*
Y631838D01*
X301339Y631493D01*
X301597Y631225D01*
X301907Y631033D01*
X302424Y630880D01*
X302889Y630842D01*
X303354Y630918D01*
X303664Y631033D01*
X303974Y631263D01*
X304181Y631532D01*
X304284Y631800D01*
Y632068D01*
X304181Y632337D01*
X304026Y632567D01*
X303819Y632758D01*
G01Y634057D02*
X304077Y634287D01*
X304232Y634555D01*
X304284Y634900D01*
X304181Y635245D01*
X303974Y635513D01*
X303612Y635705D01*
X303199Y635743D01*
X302786Y635667D01*
X302527Y635475D01*
X302321Y635207D01*
X302269Y634938D01*
X302321Y634670D01*
X302527Y634325D01*
X301184Y634440D01*
Y635475D01*
G01X304284Y638000D02*
X304232Y638268D01*
X304077Y638575D01*
X303819Y638767D01*
X303457Y638843D01*
X303096Y638767D01*
X302786Y638537D01*
X302631Y638192D01*
Y637808D01*
X302527Y637578D01*
X302269Y637387D01*
X301907Y637310D01*
X301546Y637425D01*
X301287Y637693D01*
X301184Y638000D01*
X301287Y638307D01*
X301546Y638575D01*
X301907Y638690D01*
X302269Y638613D01*
X302527Y638422D01*
X302631Y638192D01*
Y637808D01*
X302786Y637463D01*
X303096Y637233D01*
X303457Y637157D01*
X303819Y637233D01*
X304077Y637425D01*
X304232Y637732D01*
X304284Y638000D01*
G01X301184Y641100D02*
X301287Y640793D01*
X301546Y640563D01*
X301856Y640410D01*
X302269Y640295D01*
X302734Y640257D01*
X303199Y640295D01*
X303612Y640410D01*
X303922Y640563D01*
X304181Y640793D01*
X304284Y641100D01*
X304181Y641407D01*
X303922Y641637D01*
X303612Y641790D01*
X303199Y641905D01*
X302734Y641943D01*
X302269Y641905D01*
X301856Y641790D01*
X301546Y641637D01*
X301287Y641407D01*
X301184Y641100D01*
G01X290140Y652856D02*
Y702456D01*
G01X339740Y652856D02*
X290140D01*
G01Y702456D02*
X338440D01*
G01X299422Y713363D02*
X301647D01*
Y714411D01*
G01X299274Y715612D02*
Y718812D01*
G01X305474Y715612D02*
X299274D01*
G01Y718812D02*
X305474D01*
G01D02*
Y715612D01*
G01X295192Y719480D02*
Y722680D01*
G01X301392Y719480D02*
X295192D01*
G01X301392Y722680D02*
Y719480D01*
G01X295192Y722680D02*
X301392D01*
G01X290540Y732256D02*
Y726056D01*
G01X304040Y737556D02*
X300840D01*
G01X304040Y743756D02*
Y737556D01*
G01X300840D02*
Y743756D01*
G01X299440Y729156D02*
X296440D01*
G01X299540Y726056D02*
X296340D01*
G01X299540Y732256D02*
Y726056D01*
G01X296340Y732256D02*
X299540D01*
G01X296340Y726056D02*
Y732256D01*
G01X295040Y737556D02*
X291840D01*
G01D02*
Y743756D01*
G01X295040D02*
Y737556D01*
G01X308440Y729156D02*
X305440D01*
G01X308540Y726056D02*
X305340D01*
G01Y732256D02*
X308540D01*
G01X305340Y726056D02*
Y732256D01*
G01X290540Y743756D02*
Y737556D01*
G01X296340D02*
Y743756D01*
G01X299540Y737556D02*
X296340D01*
G01X299540Y743756D02*
Y737556D01*
G01X291840Y732256D02*
X295040D01*
G01X291840Y726056D02*
Y732256D01*
G01X295040Y726056D02*
X291840D01*
G01X295040Y732256D02*
Y726056D01*
G01X305340Y737556D02*
Y743756D01*
G01X308540Y737556D02*
X305340D01*
G01X303940Y740656D02*
X300940D01*
G01X300840Y743756D02*
X304040D01*
G01X290866Y746921D02*
X290711Y746691D01*
X290608Y746423D01*
Y746116D01*
X290763Y745771D01*
X291021Y745503D01*
X291331Y745311D01*
X291848Y745158D01*
X292313Y745120D01*
X292778Y745196D01*
X293088Y745311D01*
X293398Y745541D01*
X293605Y745810D01*
X293708Y746078D01*
Y746346D01*
X293605Y746615D01*
X293450Y746845D01*
X293243Y747036D01*
G01X293708Y749101D02*
X293036Y749178D01*
X292468Y749293D01*
X291951Y749446D01*
X291383Y749638D01*
X290608Y749945D01*
Y748411D01*
G01Y752278D02*
X290711Y751971D01*
X290970Y751741D01*
X291280Y751588D01*
X291693Y751473D01*
X292158Y751435D01*
X292623Y751473D01*
X293036Y751588D01*
X293346Y751741D01*
X293605Y751971D01*
X293708Y752278D01*
X293605Y752585D01*
X293346Y752815D01*
X293036Y752968D01*
X292623Y753083D01*
X292158Y753121D01*
X291693Y753083D01*
X291280Y752968D01*
X290970Y752815D01*
X290711Y752585D01*
X290608Y752278D01*
G01X293708Y755378D02*
X290608D01*
X291228Y754918D01*
G01X293708D02*
Y755838D01*
G01X294940Y740656D02*
X291940D01*
G01X291840Y743756D02*
X295040D01*
G01X298656Y747677D02*
X298501Y747447D01*
X298398Y747179D01*
Y746872D01*
X298553Y746527D01*
X298811Y746259D01*
X299121Y746067D01*
X299638Y745914D01*
X300103Y745876D01*
X300568Y745952D01*
X300878Y746067D01*
X301188Y746297D01*
X301395Y746566D01*
X301498Y746834D01*
Y747102D01*
X301395Y747371D01*
X301240Y747601D01*
X301033Y747792D01*
G01X300206Y749206D02*
X299845Y749474D01*
X299638Y749704D01*
X299535Y750011D01*
X299638Y750279D01*
X299845Y750471D01*
X300155Y750624D01*
X300516Y750662D01*
X300826Y750624D01*
X301136Y750471D01*
X301395Y750241D01*
X301498Y749972D01*
X301395Y749666D01*
X301085Y749397D01*
X300620Y749244D01*
X300103Y749206D01*
X299431Y749282D01*
X299070Y749397D01*
X298708Y749589D01*
X298450Y749857D01*
X298398Y750126D01*
X298501Y750394D01*
X298760Y750586D01*
G01X301136Y752382D02*
X301395Y752651D01*
X301498Y752957D01*
X301395Y753264D01*
X301085Y753532D01*
X300620Y753724D01*
X300155Y753801D01*
X299586D01*
X299121Y753724D01*
X298708Y753532D01*
X298501Y753302D01*
X298398Y753034D01*
X298501Y752727D01*
X298708Y752497D01*
X299018Y752344D01*
X299431Y752267D01*
X299793Y752344D01*
X300155Y752536D01*
X300361Y752766D01*
X300413Y753034D01*
X300310Y753341D01*
X300051Y753571D01*
X299586Y753801D01*
G01X301033Y755291D02*
X301291Y755521D01*
X301446Y755789D01*
X301498Y756134D01*
X301395Y756479D01*
X301188Y756747D01*
X300826Y756939D01*
X300413Y756977D01*
X300000Y756901D01*
X299741Y756709D01*
X299535Y756441D01*
X299483Y756172D01*
X299535Y755904D01*
X299741Y755559D01*
X298398Y755674D01*
Y756709D01*
G01X296340Y743756D02*
X299540D01*
G01X305767Y746067D02*
X302667D01*
Y747026D01*
X302822Y747332D01*
X303029Y747524D01*
X303442Y747601D01*
X303855Y747524D01*
X304114Y747294D01*
X304269Y747026D01*
Y746067D01*
G01Y747026D02*
X305767Y747601D01*
G01X305405Y749282D02*
X305664Y749551D01*
X305767Y749857D01*
X305664Y750164D01*
X305354Y750432D01*
X304889Y750624D01*
X304424Y750701D01*
X303855D01*
X303390Y750624D01*
X302977Y750432D01*
X302770Y750202D01*
X302667Y749934D01*
X302770Y749627D01*
X302977Y749397D01*
X303287Y749244D01*
X303700Y749167D01*
X304062Y749244D01*
X304424Y749436D01*
X304630Y749666D01*
X304682Y749934D01*
X304579Y750241D01*
X304320Y750471D01*
X303855Y750701D01*
G01X302667Y753034D02*
X302770Y752727D01*
X303029Y752497D01*
X303339Y752344D01*
X303752Y752229D01*
X304217Y752191D01*
X304682Y752229D01*
X305095Y752344D01*
X305405Y752497D01*
X305664Y752727D01*
X305767Y753034D01*
X305664Y753341D01*
X305405Y753571D01*
X305095Y753724D01*
X304682Y753839D01*
X304217Y753877D01*
X303752Y753839D01*
X303339Y753724D01*
X303029Y753571D01*
X302770Y753341D01*
X302667Y753034D01*
G01X305767Y756594D02*
X302667D01*
X304889Y755176D01*
Y757092D01*
G01X305340Y743756D02*
X308540D01*
G01X295406Y760558D02*
X295251Y760328D01*
X295148Y760060D01*
Y759753D01*
X295303Y759408D01*
X295561Y759140D01*
X295871Y758948D01*
X296388Y758795D01*
X296853Y758757D01*
X297318Y758833D01*
X297628Y758948D01*
X297938Y759178D01*
X298145Y759447D01*
X298248Y759715D01*
Y759983D01*
X298145Y760252D01*
X297990Y760482D01*
X297783Y760673D01*
G01X296956Y762087D02*
X296595Y762355D01*
X296388Y762585D01*
X296285Y762892D01*
X296388Y763160D01*
X296595Y763352D01*
X296905Y763505D01*
X297266Y763543D01*
X297576Y763505D01*
X297886Y763352D01*
X298145Y763122D01*
X298248Y762853D01*
X298145Y762547D01*
X297835Y762278D01*
X297370Y762125D01*
X296853Y762087D01*
X296181Y762163D01*
X295820Y762278D01*
X295458Y762470D01*
X295200Y762738D01*
X295148Y763007D01*
X295251Y763275D01*
X295510Y763467D01*
G01X297886Y765263D02*
X298145Y765532D01*
X298248Y765838D01*
X298145Y766145D01*
X297835Y766413D01*
X297370Y766605D01*
X296905Y766682D01*
X296336D01*
X295871Y766605D01*
X295458Y766413D01*
X295251Y766183D01*
X295148Y765915D01*
X295251Y765608D01*
X295458Y765378D01*
X295768Y765225D01*
X296181Y765148D01*
X296543Y765225D01*
X296905Y765417D01*
X297111Y765647D01*
X297163Y765915D01*
X297060Y766222D01*
X296801Y766452D01*
X296336Y766682D01*
G01X298248Y769015D02*
X298196Y769283D01*
X298041Y769590D01*
X297783Y769782D01*
X297421Y769858D01*
X297060Y769782D01*
X296750Y769552D01*
X296595Y769207D01*
Y768823D01*
X296491Y768593D01*
X296233Y768402D01*
X295871Y768325D01*
X295510Y768440D01*
X295251Y768708D01*
X295148Y769015D01*
X295251Y769322D01*
X295510Y769590D01*
X295871Y769705D01*
X296233Y769628D01*
X296491Y769437D01*
X296595Y769207D01*
Y768823D01*
X296750Y768478D01*
X297060Y768248D01*
X297421Y768172D01*
X297783Y768248D01*
X298041Y768440D01*
X298196Y768747D01*
X298248Y769015D01*
G01X303606Y760558D02*
X303451Y760328D01*
X303348Y760060D01*
Y759753D01*
X303503Y759408D01*
X303761Y759140D01*
X304071Y758948D01*
X304588Y758795D01*
X305053Y758757D01*
X305518Y758833D01*
X305828Y758948D01*
X306138Y759178D01*
X306345Y759447D01*
X306448Y759715D01*
Y759983D01*
X306345Y760252D01*
X306190Y760482D01*
X305983Y760673D01*
G01X305156Y762087D02*
X304795Y762355D01*
X304588Y762585D01*
X304485Y762892D01*
X304588Y763160D01*
X304795Y763352D01*
X305105Y763505D01*
X305466Y763543D01*
X305776Y763505D01*
X306086Y763352D01*
X306345Y763122D01*
X306448Y762853D01*
X306345Y762547D01*
X306035Y762278D01*
X305570Y762125D01*
X305053Y762087D01*
X304381Y762163D01*
X304020Y762278D01*
X303658Y762470D01*
X303400Y762738D01*
X303348Y763007D01*
X303451Y763275D01*
X303710Y763467D01*
G01X305156Y765187D02*
X304795Y765455D01*
X304588Y765685D01*
X304485Y765992D01*
X304588Y766260D01*
X304795Y766452D01*
X305105Y766605D01*
X305466Y766643D01*
X305776Y766605D01*
X306086Y766452D01*
X306345Y766222D01*
X306448Y765953D01*
X306345Y765647D01*
X306035Y765378D01*
X305570Y765225D01*
X305053Y765187D01*
X304381Y765263D01*
X304020Y765378D01*
X303658Y765570D01*
X303400Y765838D01*
X303348Y766107D01*
X303451Y766375D01*
X303710Y766567D01*
G01X306448Y768938D02*
X305776Y769015D01*
X305208Y769130D01*
X304691Y769283D01*
X304123Y769475D01*
X303348Y769782D01*
Y768248D01*
G01X294248Y758948D02*
X291148D01*
Y759907D01*
X291303Y760213D01*
X291510Y760405D01*
X291923Y760482D01*
X292336Y760405D01*
X292595Y760175D01*
X292750Y759907D01*
Y758948D01*
G01Y759907D02*
X294248Y760482D01*
G01X293886Y762163D02*
X294145Y762432D01*
X294248Y762738D01*
X294145Y763045D01*
X293835Y763313D01*
X293370Y763505D01*
X292905Y763582D01*
X292336D01*
X291871Y763505D01*
X291458Y763313D01*
X291251Y763083D01*
X291148Y762815D01*
X291251Y762508D01*
X291458Y762278D01*
X291768Y762125D01*
X292181Y762048D01*
X292543Y762125D01*
X292905Y762317D01*
X293111Y762547D01*
X293163Y762815D01*
X293060Y763122D01*
X292801Y763352D01*
X292336Y763582D01*
G01X293628Y765072D02*
X293990Y765302D01*
X294196Y765608D01*
X294248Y765953D01*
X294196Y766260D01*
X293938Y766567D01*
X293628Y766758D01*
X293318Y766797D01*
X292956Y766720D01*
X292698Y766452D01*
X292595Y766183D01*
Y765838D01*
G01Y766183D02*
X292440Y766413D01*
X292181Y766605D01*
X291871Y766682D01*
X291561Y766605D01*
X291303Y766413D01*
X291148Y766068D01*
X291200Y765723D01*
X291406Y765378D01*
G01X294248Y769015D02*
X294196Y769283D01*
X294041Y769590D01*
X293783Y769782D01*
X293421Y769858D01*
X293060Y769782D01*
X292750Y769552D01*
X292595Y769207D01*
Y768823D01*
X292491Y768593D01*
X292233Y768402D01*
X291871Y768325D01*
X291510Y768440D01*
X291251Y768708D01*
X291148Y769015D01*
X291251Y769322D01*
X291510Y769590D01*
X291871Y769705D01*
X292233Y769628D01*
X292491Y769437D01*
X292595Y769207D01*
Y768823D01*
X292750Y768478D01*
X293060Y768248D01*
X293421Y768172D01*
X293783Y768248D01*
X294041Y768440D01*
X294196Y768747D01*
X294248Y769015D01*
G01X302448Y758948D02*
X299348D01*
Y759907D01*
X299503Y760213D01*
X299710Y760405D01*
X300123Y760482D01*
X300536Y760405D01*
X300795Y760175D01*
X300950Y759907D01*
Y758948D01*
G01Y759907D02*
X302448Y760482D01*
G01X302086Y762163D02*
X302345Y762432D01*
X302448Y762738D01*
X302345Y763045D01*
X302035Y763313D01*
X301570Y763505D01*
X301105Y763582D01*
X300536D01*
X300071Y763505D01*
X299658Y763313D01*
X299451Y763083D01*
X299348Y762815D01*
X299451Y762508D01*
X299658Y762278D01*
X299968Y762125D01*
X300381Y762048D01*
X300743Y762125D01*
X301105Y762317D01*
X301311Y762547D01*
X301363Y762815D01*
X301260Y763122D01*
X301001Y763352D01*
X300536Y763582D01*
G01X301828Y765072D02*
X302190Y765302D01*
X302396Y765608D01*
X302448Y765953D01*
X302396Y766260D01*
X302138Y766567D01*
X301828Y766758D01*
X301518Y766797D01*
X301156Y766720D01*
X300898Y766452D01*
X300795Y766183D01*
Y765838D01*
G01Y766183D02*
X300640Y766413D01*
X300381Y766605D01*
X300071Y766682D01*
X299761Y766605D01*
X299503Y766413D01*
X299348Y766068D01*
X299400Y765723D01*
X299606Y765378D01*
G01X299865Y768287D02*
X299555Y768517D01*
X299400Y768785D01*
X299348Y769092D01*
X299451Y769475D01*
X299710Y769743D01*
X300020Y769820D01*
X300330Y769782D01*
X300588Y769628D01*
X301105Y768862D01*
X301466Y768517D01*
X301983Y768287D01*
X302448Y768210D01*
Y769820D01*
G01X312857Y34796D02*
Y37896D01*
X313777D01*
X314084Y37741D01*
X314314Y37379D01*
X314391Y36966D01*
X314314Y36553D01*
X314122Y36243D01*
X313777Y36088D01*
X312857D01*
G01X315957Y37896D02*
Y34796D01*
X317491D01*
G01X319824D02*
Y37896D01*
X319364Y37276D01*
G01Y34796D02*
X320284D01*
G01X322847D02*
X322924Y35468D01*
X323039Y36036D01*
X323192Y36553D01*
X323384Y37121D01*
X323691Y37896D01*
X322157D01*
G01X307408Y53462D02*
X307253Y53232D01*
X307150Y52964D01*
Y52657D01*
X307305Y52312D01*
X307563Y52044D01*
X307873Y51852D01*
X308390Y51699D01*
X308855Y51661D01*
X309320Y51737D01*
X309630Y51852D01*
X309940Y52082D01*
X310147Y52351D01*
X310250Y52619D01*
Y52887D01*
X310147Y53156D01*
X309992Y53386D01*
X309785Y53577D01*
G01X310250Y55719D02*
X307150D01*
X307770Y55259D01*
G01X310250D02*
Y56179D01*
G01X309785Y57976D02*
X310043Y58206D01*
X310198Y58474D01*
X310250Y58819D01*
X310147Y59164D01*
X309940Y59432D01*
X309578Y59624D01*
X309165Y59662D01*
X308752Y59586D01*
X308493Y59394D01*
X308287Y59126D01*
X308235Y58857D01*
X308287Y58589D01*
X308493Y58244D01*
X307150Y58359D01*
Y59394D01*
G01X309888Y61267D02*
X310147Y61536D01*
X310250Y61842D01*
X310147Y62149D01*
X309837Y62417D01*
X309372Y62609D01*
X308907Y62686D01*
X308338D01*
X307873Y62609D01*
X307460Y62417D01*
X307253Y62187D01*
X307150Y61919D01*
X307253Y61612D01*
X307460Y61382D01*
X307770Y61229D01*
X308183Y61152D01*
X308545Y61229D01*
X308907Y61421D01*
X309113Y61651D01*
X309165Y61919D01*
X309062Y62226D01*
X308803Y62456D01*
X308338Y62686D01*
G01X311408Y53462D02*
X311253Y53232D01*
X311150Y52964D01*
Y52657D01*
X311305Y52312D01*
X311563Y52044D01*
X311873Y51852D01*
X312390Y51699D01*
X312855Y51661D01*
X313320Y51737D01*
X313630Y51852D01*
X313940Y52082D01*
X314147Y52351D01*
X314250Y52619D01*
Y52887D01*
X314147Y53156D01*
X313992Y53386D01*
X313785Y53577D01*
G01X314250Y55719D02*
X311150D01*
X311770Y55259D01*
G01X314250D02*
Y56179D01*
G01X313785Y57976D02*
X314043Y58206D01*
X314198Y58474D01*
X314250Y58819D01*
X314147Y59164D01*
X313940Y59432D01*
X313578Y59624D01*
X313165Y59662D01*
X312752Y59586D01*
X312493Y59394D01*
X312287Y59126D01*
X312235Y58857D01*
X312287Y58589D01*
X312493Y58244D01*
X311150Y58359D01*
Y59394D01*
G01X314250Y61919D02*
X311150D01*
X311770Y61459D01*
G01X314250D02*
Y62379D01*
G01X315637Y53696D02*
X315482Y53466D01*
X315379Y53198D01*
Y52891D01*
X315534Y52546D01*
X315792Y52278D01*
X316102Y52086D01*
X316619Y51933D01*
X317084Y51895D01*
X317549Y51971D01*
X317859Y52086D01*
X318169Y52316D01*
X318376Y52585D01*
X318479Y52853D01*
Y53121D01*
X318376Y53390D01*
X318221Y53620D01*
X318014Y53811D01*
G01X318479Y55953D02*
X315379D01*
X315999Y55493D01*
G01X318479D02*
Y56413D01*
G01Y58976D02*
X317807Y59053D01*
X317239Y59168D01*
X316722Y59321D01*
X316154Y59513D01*
X315379Y59820D01*
Y58286D01*
G01X318479Y62076D02*
X317807Y62153D01*
X317239Y62268D01*
X316722Y62421D01*
X316154Y62613D01*
X315379Y62920D01*
Y61386D01*
G01X320236Y53696D02*
X320081Y53466D01*
X319978Y53198D01*
Y52891D01*
X320133Y52546D01*
X320391Y52278D01*
X320701Y52086D01*
X321218Y51933D01*
X321683Y51895D01*
X322148Y51971D01*
X322458Y52086D01*
X322768Y52316D01*
X322975Y52585D01*
X323078Y52853D01*
Y53121D01*
X322975Y53390D01*
X322820Y53620D01*
X322613Y53811D01*
G01X323078Y55953D02*
X319978D01*
X320598Y55493D01*
G01X323078D02*
Y56413D01*
G01Y58976D02*
X322406Y59053D01*
X321838Y59168D01*
X321321Y59321D01*
X320753Y59513D01*
X319978Y59820D01*
Y58286D01*
G01X322458Y61310D02*
X322820Y61540D01*
X323026Y61846D01*
X323078Y62191D01*
X323026Y62498D01*
X322768Y62805D01*
X322458Y62996D01*
X322148Y63035D01*
X321786Y62958D01*
X321528Y62690D01*
X321425Y62421D01*
Y62076D01*
G01Y62421D02*
X321270Y62651D01*
X321011Y62843D01*
X320701Y62920D01*
X320391Y62843D01*
X320133Y62651D01*
X319978Y62306D01*
X320030Y61961D01*
X320236Y61616D01*
G01X318066Y72704D02*
Y66504D01*
G01X314866Y72704D02*
X318066D01*
G01X317966Y69604D02*
X314966D01*
G01X314866Y66504D02*
Y72704D01*
G01X318066Y66504D02*
X314866D01*
G01X310866Y72704D02*
X314066D01*
G01X313966Y69604D02*
X310966D01*
G01X310866Y66504D02*
Y72704D01*
G01X314066D02*
Y66504D01*
G01D02*
X310866D01*
G01X306866Y72704D02*
X310066D01*
G01X309966Y69604D02*
X306966D01*
G01X306866Y66504D02*
Y72704D01*
G01X310066D02*
Y66504D01*
G01D02*
X306866D01*
G01X318866Y72704D02*
X322066D01*
G01X321966Y69604D02*
X318966D01*
G01X318866Y66504D02*
Y72704D01*
G01X322066Y66504D02*
X318866D01*
G01X305993Y74644D02*
Y64444D01*
G01X318010Y163720D02*
Y180840D01*
G01X381060Y163720D02*
X318010D01*
G01X322052Y164646D02*
X318952D01*
Y165605D01*
X319107Y165911D01*
X319314Y166103D01*
X319727Y166180D01*
X320140Y166103D01*
X320399Y165873D01*
X320554Y165605D01*
Y164646D01*
G01Y165605D02*
X322052Y166180D01*
G01Y168513D02*
X322000Y168781D01*
X321845Y169088D01*
X321587Y169280D01*
X321225Y169356D01*
X320864Y169280D01*
X320554Y169050D01*
X320399Y168705D01*
Y168321D01*
X320295Y168091D01*
X320037Y167900D01*
X319675Y167823D01*
X319314Y167938D01*
X319055Y168206D01*
X318952Y168513D01*
X319055Y168820D01*
X319314Y169088D01*
X319675Y169203D01*
X320037Y169126D01*
X320295Y168935D01*
X320399Y168705D01*
Y168321D01*
X320554Y167976D01*
X320864Y167746D01*
X321225Y167670D01*
X321587Y167746D01*
X321845Y167938D01*
X322000Y168245D01*
X322052Y168513D01*
G01Y172073D02*
X318952D01*
X321174Y170655D01*
Y172571D01*
G01X319147Y175293D02*
X320730Y180293D01*
X322313Y175293D01*
G01X321743Y177043D02*
X319717D01*
G01X318010Y174230D02*
X324580D01*
G01X318010Y180840D02*
X340850D01*
G01X311193Y206874D02*
X308659D01*
Y211874D01*
X311193D01*
G01X310179Y209457D02*
X308659D01*
G01X309110Y228990D02*
Y313550D01*
G01X340350Y228990D02*
X309110D01*
G01X313957Y234545D02*
Y237645D01*
X314916D01*
X315222Y237490D01*
X315414Y237283D01*
X315491Y236870D01*
X315414Y236457D01*
X315184Y236198D01*
X314916Y236043D01*
X313957D01*
G01X314916D02*
X315491Y234545D01*
G01X317747D02*
X317824Y235217D01*
X317939Y235785D01*
X318092Y236302D01*
X318284Y236870D01*
X318591Y237645D01*
X317057D01*
G01X320924Y234545D02*
X321192Y234597D01*
X321499Y234752D01*
X321691Y235010D01*
X321767Y235372D01*
X321691Y235733D01*
X321461Y236043D01*
X321116Y236198D01*
X320732D01*
X320502Y236302D01*
X320311Y236560D01*
X320234Y236922D01*
X320349Y237283D01*
X320617Y237542D01*
X320924Y237645D01*
X321231Y237542D01*
X321499Y237283D01*
X321614Y236922D01*
X321537Y236560D01*
X321346Y236302D01*
X321116Y236198D01*
X320732D01*
X320387Y236043D01*
X320157Y235733D01*
X320081Y235372D01*
X320157Y235010D01*
X320349Y234752D01*
X320656Y234597D01*
X320924Y234545D01*
G01X313957Y230450D02*
Y233550D01*
X314916D01*
X315222Y233395D01*
X315414Y233188D01*
X315491Y232775D01*
X315414Y232362D01*
X315184Y232103D01*
X314916Y231948D01*
X313957D01*
G01X314916D02*
X315491Y230450D01*
G01X317824D02*
Y233550D01*
X317364Y232930D01*
G01Y230450D02*
X318284D01*
G01X320924D02*
Y233550D01*
X320464Y232930D01*
G01Y230450D02*
X321384D01*
G01X324484D02*
Y233550D01*
X323066Y231328D01*
X324982D01*
G01X317876Y250384D02*
X317721Y250154D01*
X317618Y249886D01*
Y249579D01*
X317773Y249234D01*
X318031Y248966D01*
X318341Y248774D01*
X318858Y248621D01*
X319323Y248583D01*
X319788Y248659D01*
X320098Y248774D01*
X320408Y249004D01*
X320615Y249273D01*
X320718Y249541D01*
Y249809D01*
X320615Y250078D01*
X320460Y250308D01*
X320253Y250499D01*
G01X320718Y252564D02*
X320046Y252641D01*
X319478Y252756D01*
X318961Y252909D01*
X318393Y253101D01*
X317618Y253408D01*
Y251874D01*
G01Y255741D02*
X317721Y255434D01*
X317980Y255204D01*
X318290Y255051D01*
X318703Y254936D01*
X319168Y254898D01*
X319633Y254936D01*
X320046Y255051D01*
X320356Y255204D01*
X320615Y255434D01*
X320718Y255741D01*
X320615Y256048D01*
X320356Y256278D01*
X320046Y256431D01*
X319633Y256546D01*
X319168Y256584D01*
X318703Y256546D01*
X318290Y256431D01*
X317980Y256278D01*
X317721Y256048D01*
X317618Y255741D01*
G01X313876Y250384D02*
X313721Y250154D01*
X313618Y249886D01*
Y249579D01*
X313773Y249234D01*
X314031Y248966D01*
X314341Y248774D01*
X314858Y248621D01*
X315323Y248583D01*
X315788Y248659D01*
X316098Y248774D01*
X316408Y249004D01*
X316615Y249273D01*
X316718Y249541D01*
Y249809D01*
X316615Y250078D01*
X316460Y250308D01*
X316253Y250499D01*
G01X316718Y252641D02*
X316666Y252909D01*
X316511Y253216D01*
X316253Y253408D01*
X315891Y253484D01*
X315530Y253408D01*
X315220Y253178D01*
X315065Y252833D01*
Y252449D01*
X314961Y252219D01*
X314703Y252028D01*
X314341Y251951D01*
X313980Y252066D01*
X313721Y252334D01*
X313618Y252641D01*
X313721Y252948D01*
X313980Y253216D01*
X314341Y253331D01*
X314703Y253254D01*
X314961Y253063D01*
X315065Y252833D01*
Y252449D01*
X315220Y252104D01*
X315530Y251874D01*
X315891Y251798D01*
X316253Y251874D01*
X316511Y252066D01*
X316666Y252373D01*
X316718Y252641D01*
G01X316253Y254898D02*
X316511Y255128D01*
X316666Y255396D01*
X316718Y255741D01*
X316615Y256086D01*
X316408Y256354D01*
X316046Y256546D01*
X315633Y256584D01*
X315220Y256508D01*
X314961Y256316D01*
X314755Y256048D01*
X314703Y255779D01*
X314755Y255511D01*
X314961Y255166D01*
X313618Y255281D01*
Y256316D01*
G01X313957Y238521D02*
Y241621D01*
X314916D01*
X315222Y241466D01*
X315414Y241259D01*
X315491Y240846D01*
X315414Y240433D01*
X315184Y240174D01*
X314916Y240019D01*
X313957D01*
G01X314916D02*
X315491Y238521D01*
G01X317747D02*
X317824Y239193D01*
X317939Y239761D01*
X318092Y240278D01*
X318284Y240846D01*
X318591Y241621D01*
X317057D01*
G01X321384Y238521D02*
Y241621D01*
X319966Y239399D01*
X321882D01*
G01X313957Y242476D02*
Y245576D01*
X314916D01*
X315222Y245421D01*
X315414Y245214D01*
X315491Y244801D01*
X315414Y244388D01*
X315184Y244129D01*
X314916Y243974D01*
X313957D01*
G01X314916D02*
X315491Y242476D01*
G01X317747D02*
X317824Y243148D01*
X317939Y243716D01*
X318092Y244233D01*
X318284Y244801D01*
X318591Y245576D01*
X317057D01*
G01X320196Y243768D02*
X320464Y244129D01*
X320694Y244336D01*
X321001Y244439D01*
X321269Y244336D01*
X321461Y244129D01*
X321614Y243819D01*
X321652Y243458D01*
X321614Y243148D01*
X321461Y242838D01*
X321231Y242579D01*
X320962Y242476D01*
X320656Y242579D01*
X320387Y242889D01*
X320234Y243354D01*
X320196Y243871D01*
X320272Y244543D01*
X320387Y244904D01*
X320579Y245266D01*
X320847Y245524D01*
X321116Y245576D01*
X321384Y245473D01*
X321576Y245214D01*
G01X312103Y264986D02*
X311873Y265141D01*
X311605Y265244D01*
X311298D01*
X310953Y265089D01*
X310685Y264831D01*
X310493Y264521D01*
X310340Y264004D01*
X310302Y263539D01*
X310378Y263074D01*
X310493Y262764D01*
X310723Y262454D01*
X310992Y262247D01*
X311260Y262144D01*
X311528D01*
X311797Y262247D01*
X312027Y262402D01*
X312218Y262609D01*
G01X313632Y264727D02*
X313862Y265037D01*
X314130Y265192D01*
X314437Y265244D01*
X314820Y265141D01*
X315088Y264882D01*
X315165Y264572D01*
X315127Y264262D01*
X314973Y264004D01*
X314207Y263487D01*
X313862Y263126D01*
X313632Y262609D01*
X313555Y262144D01*
X315165D01*
G01X316617Y262764D02*
X316847Y262402D01*
X317153Y262196D01*
X317498Y262144D01*
X317805Y262196D01*
X318112Y262454D01*
X318303Y262764D01*
X318342Y263074D01*
X318265Y263436D01*
X317997Y263694D01*
X317728Y263797D01*
X317383D01*
G01X317728D02*
X317958Y263952D01*
X318150Y264211D01*
X318227Y264521D01*
X318150Y264831D01*
X317958Y265089D01*
X317613Y265244D01*
X317268Y265192D01*
X316923Y264986D01*
G01X310493Y266179D02*
Y269279D01*
X311452D01*
X311758Y269124D01*
X311950Y268917D01*
X312027Y268504D01*
X311950Y268091D01*
X311720Y267832D01*
X311452Y267677D01*
X310493D01*
G01X311452D02*
X312027Y266179D01*
G01X314360D02*
Y269279D01*
X313900Y268659D01*
G01Y266179D02*
X314820D01*
G01X317460D02*
Y269279D01*
X317000Y268659D01*
G01Y266179D02*
X317920D01*
G01X319832Y268762D02*
X320062Y269072D01*
X320330Y269227D01*
X320637Y269279D01*
X321020Y269176D01*
X321288Y268917D01*
X321365Y268607D01*
X321327Y268297D01*
X321173Y268039D01*
X320407Y267522D01*
X320062Y267161D01*
X319832Y266644D01*
X319755Y266179D01*
X321365D01*
G01X318899Y258266D02*
Y261366D01*
X319858D01*
X320164Y261211D01*
X320356Y261004D01*
X320433Y260591D01*
X320356Y260178D01*
X320126Y259919D01*
X319858Y259764D01*
X318899D01*
G01X319858D02*
X320433Y258266D01*
G01X322766D02*
Y261366D01*
X322306Y260746D01*
G01Y258266D02*
X323226D01*
G01X325789D02*
X325866Y258938D01*
X325981Y259506D01*
X326134Y260023D01*
X326326Y260591D01*
X326633Y261366D01*
X325099D01*
G01X328966D02*
X328659Y261263D01*
X328429Y261004D01*
X328276Y260694D01*
X328161Y260281D01*
X328123Y259816D01*
X328161Y259351D01*
X328276Y258938D01*
X328429Y258628D01*
X328659Y258369D01*
X328966Y258266D01*
X329273Y258369D01*
X329503Y258628D01*
X329656Y258938D01*
X329771Y259351D01*
X329809Y259816D01*
X329771Y260281D01*
X329656Y260694D01*
X329503Y261004D01*
X329273Y261263D01*
X328966Y261366D01*
G01X310493Y278200D02*
Y281300D01*
X311452D01*
X311758Y281145D01*
X311950Y280938D01*
X312027Y280525D01*
X311950Y280112D01*
X311720Y279853D01*
X311452Y279698D01*
X310493D01*
G01X311452D02*
X312027Y278200D01*
G01X314360D02*
Y281300D01*
X313900Y280680D01*
G01Y278200D02*
X314820D01*
G01X316732Y279492D02*
X317000Y279853D01*
X317230Y280060D01*
X317537Y280163D01*
X317805Y280060D01*
X317997Y279853D01*
X318150Y279543D01*
X318188Y279182D01*
X318150Y278872D01*
X317997Y278562D01*
X317767Y278303D01*
X317498Y278200D01*
X317192Y278303D01*
X316923Y278613D01*
X316770Y279078D01*
X316732Y279595D01*
X316808Y280267D01*
X316923Y280628D01*
X317115Y280990D01*
X317383Y281248D01*
X317652Y281300D01*
X317920Y281197D01*
X318112Y280938D01*
G01X319832Y279492D02*
X320100Y279853D01*
X320330Y280060D01*
X320637Y280163D01*
X320905Y280060D01*
X321097Y279853D01*
X321250Y279543D01*
X321288Y279182D01*
X321250Y278872D01*
X321097Y278562D01*
X320867Y278303D01*
X320598Y278200D01*
X320292Y278303D01*
X320023Y278613D01*
X319870Y279078D01*
X319832Y279595D01*
X319908Y280267D01*
X320023Y280628D01*
X320215Y280990D01*
X320483Y281248D01*
X320752Y281300D01*
X321020Y281197D01*
X321212Y280938D01*
G01X310493Y282282D02*
Y285382D01*
X311452D01*
X311758Y285227D01*
X311950Y285020D01*
X312027Y284607D01*
X311950Y284194D01*
X311720Y283935D01*
X311452Y283780D01*
X310493D01*
G01X311452D02*
X312027Y282282D01*
G01X314360D02*
Y285382D01*
X313900Y284762D01*
G01Y282282D02*
X314820D01*
G01X316732Y283574D02*
X317000Y283935D01*
X317230Y284142D01*
X317537Y284245D01*
X317805Y284142D01*
X317997Y283935D01*
X318150Y283625D01*
X318188Y283264D01*
X318150Y282954D01*
X317997Y282644D01*
X317767Y282385D01*
X317498Y282282D01*
X317192Y282385D01*
X316923Y282695D01*
X316770Y283160D01*
X316732Y283677D01*
X316808Y284349D01*
X316923Y284710D01*
X317115Y285072D01*
X317383Y285330D01*
X317652Y285382D01*
X317920Y285279D01*
X318112Y285020D01*
G01X319717Y282902D02*
X319947Y282540D01*
X320253Y282334D01*
X320598Y282282D01*
X320905Y282334D01*
X321212Y282592D01*
X321403Y282902D01*
X321442Y283212D01*
X321365Y283574D01*
X321097Y283832D01*
X320828Y283935D01*
X320483D01*
G01X320828D02*
X321058Y284090D01*
X321250Y284349D01*
X321327Y284659D01*
X321250Y284969D01*
X321058Y285227D01*
X320713Y285382D01*
X320368Y285330D01*
X320023Y285124D01*
G01X310493Y274220D02*
Y277320D01*
X311452D01*
X311758Y277165D01*
X311950Y276958D01*
X312027Y276545D01*
X311950Y276132D01*
X311720Y275873D01*
X311452Y275718D01*
X310493D01*
G01X311452D02*
X312027Y274220D01*
G01X314820D02*
Y277320D01*
X313402Y275098D01*
X315318D01*
G01X316808Y274582D02*
X317077Y274323D01*
X317383Y274220D01*
X317690Y274323D01*
X317958Y274633D01*
X318150Y275098D01*
X318227Y275563D01*
Y276132D01*
X318150Y276597D01*
X317958Y277010D01*
X317728Y277217D01*
X317460Y277320D01*
X317153Y277217D01*
X316923Y277010D01*
X316770Y276700D01*
X316693Y276287D01*
X316770Y275925D01*
X316962Y275563D01*
X317192Y275357D01*
X317460Y275305D01*
X317767Y275408D01*
X317997Y275667D01*
X318227Y276132D01*
G01X310493Y270220D02*
Y273320D01*
X311452D01*
X311758Y273165D01*
X311950Y272958D01*
X312027Y272545D01*
X311950Y272132D01*
X311720Y271873D01*
X311452Y271718D01*
X310493D01*
G01X311452D02*
X312027Y270220D01*
G01X314820D02*
Y273320D01*
X313402Y271098D01*
X315318D01*
G01X317460Y270220D02*
X317728Y270272D01*
X318035Y270427D01*
X318227Y270685D01*
X318303Y271047D01*
X318227Y271408D01*
X317997Y271718D01*
X317652Y271873D01*
X317268D01*
X317038Y271977D01*
X316847Y272235D01*
X316770Y272597D01*
X316885Y272958D01*
X317153Y273217D01*
X317460Y273320D01*
X317767Y273217D01*
X318035Y272958D01*
X318150Y272597D01*
X318073Y272235D01*
X317882Y271977D01*
X317652Y271873D01*
X317268D01*
X316923Y271718D01*
X316693Y271408D01*
X316617Y271047D01*
X316693Y270685D01*
X316885Y270427D01*
X317192Y270272D01*
X317460Y270220D01*
G01X310493Y286350D02*
Y289450D01*
X311452D01*
X311758Y289295D01*
X311950Y289088D01*
X312027Y288675D01*
X311950Y288262D01*
X311720Y288003D01*
X311452Y287848D01*
X310493D01*
G01X311452D02*
X312027Y286350D01*
G01X314360D02*
Y289450D01*
X313900Y288830D01*
G01Y286350D02*
X314820D01*
G01X317920D02*
Y289450D01*
X316502Y287228D01*
X318418D01*
G01X319832Y288933D02*
X320062Y289243D01*
X320330Y289398D01*
X320637Y289450D01*
X321020Y289347D01*
X321288Y289088D01*
X321365Y288778D01*
X321327Y288468D01*
X321173Y288210D01*
X320407Y287693D01*
X320062Y287332D01*
X319832Y286815D01*
X319755Y286350D01*
X321365D01*
G01X317998Y294251D02*
X311798D01*
G01D02*
Y297451D01*
G01D02*
X317998D01*
G01D02*
Y294251D01*
G01X318774Y291128D02*
Y297328D01*
G01D02*
X321974D01*
G01Y291128D02*
X318774D01*
G01X307210Y295836D02*
Y351991D01*
G01X311799Y305488D02*
X317999D01*
G01D02*
Y302288D01*
G01D02*
X311799D01*
G01D02*
Y305488D01*
G01X311648Y309443D02*
X317848D01*
G01D02*
Y306243D01*
G01D02*
X311648D01*
G01D02*
Y309443D01*
G01X318110Y298346D02*
X311910D01*
G01D02*
Y301546D01*
G01D02*
X318110D01*
G01D02*
Y298346D01*
G01X308830Y352315D02*
Y323370D01*
G01X313040Y320752D02*
X316240D01*
G01Y314552D02*
X313040D01*
G01X316240Y320752D02*
Y314552D01*
G01X313140Y317652D02*
X316140D01*
G01X313040Y314552D02*
Y320752D01*
G01X320240D02*
Y314552D01*
G01X317040Y320752D02*
X320240D01*
G01X317040Y314552D02*
Y320752D01*
G01X320240Y314552D02*
X317040D01*
G01X317140Y317652D02*
X320140D01*
G01X309040Y320752D02*
X312240D01*
G01X309040Y314552D02*
Y320752D01*
G01X312240Y314552D02*
X309040D01*
G01X312240Y320752D02*
Y314552D01*
G01X309140Y317652D02*
X312140D01*
G01X321040Y320752D02*
X324240D01*
G01X321040Y314552D02*
Y320752D01*
G01X324240Y314552D02*
X321040D01*
G01X321140Y317652D02*
X324140D01*
G01X320750Y324786D02*
X314550D01*
G01D02*
Y327986D01*
G01D02*
X320750D01*
G01D02*
Y324786D01*
G01X327690Y343010D02*
X321040D01*
G01D02*
Y365060D01*
G01X314817Y339820D02*
Y336820D01*
G01X317917Y336720D02*
X311717D01*
G01D02*
Y339920D01*
G01D02*
X317917D01*
G01D02*
Y336720D01*
G01X311717Y344018D02*
X317917D01*
G01D02*
Y340818D01*
G01D02*
X311717D01*
G01D02*
Y344018D01*
G01X319511Y335536D02*
X322709D01*
G01Y329336D02*
X319511D01*
G01D02*
Y335536D01*
G01X308830Y365060D02*
Y356395D01*
G01X317917Y352776D02*
X311717D01*
G01D02*
Y355976D01*
G01D02*
X317917D01*
G01D02*
Y352776D01*
G01X311717Y359976D02*
X317917D01*
G01Y356776D02*
X311717D01*
G01D02*
Y359976D01*
G01X317917D02*
Y356776D01*
G01X311717Y351976D02*
X317917D01*
G01D02*
Y348776D01*
G01D02*
X311717D01*
G01D02*
Y351976D01*
G01Y347976D02*
X317917D01*
G01D02*
Y344776D01*
G01D02*
X311717D01*
G01D02*
Y347976D01*
G01X307210Y356881D02*
Y365434D01*
G01X311990Y366620D02*
X308990D01*
G01X311990Y372950D02*
Y366620D01*
G01X311950Y372950D02*
X311990D01*
G01X321040Y365060D02*
X308830D01*
G01X306742Y373698D02*
Y367498D01*
G01X318354Y368187D02*
X315854D01*
Y368853D01*
X315979Y369067D01*
X316146Y369200D01*
X316479Y369253D01*
X316812Y369200D01*
X317021Y369040D01*
X317146Y368853D01*
Y368187D01*
G01Y368853D02*
X318354Y369253D01*
G01Y370920D02*
X315854D01*
X316354Y370600D01*
G01X318354D02*
Y371240D01*
G01Y373120D02*
X315854D01*
X316354Y372800D01*
G01X318354D02*
Y373440D01*
G01X315854Y375320D02*
X315937Y375107D01*
X316146Y374947D01*
X316396Y374840D01*
X316729Y374760D01*
X317104Y374733D01*
X317479Y374760D01*
X317812Y374840D01*
X318062Y374947D01*
X318271Y375107D01*
X318354Y375320D01*
X318271Y375533D01*
X318062Y375693D01*
X317812Y375800D01*
X317479Y375880D01*
X317104Y375907D01*
X316729Y375880D01*
X316396Y375800D01*
X316146Y375693D01*
X315937Y375533D01*
X315854Y375320D01*
G01X316271Y377013D02*
X316021Y377173D01*
X315896Y377360D01*
X315854Y377573D01*
X315937Y377840D01*
X316146Y378027D01*
X316396Y378080D01*
X316646Y378053D01*
X316854Y377947D01*
X317271Y377413D01*
X317562Y377173D01*
X317979Y377013D01*
X318354Y376960D01*
Y378080D01*
G01X309490Y364106D02*
X315690D01*
G01D02*
Y360906D01*
G01D02*
X309490D01*
G01D02*
Y364106D01*
G01X307542Y373698D02*
X310742D01*
G01X307542Y367498D02*
Y373698D01*
G01X310742D02*
Y367498D01*
G01D02*
X307542D01*
G01X309209Y378543D02*
Y393004D01*
G01X314324Y389438D02*
X311324D01*
G01X311224Y386338D02*
Y392538D01*
G01X314424D02*
Y386338D01*
G01D02*
X311224D01*
G01X311622Y377458D02*
Y383658D01*
G01D02*
X314822D01*
G01D02*
Y377458D01*
G01D02*
X311622D01*
G01X321655Y378971D02*
X315455D01*
G01D02*
Y382171D01*
G01D02*
X321655D01*
G01X317584Y385735D02*
X316778D01*
G01D02*
Y390241D01*
G01X311224Y392538D02*
X314424D01*
G01X316926Y401440D02*
Y404540D01*
X317885D01*
X318191Y404385D01*
X318383Y404178D01*
X318460Y403765D01*
X318383Y403352D01*
X318153Y403093D01*
X317885Y402938D01*
X316926D01*
G01X317885D02*
X318460Y401440D01*
G01X320793D02*
Y404540D01*
X320333Y403920D01*
G01Y401440D02*
X321253D01*
G01X323893Y404540D02*
X323586Y404437D01*
X323356Y404178D01*
X323203Y403868D01*
X323088Y403455D01*
X323050Y402990D01*
X323088Y402525D01*
X323203Y402112D01*
X323356Y401802D01*
X323586Y401543D01*
X323893Y401440D01*
X324200Y401543D01*
X324430Y401802D01*
X324583Y402112D01*
X324698Y402525D01*
X324736Y402990D01*
X324698Y403455D01*
X324583Y403868D01*
X324430Y404178D01*
X324200Y404437D01*
X323893Y404540D01*
G01X326341Y401802D02*
X326610Y401543D01*
X326916Y401440D01*
X327223Y401543D01*
X327491Y401853D01*
X327683Y402318D01*
X327760Y402783D01*
Y403352D01*
X327683Y403817D01*
X327491Y404230D01*
X327261Y404437D01*
X326993Y404540D01*
X326686Y404437D01*
X326456Y404230D01*
X326303Y403920D01*
X326226Y403507D01*
X326303Y403145D01*
X326495Y402783D01*
X326725Y402577D01*
X326993Y402525D01*
X327300Y402628D01*
X327530Y402887D01*
X327760Y403352D01*
G01X329441Y401802D02*
X329710Y401543D01*
X330016Y401440D01*
X330323Y401543D01*
X330591Y401853D01*
X330783Y402318D01*
X330860Y402783D01*
Y403352D01*
X330783Y403817D01*
X330591Y404230D01*
X330361Y404437D01*
X330093Y404540D01*
X329786Y404437D01*
X329556Y404230D01*
X329403Y403920D01*
X329326Y403507D01*
X329403Y403145D01*
X329595Y402783D01*
X329825Y402577D01*
X330093Y402525D01*
X330400Y402628D01*
X330630Y402887D01*
X330860Y403352D01*
G01X315338Y405544D02*
Y411744D01*
G01X318538D02*
Y405544D01*
G01D02*
X315338D01*
G01X305862Y400029D02*
Y396829D01*
G01X312956Y393793D02*
X309856D01*
Y394752D01*
X310011Y395058D01*
X310218Y395250D01*
X310631Y395327D01*
X311044Y395250D01*
X311303Y395020D01*
X311458Y394752D01*
Y393793D01*
G01Y394752D02*
X312956Y395327D01*
G01Y397660D02*
X309856D01*
X310476Y397200D01*
G01X312956D02*
Y398120D01*
G01X309856Y400760D02*
X309959Y400453D01*
X310218Y400223D01*
X310528Y400070D01*
X310941Y399955D01*
X311406Y399917D01*
X311871Y399955D01*
X312284Y400070D01*
X312594Y400223D01*
X312853Y400453D01*
X312956Y400760D01*
X312853Y401067D01*
X312594Y401297D01*
X312284Y401450D01*
X311871Y401565D01*
X311406Y401603D01*
X310941Y401565D01*
X310528Y401450D01*
X310218Y401297D01*
X309959Y401067D01*
X309856Y400760D01*
G01X312491Y403017D02*
X312749Y403247D01*
X312904Y403515D01*
X312956Y403860D01*
X312853Y404205D01*
X312646Y404473D01*
X312284Y404665D01*
X311871Y404703D01*
X311458Y404627D01*
X311199Y404435D01*
X310993Y404167D01*
X310941Y403898D01*
X310993Y403630D01*
X311199Y403285D01*
X309856Y403400D01*
Y404435D01*
G01X310373Y406232D02*
X310063Y406462D01*
X309908Y406730D01*
X309856Y407037D01*
X309959Y407420D01*
X310218Y407688D01*
X310528Y407765D01*
X310838Y407727D01*
X311096Y407573D01*
X311613Y406807D01*
X311974Y406462D01*
X312491Y406232D01*
X312956Y406155D01*
Y407765D01*
G01X316778Y393041D02*
Y397546D01*
G01D02*
X317484D01*
G01X331160Y405380D02*
X319348D01*
G01D02*
Y418004D01*
G01X310057Y410682D02*
X309902Y410452D01*
X309799Y410184D01*
Y409877D01*
X309954Y409532D01*
X310212Y409264D01*
X310522Y409072D01*
X311039Y408919D01*
X311504Y408881D01*
X311969Y408957D01*
X312279Y409072D01*
X312589Y409302D01*
X312796Y409571D01*
X312899Y409839D01*
Y410107D01*
X312796Y410376D01*
X312641Y410606D01*
X312434Y410797D01*
G01X312899Y412862D02*
X312227Y412939D01*
X311659Y413054D01*
X311142Y413207D01*
X310574Y413399D01*
X309799Y413706D01*
Y412172D01*
G01X312537Y415387D02*
X312796Y415656D01*
X312899Y415962D01*
X312796Y416269D01*
X312486Y416537D01*
X312021Y416729D01*
X311556Y416806D01*
X310987D01*
X310522Y416729D01*
X310109Y416537D01*
X309902Y416307D01*
X309799Y416039D01*
X309902Y415732D01*
X310109Y415502D01*
X310419Y415349D01*
X310832Y415272D01*
X311194Y415349D01*
X311556Y415541D01*
X311762Y415771D01*
X311814Y416039D01*
X311711Y416346D01*
X311452Y416576D01*
X310987Y416806D01*
G01X312434Y418296D02*
X312692Y418526D01*
X312847Y418794D01*
X312899Y419139D01*
X312796Y419484D01*
X312589Y419752D01*
X312227Y419944D01*
X311814Y419982D01*
X311401Y419906D01*
X311142Y419714D01*
X310936Y419446D01*
X310884Y419177D01*
X310936Y418909D01*
X311142Y418564D01*
X309799Y418679D01*
Y419714D01*
G01X315338Y411744D02*
X318538D01*
G01X321074Y420043D02*
Y423243D01*
G01X327274Y420043D02*
X321074D01*
G01Y423243D02*
X327274D01*
G01X317357Y413709D02*
X317570Y413501D01*
X317810Y413376D01*
X318024D01*
X318237Y413501D01*
X318397Y413709D01*
X318477Y414001D01*
X318424Y414293D01*
X318290Y414543D01*
X318050Y414709D01*
X317730Y414793D01*
X317544Y414959D01*
X317464Y415251D01*
X317517Y415543D01*
X317650Y415751D01*
X317837Y415876D01*
X318024D01*
X318210Y415793D01*
X318370Y415584D01*
G01X318148Y418645D02*
Y421145D01*
X318682D01*
X318895Y421020D01*
X319055Y420853D01*
X319188Y420603D01*
X319295Y420312D01*
X319322Y419895D01*
X319295Y419478D01*
X319188Y419187D01*
X319055Y418937D01*
X318895Y418770D01*
X318682Y418645D01*
X318148D01*
G01X319348Y418004D02*
X331160D01*
G01X327274Y427983D02*
X321074D01*
G01D02*
Y431183D01*
G01D02*
X327274D01*
G01X321074Y423985D02*
Y427185D01*
G01X327274Y423985D02*
X321074D01*
G01Y427185D02*
X327274D01*
G01X316691Y449133D02*
X316536Y448903D01*
X316433Y448635D01*
Y448328D01*
X316588Y447983D01*
X316846Y447715D01*
X317156Y447523D01*
X317673Y447370D01*
X318138Y447332D01*
X318603Y447408D01*
X318913Y447523D01*
X319223Y447753D01*
X319430Y448022D01*
X319533Y448290D01*
Y448558D01*
X319430Y448827D01*
X319275Y449057D01*
X319068Y449248D01*
G01X319533Y451390D02*
X316433D01*
X317053Y450930D01*
G01X319533D02*
Y451850D01*
G01Y454490D02*
X316433D01*
X317053Y454030D01*
G01X319533D02*
Y454950D01*
G01X316950Y456862D02*
X316640Y457092D01*
X316485Y457360D01*
X316433Y457667D01*
X316536Y458050D01*
X316795Y458318D01*
X317105Y458395D01*
X317415Y458357D01*
X317673Y458203D01*
X318190Y457437D01*
X318551Y457092D01*
X319068Y456862D01*
X319533Y456785D01*
Y458395D01*
G01Y460690D02*
X316433D01*
X317053Y460230D01*
G01X319533D02*
Y461150D01*
G01X326515Y469061D02*
X321215D01*
G01X309503Y471700D02*
X309273Y471855D01*
X309005Y471958D01*
X308698D01*
X308353Y471803D01*
X308085Y471545D01*
X307893Y471235D01*
X307740Y470718D01*
X307702Y470253D01*
X307778Y469788D01*
X307893Y469478D01*
X308123Y469168D01*
X308392Y468961D01*
X308660Y468858D01*
X308928D01*
X309197Y468961D01*
X309427Y469116D01*
X309618Y469323D01*
G01X311760Y468858D02*
Y471958D01*
X311300Y471338D01*
G01Y468858D02*
X312220D01*
G01X314860D02*
Y471958D01*
X314400Y471338D01*
G01Y468858D02*
X315320D01*
G01X317232Y471441D02*
X317462Y471751D01*
X317730Y471906D01*
X318037Y471958D01*
X318420Y471855D01*
X318688Y471596D01*
X318765Y471286D01*
X318727Y470976D01*
X318573Y470718D01*
X317807Y470201D01*
X317462Y469840D01*
X317232Y469323D01*
X317155Y468858D01*
X318765D01*
G01X321060Y471958D02*
X320753Y471855D01*
X320523Y471596D01*
X320370Y471286D01*
X320255Y470873D01*
X320217Y470408D01*
X320255Y469943D01*
X320370Y469530D01*
X320523Y469220D01*
X320753Y468961D01*
X321060Y468858D01*
X321367Y468961D01*
X321597Y469220D01*
X321750Y469530D01*
X321865Y469943D01*
X321903Y470408D01*
X321865Y470873D01*
X321750Y471286D01*
X321597Y471596D01*
X321367Y471855D01*
X321060Y471958D01*
G01X315438Y462189D02*
Y465389D01*
G01X321638Y462189D02*
X315438D01*
G01Y465389D02*
X321638D01*
G01X318538Y462289D02*
Y465289D01*
G01X308235Y580352D02*
Y481534D01*
G01X315431Y477219D02*
X321631D01*
G01X315431Y474019D02*
Y477219D01*
G01X321631Y474019D02*
X315431D01*
G01X318531Y477119D02*
Y474119D01*
G01X320101Y484866D02*
X317001D01*
Y485825D01*
X317156Y486131D01*
X317363Y486323D01*
X317776Y486400D01*
X318189Y486323D01*
X318448Y486093D01*
X318603Y485825D01*
Y484866D01*
G01Y485825D02*
X320101Y486400D01*
G01Y488733D02*
X317001D01*
X317621Y488273D01*
G01X320101D02*
Y489193D01*
G01X317518Y491105D02*
X317208Y491335D01*
X317053Y491603D01*
X317001Y491910D01*
X317104Y492293D01*
X317363Y492561D01*
X317673Y492638D01*
X317983Y492600D01*
X318241Y492446D01*
X318758Y491680D01*
X319119Y491335D01*
X319636Y491105D01*
X320101Y491028D01*
Y492638D01*
G01X319636Y494090D02*
X319894Y494320D01*
X320049Y494588D01*
X320101Y494933D01*
X319998Y495278D01*
X319791Y495546D01*
X319429Y495738D01*
X319016Y495776D01*
X318603Y495700D01*
X318344Y495508D01*
X318138Y495240D01*
X318086Y494971D01*
X318138Y494703D01*
X318344Y494358D01*
X317001Y494473D01*
Y495508D01*
G01X320101Y498493D02*
X317001D01*
X319223Y497075D01*
Y498991D01*
G01X324131Y484866D02*
X321031D01*
Y485825D01*
X321186Y486131D01*
X321393Y486323D01*
X321806Y486400D01*
X322219Y486323D01*
X322478Y486093D01*
X322633Y485825D01*
Y484866D01*
G01Y485825D02*
X324131Y486400D01*
G01Y488733D02*
X321031D01*
X321651Y488273D01*
G01X324131D02*
Y489193D01*
G01X321548Y491105D02*
X321238Y491335D01*
X321083Y491603D01*
X321031Y491910D01*
X321134Y492293D01*
X321393Y492561D01*
X321703Y492638D01*
X322013Y492600D01*
X322271Y492446D01*
X322788Y491680D01*
X323149Y491335D01*
X323666Y491105D01*
X324131Y491028D01*
Y492638D01*
G01X323666Y494090D02*
X323924Y494320D01*
X324079Y494588D01*
X324131Y494933D01*
X324028Y495278D01*
X323821Y495546D01*
X323459Y495738D01*
X323046Y495776D01*
X322633Y495700D01*
X322374Y495508D01*
X322168Y495240D01*
X322116Y494971D01*
X322168Y494703D01*
X322374Y494358D01*
X321031Y494473D01*
Y495508D01*
G01X323666Y497190D02*
X323924Y497420D01*
X324079Y497688D01*
X324131Y498033D01*
X324028Y498378D01*
X323821Y498646D01*
X323459Y498838D01*
X323046Y498876D01*
X322633Y498800D01*
X322374Y498608D01*
X322168Y498340D01*
X322116Y498071D01*
X322168Y497803D01*
X322374Y497458D01*
X321031Y497573D01*
Y498608D01*
G01X315851Y484866D02*
X312751D01*
Y485825D01*
X312906Y486131D01*
X313113Y486323D01*
X313526Y486400D01*
X313939Y486323D01*
X314198Y486093D01*
X314353Y485825D01*
Y484866D01*
G01Y485825D02*
X315851Y486400D01*
G01Y488733D02*
X312751D01*
X313371Y488273D01*
G01X315851D02*
Y489193D01*
G01X313268Y491105D02*
X312958Y491335D01*
X312803Y491603D01*
X312751Y491910D01*
X312854Y492293D01*
X313113Y492561D01*
X313423Y492638D01*
X313733Y492600D01*
X313991Y492446D01*
X314508Y491680D01*
X314869Y491335D01*
X315386Y491105D01*
X315851Y491028D01*
Y492638D01*
G01X315386Y494090D02*
X315644Y494320D01*
X315799Y494588D01*
X315851Y494933D01*
X315748Y495278D01*
X315541Y495546D01*
X315179Y495738D01*
X314766Y495776D01*
X314353Y495700D01*
X314094Y495508D01*
X313888Y495240D01*
X313836Y494971D01*
X313888Y494703D01*
X314094Y494358D01*
X312751Y494473D01*
Y495508D01*
G01X315231Y497190D02*
X315593Y497420D01*
X315799Y497726D01*
X315851Y498071D01*
X315799Y498378D01*
X315541Y498685D01*
X315231Y498876D01*
X314921Y498915D01*
X314559Y498838D01*
X314301Y498570D01*
X314198Y498301D01*
Y497956D01*
G01Y498301D02*
X314043Y498531D01*
X313784Y498723D01*
X313474Y498800D01*
X313164Y498723D01*
X312906Y498531D01*
X312751Y498186D01*
X312803Y497841D01*
X313009Y497496D01*
G01X311624Y484866D02*
X308524D01*
Y485825D01*
X308679Y486131D01*
X308886Y486323D01*
X309299Y486400D01*
X309712Y486323D01*
X309971Y486093D01*
X310126Y485825D01*
Y484866D01*
G01Y485825D02*
X311624Y486400D01*
G01Y488733D02*
X308524D01*
X309144Y488273D01*
G01X311624D02*
Y489193D01*
G01X309041Y491105D02*
X308731Y491335D01*
X308576Y491603D01*
X308524Y491910D01*
X308627Y492293D01*
X308886Y492561D01*
X309196Y492638D01*
X309506Y492600D01*
X309764Y492446D01*
X310281Y491680D01*
X310642Y491335D01*
X311159Y491105D01*
X311624Y491028D01*
Y492638D01*
G01X310332Y494205D02*
X309971Y494473D01*
X309764Y494703D01*
X309661Y495010D01*
X309764Y495278D01*
X309971Y495470D01*
X310281Y495623D01*
X310642Y495661D01*
X310952Y495623D01*
X311262Y495470D01*
X311521Y495240D01*
X311624Y494971D01*
X311521Y494665D01*
X311211Y494396D01*
X310746Y494243D01*
X310229Y494205D01*
X309557Y494281D01*
X309196Y494396D01*
X308834Y494588D01*
X308576Y494856D01*
X308524Y495125D01*
X308627Y495393D01*
X308886Y495585D01*
G01X308524Y498033D02*
X308627Y497726D01*
X308886Y497496D01*
X309196Y497343D01*
X309609Y497228D01*
X310074Y497190D01*
X310539Y497228D01*
X310952Y497343D01*
X311262Y497496D01*
X311521Y497726D01*
X311624Y498033D01*
X311521Y498340D01*
X311262Y498570D01*
X310952Y498723D01*
X310539Y498838D01*
X310074Y498876D01*
X309609Y498838D01*
X309196Y498723D01*
X308886Y498570D01*
X308627Y498340D01*
X308524Y498033D01*
G01X316634Y503818D02*
X313534D01*
Y504584D01*
X313689Y504891D01*
X313896Y505121D01*
X314206Y505313D01*
X314567Y505466D01*
X315084Y505504D01*
X315601Y505466D01*
X315962Y505313D01*
X316272Y505121D01*
X316479Y504891D01*
X316634Y504584D01*
Y503818D01*
G01X316014Y506918D02*
X316376Y507148D01*
X316582Y507454D01*
X316634Y507799D01*
X316582Y508106D01*
X316324Y508413D01*
X316014Y508604D01*
X315704Y508643D01*
X315342Y508566D01*
X315084Y508298D01*
X314981Y508029D01*
Y507684D01*
G01Y508029D02*
X314826Y508259D01*
X314567Y508451D01*
X314257Y508528D01*
X313947Y508451D01*
X313689Y508259D01*
X313534Y507914D01*
X313586Y507569D01*
X313792Y507224D01*
G01X314051Y510133D02*
X313741Y510363D01*
X313586Y510631D01*
X313534Y510938D01*
X313637Y511321D01*
X313896Y511589D01*
X314206Y511666D01*
X314516Y511628D01*
X314774Y511474D01*
X315291Y510708D01*
X315652Y510363D01*
X316169Y510133D01*
X316634Y510056D01*
Y511666D01*
G01X321071Y503818D02*
X317971D01*
Y504584D01*
X318126Y504891D01*
X318333Y505121D01*
X318643Y505313D01*
X319004Y505466D01*
X319521Y505504D01*
X320038Y505466D01*
X320399Y505313D01*
X320709Y505121D01*
X320916Y504891D01*
X321071Y504584D01*
Y503818D01*
G01X320451Y506918D02*
X320813Y507148D01*
X321019Y507454D01*
X321071Y507799D01*
X321019Y508106D01*
X320761Y508413D01*
X320451Y508604D01*
X320141Y508643D01*
X319779Y508566D01*
X319521Y508298D01*
X319418Y508029D01*
Y507684D01*
G01Y508029D02*
X319263Y508259D01*
X319004Y508451D01*
X318694Y508528D01*
X318384Y508451D01*
X318126Y508259D01*
X317971Y507914D01*
X318023Y507569D01*
X318229Y507224D01*
G01X320451Y510018D02*
X320813Y510248D01*
X321019Y510554D01*
X321071Y510899D01*
X321019Y511206D01*
X320761Y511513D01*
X320451Y511704D01*
X320141Y511743D01*
X319779Y511666D01*
X319521Y511398D01*
X319418Y511129D01*
Y510784D01*
G01Y511129D02*
X319263Y511359D01*
X319004Y511551D01*
X318694Y511628D01*
X318384Y511551D01*
X318126Y511359D01*
X317971Y511014D01*
X318023Y510669D01*
X318229Y510324D01*
G01X312334Y503818D02*
X309234D01*
Y504584D01*
X309389Y504891D01*
X309596Y505121D01*
X309906Y505313D01*
X310267Y505466D01*
X310784Y505504D01*
X311301Y505466D01*
X311662Y505313D01*
X311972Y505121D01*
X312179Y504891D01*
X312334Y504584D01*
Y503818D01*
G01X311714Y506918D02*
X312076Y507148D01*
X312282Y507454D01*
X312334Y507799D01*
X312282Y508106D01*
X312024Y508413D01*
X311714Y508604D01*
X311404Y508643D01*
X311042Y508566D01*
X310784Y508298D01*
X310681Y508029D01*
Y507684D01*
G01Y508029D02*
X310526Y508259D01*
X310267Y508451D01*
X309957Y508528D01*
X309647Y508451D01*
X309389Y508259D01*
X309234Y507914D01*
X309286Y507569D01*
X309492Y507224D01*
G01X312334Y510861D02*
X309234D01*
X309854Y510401D01*
G01X312334D02*
Y511321D01*
G01X314200Y519078D02*
Y518082D01*
G01X320488Y517453D02*
X316088D01*
G01D02*
Y519253D01*
G01X320488Y517453D02*
Y519253D01*
G01X319916Y514853D02*
G02I-1628J0D01*
G01X319717Y535179D02*
X319210Y535012D01*
X318830Y534596D01*
X318577Y534096D01*
X318387Y533429D01*
X318324Y532679D01*
X318387Y531929D01*
X318577Y531262D01*
X318830Y530762D01*
X319210Y530346D01*
X319717Y530179D01*
X320224Y530346D01*
X320604Y530762D01*
X320857Y531262D01*
X321047Y531929D01*
X321110Y532679D01*
X321047Y533429D01*
X320857Y534096D01*
X320604Y534596D01*
X320224Y535012D01*
X319717Y535179D01*
G01X310407Y535566D02*
X310247Y535691D01*
X310060Y535774D01*
X309847D01*
X309607Y535649D01*
X309420Y535441D01*
X309287Y535191D01*
X309180Y534774D01*
X309153Y534399D01*
X309207Y534024D01*
X309287Y533774D01*
X309447Y533524D01*
X309633Y533357D01*
X309820Y533274D01*
X310007D01*
X310193Y533357D01*
X310353Y533482D01*
X310487Y533649D01*
G01X312020Y533274D02*
X312207Y533316D01*
X312420Y533441D01*
X312553Y533649D01*
X312607Y533941D01*
X312553Y534232D01*
X312393Y534482D01*
X312153Y534607D01*
X311887D01*
X311727Y534691D01*
X311593Y534899D01*
X311540Y535191D01*
X311620Y535482D01*
X311807Y535691D01*
X312020Y535774D01*
X312233Y535691D01*
X312420Y535482D01*
X312500Y535191D01*
X312447Y534899D01*
X312313Y534691D01*
X312153Y534607D01*
X311887D01*
X311647Y534482D01*
X311487Y534232D01*
X311433Y533941D01*
X311487Y533649D01*
X311620Y533441D01*
X311833Y533316D01*
X312020Y533274D01*
G01X313633Y533774D02*
X313793Y533482D01*
X314007Y533316D01*
X314247Y533274D01*
X314460Y533316D01*
X314673Y533524D01*
X314807Y533774D01*
X314833Y534024D01*
X314780Y534316D01*
X314593Y534524D01*
X314407Y534607D01*
X314167D01*
G01X314407D02*
X314567Y534732D01*
X314700Y534941D01*
X314753Y535191D01*
X314700Y535441D01*
X314567Y535649D01*
X314327Y535774D01*
X314087Y535732D01*
X313847Y535566D01*
G01X316420Y533274D02*
X316607Y533316D01*
X316820Y533441D01*
X316953Y533649D01*
X317007Y533941D01*
X316953Y534232D01*
X316793Y534482D01*
X316553Y534607D01*
X316287D01*
X316127Y534691D01*
X315993Y534899D01*
X315940Y535191D01*
X316020Y535482D01*
X316207Y535691D01*
X316420Y535774D01*
X316633Y535691D01*
X316820Y535482D01*
X316900Y535191D01*
X316847Y534899D01*
X316713Y534691D01*
X316553Y534607D01*
X316287D01*
X316047Y534482D01*
X315887Y534232D01*
X315833Y533941D01*
X315887Y533649D01*
X316020Y533441D01*
X316233Y533316D01*
X316420Y533274D01*
G01X316088Y529653D02*
X320488D01*
G01X316088Y519253D02*
Y529653D01*
G01X320488Y519253D02*
X316088D01*
G01X320488Y529653D02*
Y519253D01*
G01Y518653D02*
X316088D01*
G01Y518053D02*
X320488D01*
G01X317037Y543104D02*
Y549704D01*
G01X309537Y543004D02*
Y549804D01*
G01X324537Y543004D02*
X309537D01*
G01X310389Y542107D02*
X310229Y542232D01*
X310042Y542315D01*
X309829D01*
X309589Y542190D01*
X309402Y541982D01*
X309269Y541732D01*
X309162Y541315D01*
X309135Y540940D01*
X309189Y540565D01*
X309269Y540315D01*
X309429Y540065D01*
X309615Y539898D01*
X309802Y539815D01*
X309989D01*
X310175Y539898D01*
X310335Y540023D01*
X310469Y540190D01*
G01X312002Y539815D02*
X312189Y539857D01*
X312402Y539982D01*
X312535Y540190D01*
X312589Y540482D01*
X312535Y540773D01*
X312375Y541023D01*
X312135Y541148D01*
X311869D01*
X311709Y541232D01*
X311575Y541440D01*
X311522Y541732D01*
X311602Y542023D01*
X311789Y542232D01*
X312002Y542315D01*
X312215Y542232D01*
X312402Y542023D01*
X312482Y541732D01*
X312429Y541440D01*
X312295Y541232D01*
X312135Y541148D01*
X311869D01*
X311629Y541023D01*
X311469Y540773D01*
X311415Y540482D01*
X311469Y540190D01*
X311602Y539982D01*
X311815Y539857D01*
X312002Y539815D01*
G01X314522D02*
Y542315D01*
X313535Y540523D01*
X314869D01*
G01X316402Y542315D02*
X316189Y542232D01*
X316029Y542023D01*
X315922Y541773D01*
X315842Y541440D01*
X315815Y541065D01*
X315842Y540690D01*
X315922Y540357D01*
X316029Y540107D01*
X316189Y539898D01*
X316402Y539815D01*
X316615Y539898D01*
X316775Y540107D01*
X316882Y540357D01*
X316962Y540690D01*
X316989Y541065D01*
X316962Y541440D01*
X316882Y541773D01*
X316775Y542023D01*
X316615Y542232D01*
X316402Y542315D01*
G01X310367Y538938D02*
X310207Y539063D01*
X310020Y539146D01*
X309807D01*
X309567Y539021D01*
X309380Y538813D01*
X309247Y538563D01*
X309140Y538146D01*
X309113Y537771D01*
X309167Y537396D01*
X309247Y537146D01*
X309407Y536896D01*
X309593Y536729D01*
X309780Y536646D01*
X309967D01*
X310153Y536729D01*
X310313Y536854D01*
X310447Y537021D01*
G01X311980Y536646D02*
X312167Y536688D01*
X312380Y536813D01*
X312513Y537021D01*
X312567Y537313D01*
X312513Y537604D01*
X312353Y537854D01*
X312113Y537979D01*
X311847D01*
X311687Y538063D01*
X311553Y538271D01*
X311500Y538563D01*
X311580Y538854D01*
X311767Y539063D01*
X311980Y539146D01*
X312193Y539063D01*
X312380Y538854D01*
X312460Y538563D01*
X312407Y538271D01*
X312273Y538063D01*
X312113Y537979D01*
X311847D01*
X311607Y537854D01*
X311447Y537604D01*
X311393Y537313D01*
X311447Y537021D01*
X311580Y536813D01*
X311793Y536688D01*
X311980Y536646D01*
G01X313593Y537146D02*
X313753Y536854D01*
X313967Y536688D01*
X314207Y536646D01*
X314420Y536688D01*
X314633Y536896D01*
X314767Y537146D01*
X314793Y537396D01*
X314740Y537688D01*
X314553Y537896D01*
X314367Y537979D01*
X314127D01*
G01X314367D02*
X314527Y538104D01*
X314660Y538313D01*
X314713Y538563D01*
X314660Y538813D01*
X314527Y539021D01*
X314287Y539146D01*
X314047Y539104D01*
X313807Y538938D01*
G01X315927Y536938D02*
X316113Y536729D01*
X316327Y536646D01*
X316540Y536729D01*
X316727Y536979D01*
X316860Y537354D01*
X316913Y537729D01*
Y538188D01*
X316860Y538563D01*
X316727Y538896D01*
X316567Y539063D01*
X316380Y539146D01*
X316167Y539063D01*
X316007Y538896D01*
X315900Y538646D01*
X315847Y538313D01*
X315900Y538021D01*
X316033Y537729D01*
X316193Y537563D01*
X316380Y537521D01*
X316593Y537604D01*
X316753Y537813D01*
X316913Y538188D01*
G01X309537Y549804D02*
X324537D01*
G01X309425Y560374D02*
X309270Y560144D01*
X309167Y559876D01*
Y559569D01*
X309322Y559224D01*
X309580Y558956D01*
X309890Y558764D01*
X310407Y558611D01*
X310872Y558573D01*
X311337Y558649D01*
X311647Y558764D01*
X311957Y558994D01*
X312164Y559263D01*
X312267Y559531D01*
Y559799D01*
X312164Y560068D01*
X312009Y560298D01*
X311802Y560489D01*
G01X312267Y562631D02*
X312215Y562899D01*
X312060Y563206D01*
X311802Y563398D01*
X311440Y563474D01*
X311079Y563398D01*
X310769Y563168D01*
X310614Y562823D01*
Y562439D01*
X310510Y562209D01*
X310252Y562018D01*
X309890Y561941D01*
X309529Y562056D01*
X309270Y562324D01*
X309167Y562631D01*
X309270Y562938D01*
X309529Y563206D01*
X309890Y563321D01*
X310252Y563244D01*
X310510Y563053D01*
X310614Y562823D01*
Y562439D01*
X310769Y562094D01*
X311079Y561864D01*
X311440Y561788D01*
X311802Y561864D01*
X312060Y562056D01*
X312215Y562363D01*
X312267Y562631D01*
G01X311647Y564888D02*
X312009Y565118D01*
X312215Y565424D01*
X312267Y565769D01*
X312215Y566076D01*
X311957Y566383D01*
X311647Y566574D01*
X311337Y566613D01*
X310975Y566536D01*
X310717Y566268D01*
X310614Y565999D01*
Y565654D01*
G01Y565999D02*
X310459Y566229D01*
X310200Y566421D01*
X309890Y566498D01*
X309580Y566421D01*
X309322Y566229D01*
X309167Y565884D01*
X309219Y565539D01*
X309425Y565194D01*
G01X311802Y567988D02*
X312060Y568218D01*
X312215Y568486D01*
X312267Y568831D01*
X312164Y569176D01*
X311957Y569444D01*
X311595Y569636D01*
X311182Y569674D01*
X310769Y569598D01*
X310510Y569406D01*
X310304Y569138D01*
X310252Y568869D01*
X310304Y568601D01*
X310510Y568256D01*
X309167Y568371D01*
Y569406D01*
G01X317088Y561503D02*
Y564503D01*
G01X313988Y561403D02*
Y564603D01*
G01X320188Y561403D02*
X313988D01*
G01X320188Y564603D02*
Y561403D01*
G01X313988Y564603D02*
X320188D01*
G01X318532Y554988D02*
Y557988D01*
G01X315432Y554888D02*
Y558088D01*
G01X321632Y554888D02*
X315432D01*
G01Y558088D02*
X321632D01*
G01X318532Y550688D02*
Y553688D01*
G01X315432Y550588D02*
Y553788D01*
G01X321632Y550588D02*
X315432D01*
G01Y553788D02*
X321632D01*
G01X320873Y578639D02*
X320643Y578794D01*
X320375Y578897D01*
X320068D01*
X319723Y578742D01*
X319455Y578484D01*
X319263Y578174D01*
X319110Y577657D01*
X319072Y577192D01*
X319148Y576727D01*
X319263Y576417D01*
X319493Y576107D01*
X319762Y575900D01*
X320030Y575797D01*
X320298D01*
X320567Y575900D01*
X320797Y576055D01*
X320988Y576262D01*
G01X323130Y575797D02*
X323398Y575849D01*
X323705Y576004D01*
X323897Y576262D01*
X323973Y576624D01*
X323897Y576985D01*
X323667Y577295D01*
X323322Y577450D01*
X322938D01*
X322708Y577554D01*
X322517Y577812D01*
X322440Y578174D01*
X322555Y578535D01*
X322823Y578794D01*
X323130Y578897D01*
X323437Y578794D01*
X323705Y578535D01*
X323820Y578174D01*
X323743Y577812D01*
X323552Y577554D01*
X323322Y577450D01*
X322938D01*
X322593Y577295D01*
X322363Y576985D01*
X322287Y576624D01*
X322363Y576262D01*
X322555Y576004D01*
X322862Y575849D01*
X323130Y575797D01*
G01X325387Y576417D02*
X325617Y576055D01*
X325923Y575849D01*
X326268Y575797D01*
X326575Y575849D01*
X326882Y576107D01*
X327073Y576417D01*
X327112Y576727D01*
X327035Y577089D01*
X326767Y577347D01*
X326498Y577450D01*
X326153D01*
G01X326498D02*
X326728Y577605D01*
X326920Y577864D01*
X326997Y578174D01*
X326920Y578484D01*
X326728Y578742D01*
X326383Y578897D01*
X326038Y578845D01*
X325693Y578639D01*
G01X328602Y577089D02*
X328870Y577450D01*
X329100Y577657D01*
X329407Y577760D01*
X329675Y577657D01*
X329867Y577450D01*
X330020Y577140D01*
X330058Y576779D01*
X330020Y576469D01*
X329867Y576159D01*
X329637Y575900D01*
X329368Y575797D01*
X329062Y575900D01*
X328793Y576210D01*
X328640Y576675D01*
X328602Y577192D01*
X328678Y577864D01*
X328793Y578225D01*
X328985Y578587D01*
X329253Y578845D01*
X329522Y578897D01*
X329790Y578794D01*
X329982Y578535D01*
G01X318088Y575203D02*
X333088D01*
G01X318088Y568403D02*
Y575203D01*
G01X333088Y568403D02*
X318088D01*
G01X314173Y574713D02*
X311073D01*
Y575672D01*
X311228Y575978D01*
X311435Y576170D01*
X311848Y576247D01*
X312261Y576170D01*
X312520Y575940D01*
X312675Y575672D01*
Y574713D01*
G01Y575672D02*
X314173Y576247D01*
G01Y578580D02*
X311073D01*
X311693Y578120D01*
G01X314173D02*
Y579040D01*
G01X311073Y581680D02*
X311176Y581373D01*
X311435Y581143D01*
X311745Y580990D01*
X312158Y580875D01*
X312623Y580837D01*
X313088Y580875D01*
X313501Y580990D01*
X313811Y581143D01*
X314070Y581373D01*
X314173Y581680D01*
X314070Y581987D01*
X313811Y582217D01*
X313501Y582370D01*
X313088Y582485D01*
X312623Y582523D01*
X312158Y582485D01*
X311745Y582370D01*
X311435Y582217D01*
X311176Y581987D01*
X311073Y581680D01*
G01X314173Y584780D02*
X314121Y585048D01*
X313966Y585355D01*
X313708Y585547D01*
X313346Y585623D01*
X312985Y585547D01*
X312675Y585317D01*
X312520Y584972D01*
Y584588D01*
X312416Y584358D01*
X312158Y584167D01*
X311796Y584090D01*
X311435Y584205D01*
X311176Y584473D01*
X311073Y584780D01*
X311176Y585087D01*
X311435Y585355D01*
X311796Y585470D01*
X312158Y585393D01*
X312416Y585202D01*
X312520Y584972D01*
Y584588D01*
X312675Y584243D01*
X312985Y584013D01*
X313346Y583937D01*
X313708Y584013D01*
X313966Y584205D01*
X314121Y584512D01*
X314173Y584780D01*
G01X311590Y587152D02*
X311280Y587382D01*
X311125Y587650D01*
X311073Y587957D01*
X311176Y588340D01*
X311435Y588608D01*
X311745Y588685D01*
X312055Y588647D01*
X312313Y588493D01*
X312830Y587727D01*
X313191Y587382D01*
X313708Y587152D01*
X314173Y587075D01*
Y588685D01*
G01X306375Y599406D02*
Y596206D01*
G01X309564Y595407D02*
Y588007D01*
G01X310540Y595655D02*
Y598855D01*
G01X316740Y595655D02*
X310540D01*
G01X316740Y598855D02*
Y595655D01*
G01X316133Y585497D02*
Y588597D01*
X317092D01*
X317398Y588442D01*
X317590Y588235D01*
X317667Y587822D01*
X317590Y587409D01*
X317360Y587150D01*
X317092Y586995D01*
X316133D01*
G01X317092D02*
X317667Y585497D01*
G01X320000D02*
Y588597D01*
X319540Y587977D01*
G01Y585497D02*
X320460D01*
G01X323100Y588597D02*
X322793Y588494D01*
X322563Y588235D01*
X322410Y587925D01*
X322295Y587512D01*
X322257Y587047D01*
X322295Y586582D01*
X322410Y586169D01*
X322563Y585859D01*
X322793Y585600D01*
X323100Y585497D01*
X323407Y585600D01*
X323637Y585859D01*
X323790Y586169D01*
X323905Y586582D01*
X323943Y587047D01*
X323905Y587512D01*
X323790Y587925D01*
X323637Y588235D01*
X323407Y588494D01*
X323100Y588597D01*
G01X326200Y585497D02*
X326468Y585549D01*
X326775Y585704D01*
X326967Y585962D01*
X327043Y586324D01*
X326967Y586685D01*
X326737Y586995D01*
X326392Y587150D01*
X326008D01*
X325778Y587254D01*
X325587Y587512D01*
X325510Y587874D01*
X325625Y588235D01*
X325893Y588494D01*
X326200Y588597D01*
X326507Y588494D01*
X326775Y588235D01*
X326890Y587874D01*
X326813Y587512D01*
X326622Y587254D01*
X326392Y587150D01*
X326008D01*
X325663Y586995D01*
X325433Y586685D01*
X325357Y586324D01*
X325433Y585962D01*
X325625Y585704D01*
X325932Y585549D01*
X326200Y585497D01*
G01X328457Y586117D02*
X328687Y585755D01*
X328993Y585549D01*
X329338Y585497D01*
X329645Y585549D01*
X329952Y585807D01*
X330143Y586117D01*
X330182Y586427D01*
X330105Y586789D01*
X329837Y587047D01*
X329568Y587150D01*
X329223D01*
G01X329568D02*
X329798Y587305D01*
X329990Y587564D01*
X330067Y587874D01*
X329990Y588184D01*
X329798Y588442D01*
X329453Y588597D01*
X329108Y588545D01*
X328763Y588339D01*
G01X320735Y592587D02*
X317535D01*
G01X320735Y598787D02*
Y592587D01*
G01X317535D02*
Y598787D01*
G01X321424Y595598D02*
Y598798D01*
G01X327624Y595598D02*
X321424D01*
G01X321340Y604593D02*
X318240D01*
Y605513D01*
X318395Y605820D01*
X318757Y606050D01*
X319170Y606127D01*
X319583Y606050D01*
X319893Y605858D01*
X320048Y605513D01*
Y604593D01*
G01X318240Y607617D02*
X320462D01*
X320927Y607770D01*
X321237Y608077D01*
X321340Y608460D01*
X321237Y608843D01*
X320927Y609150D01*
X320462Y609303D01*
X318240D01*
G01X321340Y611560D02*
X318240D01*
X318860Y611100D01*
G01X321340D02*
Y612020D01*
G01X314991Y600276D02*
Y602776D01*
X314671Y602276D01*
G01Y600276D02*
X315311D01*
G01X316684Y601318D02*
X316871Y601609D01*
X317031Y601776D01*
X317244Y601859D01*
X317431Y601776D01*
X317564Y601609D01*
X317671Y601359D01*
X317698Y601068D01*
X317671Y600818D01*
X317564Y600568D01*
X317404Y600359D01*
X317218Y600276D01*
X317004Y600359D01*
X316818Y600609D01*
X316711Y600984D01*
X316684Y601401D01*
X316738Y601943D01*
X316818Y602234D01*
X316951Y602526D01*
X317138Y602734D01*
X317324Y602776D01*
X317511Y602693D01*
X317644Y602484D01*
G01X316528Y603013D02*
Y605114D01*
G01X314527Y603013D02*
X316528D01*
G01X311334Y599961D02*
Y601161D01*
G01X321436Y612488D02*
Y618688D01*
G01X324636Y612488D02*
X321436D01*
G01X321424Y599521D02*
Y602721D01*
G01D02*
X327624D01*
G01Y599521D02*
X321424D01*
G01X310540Y598855D02*
X316740D01*
G01X317535Y598787D02*
X320735D01*
G01X321424Y598798D02*
X327624D01*
G01X314620Y617382D02*
X314412Y617222D01*
X314287Y617035D01*
X314245Y616795D01*
X314328Y616555D01*
X314495Y616368D01*
X314787Y616235D01*
X315120Y616208D01*
X315453Y616262D01*
X315662Y616395D01*
X315828Y616582D01*
X315870Y616768D01*
X315828Y616955D01*
X315662Y617195D01*
X316745Y617115D01*
Y616395D01*
G01X313280Y617261D02*
Y618461D01*
G01X316528Y615415D02*
X314627D01*
G01X316528Y613514D02*
Y615415D01*
G01X306711Y625477D02*
Y622277D01*
G01X317652Y628903D02*
X317497Y628673D01*
X317394Y628405D01*
Y628098D01*
X317549Y627753D01*
X317807Y627485D01*
X318117Y627293D01*
X318634Y627140D01*
X319099Y627102D01*
X319564Y627178D01*
X319874Y627293D01*
X320184Y627523D01*
X320391Y627792D01*
X320494Y628060D01*
Y628328D01*
X320391Y628597D01*
X320236Y628827D01*
X320029Y629018D01*
G01Y630317D02*
X320287Y630547D01*
X320442Y630815D01*
X320494Y631160D01*
X320391Y631505D01*
X320184Y631773D01*
X319822Y631965D01*
X319409Y632003D01*
X318996Y631927D01*
X318737Y631735D01*
X318531Y631467D01*
X318479Y631198D01*
X318531Y630930D01*
X318737Y630585D01*
X317394Y630700D01*
Y631735D01*
G01X320494Y634183D02*
X319822Y634260D01*
X319254Y634375D01*
X318737Y634528D01*
X318169Y634720D01*
X317394Y635027D01*
Y633493D01*
G01X320494Y637360D02*
X320442Y637628D01*
X320287Y637935D01*
X320029Y638127D01*
X319667Y638203D01*
X319306Y638127D01*
X318996Y637897D01*
X318841Y637552D01*
Y637168D01*
X318737Y636938D01*
X318479Y636747D01*
X318117Y636670D01*
X317756Y636785D01*
X317497Y637053D01*
X317394Y637360D01*
X317497Y637667D01*
X317756Y637935D01*
X318117Y638050D01*
X318479Y637973D01*
X318737Y637782D01*
X318841Y637552D01*
Y637168D01*
X318996Y636823D01*
X319306Y636593D01*
X319667Y636517D01*
X320029Y636593D01*
X320287Y636785D01*
X320442Y637092D01*
X320494Y637360D01*
G01X321436Y618688D02*
X324636D01*
G01X324536Y615588D02*
X321536D01*
G01X320480Y619902D02*
X317280D01*
G01X320480Y626102D02*
Y619902D01*
G01X317280Y626102D02*
X320480D01*
G01X317280Y619902D02*
Y626102D01*
G01X313310D02*
X316510D01*
G01X313310Y619902D02*
Y626102D01*
G01X316510Y619902D02*
X313310D01*
G01X316510Y626102D02*
Y619902D01*
G01X318840Y638456D02*
Y643456D01*
G01X309040Y632456D02*
Y643256D01*
G01X316348Y637993D02*
X313348D01*
G01X316448Y634893D02*
X313248D01*
G01X316448Y641093D02*
Y634893D01*
G01X313248Y641093D02*
X316448D01*
G01X313248Y634893D02*
Y641093D01*
G01X309074Y638188D02*
X306074D01*
G01X309174Y635088D02*
X305974D01*
G01X309174Y641288D02*
Y635088D01*
G01X305974Y641288D02*
X309174D01*
G01X305974Y635088D02*
Y641288D01*
G01X310840Y712156D02*
Y717156D01*
G01X320840Y712056D02*
Y722856D01*
G01X307256Y715042D02*
X307101Y714812D01*
X306998Y714544D01*
Y714237D01*
X307153Y713892D01*
X307411Y713624D01*
X307721Y713432D01*
X308238Y713279D01*
X308703Y713241D01*
X309168Y713317D01*
X309478Y713432D01*
X309788Y713662D01*
X309995Y713931D01*
X310098Y714199D01*
Y714467D01*
X309995Y714736D01*
X309840Y714966D01*
X309633Y715157D01*
G01Y716456D02*
X309891Y716686D01*
X310046Y716954D01*
X310098Y717299D01*
X309995Y717644D01*
X309788Y717912D01*
X309426Y718104D01*
X309013Y718142D01*
X308600Y718066D01*
X308341Y717874D01*
X308135Y717606D01*
X308083Y717337D01*
X308135Y717069D01*
X308341Y716724D01*
X306998Y716839D01*
Y717874D01*
G01X310098Y720399D02*
X310046Y720667D01*
X309891Y720974D01*
X309633Y721166D01*
X309271Y721242D01*
X308910Y721166D01*
X308600Y720936D01*
X308445Y720591D01*
Y720207D01*
X308341Y719977D01*
X308083Y719786D01*
X307721Y719709D01*
X307360Y719824D01*
X307101Y720092D01*
X306998Y720399D01*
X307101Y720706D01*
X307360Y720974D01*
X307721Y721089D01*
X308083Y721012D01*
X308341Y720821D01*
X308445Y720591D01*
Y720207D01*
X308600Y719862D01*
X308910Y719632D01*
X309271Y719556D01*
X309633Y719632D01*
X309891Y719824D01*
X310046Y720131D01*
X310098Y720399D01*
G01X309633Y722656D02*
X309891Y722886D01*
X310046Y723154D01*
X310098Y723499D01*
X309995Y723844D01*
X309788Y724112D01*
X309426Y724304D01*
X309013Y724342D01*
X308600Y724266D01*
X308341Y724074D01*
X308135Y723806D01*
X308083Y723537D01*
X308135Y723269D01*
X308341Y722924D01*
X306998Y723039D01*
Y724074D01*
G01X313440Y718156D02*
X316440D01*
G01X313340Y721256D02*
X316540D01*
G01X313340Y715056D02*
Y721256D01*
G01X316540Y715056D02*
X313340D01*
G01X316540Y721256D02*
Y715056D01*
G01X321440Y718156D02*
X324440D01*
G01X321340Y721256D02*
X324540D01*
G01X321340Y715056D02*
Y721256D01*
G01X324540Y715056D02*
X321340D01*
G01X313040Y737556D02*
X309840D01*
G01X313040Y743756D02*
Y737556D01*
G01X309840D02*
Y743756D01*
G01X322040Y737556D02*
X318840D01*
G01D02*
Y743756D01*
G01X317540Y737556D02*
X314340D01*
G01X317540Y743756D02*
Y737556D01*
G01X314340D02*
Y743756D01*
G01X308540Y732256D02*
Y726056D01*
G01X309840Y732256D02*
X313040D01*
G01X309840Y726056D02*
Y732256D01*
G01X313040Y726056D02*
X309840D01*
G01X313040Y732256D02*
Y726056D01*
G01X318840Y732256D02*
X322040D01*
G01X318840Y726056D02*
Y732256D01*
G01X322040Y726056D02*
X318840D01*
G01X314340Y732256D02*
X317540D01*
G01X314340Y726056D02*
Y732256D01*
G01X317540Y726056D02*
X314340D01*
G01X317540Y732256D02*
Y726056D01*
G01X308540Y743756D02*
Y737556D01*
G01X312940Y740656D02*
X309940D01*
G01X309840Y743756D02*
X313040D01*
G01X321940Y740656D02*
X318940D01*
G01X318840Y743756D02*
X322040D01*
G01X317440Y740656D02*
X314440D01*
G01X314340Y743756D02*
X317540D01*
G01X319267Y746067D02*
X316167D01*
Y747026D01*
X316322Y747332D01*
X316529Y747524D01*
X316942Y747601D01*
X317355Y747524D01*
X317614Y747294D01*
X317769Y747026D01*
Y746067D01*
G01Y747026D02*
X319267Y747601D01*
G01Y749934D02*
X319215Y750202D01*
X319060Y750509D01*
X318802Y750701D01*
X318440Y750777D01*
X318079Y750701D01*
X317769Y750471D01*
X317614Y750126D01*
Y749742D01*
X317510Y749512D01*
X317252Y749321D01*
X316890Y749244D01*
X316529Y749359D01*
X316270Y749627D01*
X316167Y749934D01*
X316270Y750241D01*
X316529Y750509D01*
X316890Y750624D01*
X317252Y750547D01*
X317510Y750356D01*
X317614Y750126D01*
Y749742D01*
X317769Y749397D01*
X318079Y749167D01*
X318440Y749091D01*
X318802Y749167D01*
X319060Y749359D01*
X319215Y749666D01*
X319267Y749934D01*
G01X318905Y752382D02*
X319164Y752651D01*
X319267Y752957D01*
X319164Y753264D01*
X318854Y753532D01*
X318389Y753724D01*
X317924Y753801D01*
X317355D01*
X316890Y753724D01*
X316477Y753532D01*
X316270Y753302D01*
X316167Y753034D01*
X316270Y752727D01*
X316477Y752497D01*
X316787Y752344D01*
X317200Y752267D01*
X317562Y752344D01*
X317924Y752536D01*
X318130Y752766D01*
X318182Y753034D01*
X318079Y753341D01*
X317820Y753571D01*
X317355Y753801D01*
G01X318802Y755291D02*
X319060Y755521D01*
X319215Y755789D01*
X319267Y756134D01*
X319164Y756479D01*
X318957Y756747D01*
X318595Y756939D01*
X318182Y756977D01*
X317769Y756901D01*
X317510Y756709D01*
X317304Y756441D01*
X317252Y756172D01*
X317304Y755904D01*
X317510Y755559D01*
X316167Y755674D01*
Y756709D01*
G01X323447Y746067D02*
X320347D01*
Y747026D01*
X320502Y747332D01*
X320709Y747524D01*
X321122Y747601D01*
X321535Y747524D01*
X321794Y747294D01*
X321949Y747026D01*
Y746067D01*
G01Y747026D02*
X323447Y747601D01*
G01Y749934D02*
X323395Y750202D01*
X323240Y750509D01*
X322982Y750701D01*
X322620Y750777D01*
X322259Y750701D01*
X321949Y750471D01*
X321794Y750126D01*
Y749742D01*
X321690Y749512D01*
X321432Y749321D01*
X321070Y749244D01*
X320709Y749359D01*
X320450Y749627D01*
X320347Y749934D01*
X320450Y750241D01*
X320709Y750509D01*
X321070Y750624D01*
X321432Y750547D01*
X321690Y750356D01*
X321794Y750126D01*
Y749742D01*
X321949Y749397D01*
X322259Y749167D01*
X322620Y749091D01*
X322982Y749167D01*
X323240Y749359D01*
X323395Y749666D01*
X323447Y749934D01*
G01X320864Y752306D02*
X320554Y752536D01*
X320399Y752804D01*
X320347Y753111D01*
X320450Y753494D01*
X320709Y753762D01*
X321019Y753839D01*
X321329Y753801D01*
X321587Y753647D01*
X322104Y752881D01*
X322465Y752536D01*
X322982Y752306D01*
X323447Y752229D01*
Y753839D01*
G01X320864Y755406D02*
X320554Y755636D01*
X320399Y755904D01*
X320347Y756211D01*
X320450Y756594D01*
X320709Y756862D01*
X321019Y756939D01*
X321329Y756901D01*
X321587Y756747D01*
X322104Y755981D01*
X322465Y755636D01*
X322982Y755406D01*
X323447Y755329D01*
Y756939D01*
G01X314767Y746067D02*
X311667D01*
Y747026D01*
X311822Y747332D01*
X312029Y747524D01*
X312442Y747601D01*
X312855Y747524D01*
X313114Y747294D01*
X313269Y747026D01*
Y746067D01*
G01Y747026D02*
X314767Y747601D01*
G01Y749934D02*
X314715Y750202D01*
X314560Y750509D01*
X314302Y750701D01*
X313940Y750777D01*
X313579Y750701D01*
X313269Y750471D01*
X313114Y750126D01*
Y749742D01*
X313010Y749512D01*
X312752Y749321D01*
X312390Y749244D01*
X312029Y749359D01*
X311770Y749627D01*
X311667Y749934D01*
X311770Y750241D01*
X312029Y750509D01*
X312390Y750624D01*
X312752Y750547D01*
X313010Y750356D01*
X313114Y750126D01*
Y749742D01*
X313269Y749397D01*
X313579Y749167D01*
X313940Y749091D01*
X314302Y749167D01*
X314560Y749359D01*
X314715Y749666D01*
X314767Y749934D01*
G01X314405Y752382D02*
X314664Y752651D01*
X314767Y752957D01*
X314664Y753264D01*
X314354Y753532D01*
X313889Y753724D01*
X313424Y753801D01*
X312855D01*
X312390Y753724D01*
X311977Y753532D01*
X311770Y753302D01*
X311667Y753034D01*
X311770Y752727D01*
X311977Y752497D01*
X312287Y752344D01*
X312700Y752267D01*
X313062Y752344D01*
X313424Y752536D01*
X313630Y752766D01*
X313682Y753034D01*
X313579Y753341D01*
X313320Y753571D01*
X312855Y753801D01*
G01X314767Y756134D02*
X314715Y756402D01*
X314560Y756709D01*
X314302Y756901D01*
X313940Y756977D01*
X313579Y756901D01*
X313269Y756671D01*
X313114Y756326D01*
Y755942D01*
X313010Y755712D01*
X312752Y755521D01*
X312390Y755444D01*
X312029Y755559D01*
X311770Y755827D01*
X311667Y756134D01*
X311770Y756441D01*
X312029Y756709D01*
X312390Y756824D01*
X312752Y756747D01*
X313010Y756556D01*
X313114Y756326D01*
Y755942D01*
X313269Y755597D01*
X313579Y755367D01*
X313940Y755291D01*
X314302Y755367D01*
X314560Y755559D01*
X314715Y755866D01*
X314767Y756134D01*
G01X310267Y746067D02*
X307167D01*
Y747026D01*
X307322Y747332D01*
X307529Y747524D01*
X307942Y747601D01*
X308355Y747524D01*
X308614Y747294D01*
X308769Y747026D01*
Y746067D01*
G01Y747026D02*
X310267Y747601D01*
G01X309905Y749282D02*
X310164Y749551D01*
X310267Y749857D01*
X310164Y750164D01*
X309854Y750432D01*
X309389Y750624D01*
X308924Y750701D01*
X308355D01*
X307890Y750624D01*
X307477Y750432D01*
X307270Y750202D01*
X307167Y749934D01*
X307270Y749627D01*
X307477Y749397D01*
X307787Y749244D01*
X308200Y749167D01*
X308562Y749244D01*
X308924Y749436D01*
X309130Y749666D01*
X309182Y749934D01*
X309079Y750241D01*
X308820Y750471D01*
X308355Y750701D01*
G01X307167Y753034D02*
X307270Y752727D01*
X307529Y752497D01*
X307839Y752344D01*
X308252Y752229D01*
X308717Y752191D01*
X309182Y752229D01*
X309595Y752344D01*
X309905Y752497D01*
X310164Y752727D01*
X310267Y753034D01*
X310164Y753341D01*
X309905Y753571D01*
X309595Y753724D01*
X309182Y753839D01*
X308717Y753877D01*
X308252Y753839D01*
X307839Y753724D01*
X307529Y753571D01*
X307270Y753341D01*
X307167Y753034D01*
G01X310267Y756134D02*
X307167D01*
X307787Y755674D01*
G01X310267D02*
Y756594D01*
G01X316281Y760558D02*
X316126Y760328D01*
X316023Y760060D01*
Y759753D01*
X316178Y759408D01*
X316436Y759140D01*
X316746Y758948D01*
X317263Y758795D01*
X317728Y758757D01*
X318193Y758833D01*
X318503Y758948D01*
X318813Y759178D01*
X319020Y759447D01*
X319123Y759715D01*
Y759983D01*
X319020Y760252D01*
X318865Y760482D01*
X318658Y760673D01*
G01X317831Y762087D02*
X317470Y762355D01*
X317263Y762585D01*
X317160Y762892D01*
X317263Y763160D01*
X317470Y763352D01*
X317780Y763505D01*
X318141Y763543D01*
X318451Y763505D01*
X318761Y763352D01*
X319020Y763122D01*
X319123Y762853D01*
X319020Y762547D01*
X318710Y762278D01*
X318245Y762125D01*
X317728Y762087D01*
X317056Y762163D01*
X316695Y762278D01*
X316333Y762470D01*
X316075Y762738D01*
X316023Y763007D01*
X316126Y763275D01*
X316385Y763467D01*
G01X318658Y765072D02*
X318916Y765302D01*
X319071Y765570D01*
X319123Y765915D01*
X319020Y766260D01*
X318813Y766528D01*
X318451Y766720D01*
X318038Y766758D01*
X317625Y766682D01*
X317366Y766490D01*
X317160Y766222D01*
X317108Y765953D01*
X317160Y765685D01*
X317366Y765340D01*
X316023Y765455D01*
Y766490D01*
G01X319123Y769015D02*
X319071Y769283D01*
X318916Y769590D01*
X318658Y769782D01*
X318296Y769858D01*
X317935Y769782D01*
X317625Y769552D01*
X317470Y769207D01*
Y768823D01*
X317366Y768593D01*
X317108Y768402D01*
X316746Y768325D01*
X316385Y768440D01*
X316126Y768708D01*
X316023Y769015D01*
X316126Y769322D01*
X316385Y769590D01*
X316746Y769705D01*
X317108Y769628D01*
X317366Y769437D01*
X317470Y769207D01*
Y768823D01*
X317625Y768478D01*
X317935Y768248D01*
X318296Y768172D01*
X318658Y768248D01*
X318916Y768440D01*
X319071Y768747D01*
X319123Y769015D01*
G01X320721Y760558D02*
X320566Y760328D01*
X320463Y760060D01*
Y759753D01*
X320618Y759408D01*
X320876Y759140D01*
X321186Y758948D01*
X321703Y758795D01*
X322168Y758757D01*
X322633Y758833D01*
X322943Y758948D01*
X323253Y759178D01*
X323460Y759447D01*
X323563Y759715D01*
Y759983D01*
X323460Y760252D01*
X323305Y760482D01*
X323098Y760673D01*
G01Y761972D02*
X323356Y762202D01*
X323511Y762470D01*
X323563Y762815D01*
X323460Y763160D01*
X323253Y763428D01*
X322891Y763620D01*
X322478Y763658D01*
X322065Y763582D01*
X321806Y763390D01*
X321600Y763122D01*
X321548Y762853D01*
X321600Y762585D01*
X321806Y762240D01*
X320463Y762355D01*
Y763390D01*
G01X323201Y765263D02*
X323460Y765532D01*
X323563Y765838D01*
X323460Y766145D01*
X323150Y766413D01*
X322685Y766605D01*
X322220Y766682D01*
X321651D01*
X321186Y766605D01*
X320773Y766413D01*
X320566Y766183D01*
X320463Y765915D01*
X320566Y765608D01*
X320773Y765378D01*
X321083Y765225D01*
X321496Y765148D01*
X321858Y765225D01*
X322220Y765417D01*
X322426Y765647D01*
X322478Y765915D01*
X322375Y766222D01*
X322116Y766452D01*
X321651Y766682D01*
G01X323563Y769015D02*
X320463D01*
X321083Y768555D01*
G01X323563D02*
Y769475D01*
G01X311781Y760558D02*
X311626Y760328D01*
X311523Y760060D01*
Y759753D01*
X311678Y759408D01*
X311936Y759140D01*
X312246Y758948D01*
X312763Y758795D01*
X313228Y758757D01*
X313693Y758833D01*
X314003Y758948D01*
X314313Y759178D01*
X314520Y759447D01*
X314623Y759715D01*
Y759983D01*
X314520Y760252D01*
X314365Y760482D01*
X314158Y760673D01*
G01X313331Y762087D02*
X312970Y762355D01*
X312763Y762585D01*
X312660Y762892D01*
X312763Y763160D01*
X312970Y763352D01*
X313280Y763505D01*
X313641Y763543D01*
X313951Y763505D01*
X314261Y763352D01*
X314520Y763122D01*
X314623Y762853D01*
X314520Y762547D01*
X314210Y762278D01*
X313745Y762125D01*
X313228Y762087D01*
X312556Y762163D01*
X312195Y762278D01*
X311833Y762470D01*
X311575Y762738D01*
X311523Y763007D01*
X311626Y763275D01*
X311885Y763467D01*
G01X313331Y765187D02*
X312970Y765455D01*
X312763Y765685D01*
X312660Y765992D01*
X312763Y766260D01*
X312970Y766452D01*
X313280Y766605D01*
X313641Y766643D01*
X313951Y766605D01*
X314261Y766452D01*
X314520Y766222D01*
X314623Y765953D01*
X314520Y765647D01*
X314210Y765378D01*
X313745Y765225D01*
X313228Y765187D01*
X312556Y765263D01*
X312195Y765378D01*
X311833Y765570D01*
X311575Y765838D01*
X311523Y766107D01*
X311626Y766375D01*
X311885Y766567D01*
G01X314623Y769015D02*
X311523D01*
X312143Y768555D01*
G01X314623D02*
Y769475D01*
G01X307606Y760558D02*
X307451Y760328D01*
X307348Y760060D01*
Y759753D01*
X307503Y759408D01*
X307761Y759140D01*
X308071Y758948D01*
X308588Y758795D01*
X309053Y758757D01*
X309518Y758833D01*
X309828Y758948D01*
X310138Y759178D01*
X310345Y759447D01*
X310448Y759715D01*
Y759983D01*
X310345Y760252D01*
X310190Y760482D01*
X309983Y760673D01*
G01X309156Y762087D02*
X308795Y762355D01*
X308588Y762585D01*
X308485Y762892D01*
X308588Y763160D01*
X308795Y763352D01*
X309105Y763505D01*
X309466Y763543D01*
X309776Y763505D01*
X310086Y763352D01*
X310345Y763122D01*
X310448Y762853D01*
X310345Y762547D01*
X310035Y762278D01*
X309570Y762125D01*
X309053Y762087D01*
X308381Y762163D01*
X308020Y762278D01*
X307658Y762470D01*
X307400Y762738D01*
X307348Y763007D01*
X307451Y763275D01*
X307710Y763467D01*
G01X309156Y765187D02*
X308795Y765455D01*
X308588Y765685D01*
X308485Y765992D01*
X308588Y766260D01*
X308795Y766452D01*
X309105Y766605D01*
X309466Y766643D01*
X309776Y766605D01*
X310086Y766452D01*
X310345Y766222D01*
X310448Y765953D01*
X310345Y765647D01*
X310035Y765378D01*
X309570Y765225D01*
X309053Y765187D01*
X308381Y765263D01*
X308020Y765378D01*
X307658Y765570D01*
X307400Y765838D01*
X307348Y766107D01*
X307451Y766375D01*
X307710Y766567D01*
G01X310448Y769475D02*
X307348D01*
X309570Y768057D01*
Y769973D01*
G01X338883Y7130D02*
X323883D01*
G01D02*
Y13930D01*
G01D02*
X338883D01*
G01X331383Y13830D02*
Y7230D01*
G01X322863Y33290D02*
Y6912D01*
G01X338883Y23130D02*
X323883D01*
G01D02*
Y29930D01*
G01X331383Y29830D02*
Y23230D01*
G01X323883Y15130D02*
Y21930D01*
G01D02*
X338883D01*
G01Y15130D02*
X323883D01*
G01X331383Y21830D02*
Y15230D01*
G01X323883Y29930D02*
X338883D01*
G01X334530Y33931D02*
Y30731D01*
G01X331430Y33831D02*
Y30831D01*
G01X334530Y30731D02*
X328330D01*
G01D02*
Y33931D01*
G01D02*
X334530D01*
G01X336764Y53696D02*
X336609Y53466D01*
X336506Y53198D01*
Y52891D01*
X336661Y52546D01*
X336919Y52278D01*
X337229Y52086D01*
X337746Y51933D01*
X338211Y51895D01*
X338676Y51971D01*
X338986Y52086D01*
X339296Y52316D01*
X339503Y52585D01*
X339606Y52853D01*
Y53121D01*
X339503Y53390D01*
X339348Y53620D01*
X339141Y53811D01*
G01X339606Y55953D02*
X336506D01*
X337126Y55493D01*
G01X339606D02*
Y56413D01*
G01Y59513D02*
X336506D01*
X338728Y58095D01*
Y60011D01*
G01X339141Y61310D02*
X339399Y61540D01*
X339554Y61808D01*
X339606Y62153D01*
X339503Y62498D01*
X339296Y62766D01*
X338934Y62958D01*
X338521Y62996D01*
X338108Y62920D01*
X337849Y62728D01*
X337643Y62460D01*
X337591Y62191D01*
X337643Y61923D01*
X337849Y61578D01*
X336506Y61693D01*
Y62728D01*
G01X332764Y53696D02*
X332609Y53466D01*
X332506Y53198D01*
Y52891D01*
X332661Y52546D01*
X332919Y52278D01*
X333229Y52086D01*
X333746Y51933D01*
X334211Y51895D01*
X334676Y51971D01*
X334986Y52086D01*
X335296Y52316D01*
X335503Y52585D01*
X335606Y52853D01*
Y53121D01*
X335503Y53390D01*
X335348Y53620D01*
X335141Y53811D01*
G01X335606Y55953D02*
X332506D01*
X333126Y55493D01*
G01X335606D02*
Y56413D01*
G01Y59513D02*
X332506D01*
X334728Y58095D01*
Y60011D01*
G01X335244Y61501D02*
X335503Y61770D01*
X335606Y62076D01*
X335503Y62383D01*
X335193Y62651D01*
X334728Y62843D01*
X334263Y62920D01*
X333694D01*
X333229Y62843D01*
X332816Y62651D01*
X332609Y62421D01*
X332506Y62153D01*
X332609Y61846D01*
X332816Y61616D01*
X333126Y61463D01*
X333539Y61386D01*
X333901Y61463D01*
X334263Y61655D01*
X334469Y61885D01*
X334521Y62153D01*
X334418Y62460D01*
X334159Y62690D01*
X333694Y62920D01*
G01X328764Y53696D02*
X328609Y53466D01*
X328506Y53198D01*
Y52891D01*
X328661Y52546D01*
X328919Y52278D01*
X329229Y52086D01*
X329746Y51933D01*
X330211Y51895D01*
X330676Y51971D01*
X330986Y52086D01*
X331296Y52316D01*
X331503Y52585D01*
X331606Y52853D01*
Y53121D01*
X331503Y53390D01*
X331348Y53620D01*
X331141Y53811D01*
G01X331606Y55953D02*
X328506D01*
X329126Y55493D01*
G01X331606D02*
Y56413D01*
G01X330314Y58325D02*
X329953Y58593D01*
X329746Y58823D01*
X329643Y59130D01*
X329746Y59398D01*
X329953Y59590D01*
X330263Y59743D01*
X330624Y59781D01*
X330934Y59743D01*
X331244Y59590D01*
X331503Y59360D01*
X331606Y59091D01*
X331503Y58785D01*
X331193Y58516D01*
X330728Y58363D01*
X330211Y58325D01*
X329539Y58401D01*
X329178Y58516D01*
X328816Y58708D01*
X328558Y58976D01*
X328506Y59245D01*
X328609Y59513D01*
X328868Y59705D01*
G01X330314Y61425D02*
X329953Y61693D01*
X329746Y61923D01*
X329643Y62230D01*
X329746Y62498D01*
X329953Y62690D01*
X330263Y62843D01*
X330624Y62881D01*
X330934Y62843D01*
X331244Y62690D01*
X331503Y62460D01*
X331606Y62191D01*
X331503Y61885D01*
X331193Y61616D01*
X330728Y61463D01*
X330211Y61425D01*
X329539Y61501D01*
X329178Y61616D01*
X328816Y61808D01*
X328558Y62076D01*
X328506Y62345D01*
X328609Y62613D01*
X328868Y62805D01*
G01X324499Y53696D02*
X324344Y53466D01*
X324241Y53198D01*
Y52891D01*
X324396Y52546D01*
X324654Y52278D01*
X324964Y52086D01*
X325481Y51933D01*
X325946Y51895D01*
X326411Y51971D01*
X326721Y52086D01*
X327031Y52316D01*
X327238Y52585D01*
X327341Y52853D01*
Y53121D01*
X327238Y53390D01*
X327083Y53620D01*
X326876Y53811D01*
G01X327341Y55953D02*
X324241D01*
X324861Y55493D01*
G01X327341D02*
Y56413D01*
G01Y58976D02*
X326669Y59053D01*
X326101Y59168D01*
X325584Y59321D01*
X325016Y59513D01*
X324241Y59820D01*
Y58286D01*
G01X326049Y61425D02*
X325688Y61693D01*
X325481Y61923D01*
X325378Y62230D01*
X325481Y62498D01*
X325688Y62690D01*
X325998Y62843D01*
X326359Y62881D01*
X326669Y62843D01*
X326979Y62690D01*
X327238Y62460D01*
X327341Y62191D01*
X327238Y61885D01*
X326928Y61616D01*
X326463Y61463D01*
X325946Y61425D01*
X325274Y61501D01*
X324913Y61616D01*
X324551Y61808D01*
X324293Y62076D01*
X324241Y62345D01*
X324344Y62613D01*
X324603Y62805D01*
G01X322066Y72704D02*
Y66504D01*
G01X322866Y72704D02*
X326066D01*
G01X325966Y69604D02*
X322966D01*
G01X322866Y66504D02*
Y72704D01*
G01X326066D02*
Y66504D01*
G01D02*
X322866D01*
G01X326052Y164646D02*
X322952D01*
Y165605D01*
X323107Y165911D01*
X323314Y166103D01*
X323727Y166180D01*
X324140Y166103D01*
X324399Y165873D01*
X324554Y165605D01*
Y164646D01*
G01Y165605D02*
X326052Y166180D01*
G01Y168513D02*
X326000Y168781D01*
X325845Y169088D01*
X325587Y169280D01*
X325225Y169356D01*
X324864Y169280D01*
X324554Y169050D01*
X324399Y168705D01*
Y168321D01*
X324295Y168091D01*
X324037Y167900D01*
X323675Y167823D01*
X323314Y167938D01*
X323055Y168206D01*
X322952Y168513D01*
X323055Y168820D01*
X323314Y169088D01*
X323675Y169203D01*
X324037Y169126D01*
X324295Y168935D01*
X324399Y168705D01*
Y168321D01*
X324554Y167976D01*
X324864Y167746D01*
X325225Y167670D01*
X325587Y167746D01*
X325845Y167938D01*
X326000Y168245D01*
X326052Y168513D01*
G01X325432Y170770D02*
X325794Y171000D01*
X326000Y171306D01*
X326052Y171651D01*
X326000Y171958D01*
X325742Y172265D01*
X325432Y172456D01*
X325122Y172495D01*
X324760Y172418D01*
X324502Y172150D01*
X324399Y171881D01*
Y171536D01*
G01Y171881D02*
X324244Y172111D01*
X323985Y172303D01*
X323675Y172380D01*
X323365Y172303D01*
X323107Y172111D01*
X322952Y171766D01*
X323004Y171421D01*
X323210Y171076D01*
G01X330052Y164646D02*
X326952D01*
Y165605D01*
X327107Y165911D01*
X327314Y166103D01*
X327727Y166180D01*
X328140Y166103D01*
X328399Y165873D01*
X328554Y165605D01*
Y164646D01*
G01Y165605D02*
X330052Y166180D01*
G01Y168513D02*
X330000Y168781D01*
X329845Y169088D01*
X329587Y169280D01*
X329225Y169356D01*
X328864Y169280D01*
X328554Y169050D01*
X328399Y168705D01*
Y168321D01*
X328295Y168091D01*
X328037Y167900D01*
X327675Y167823D01*
X327314Y167938D01*
X327055Y168206D01*
X326952Y168513D01*
X327055Y168820D01*
X327314Y169088D01*
X327675Y169203D01*
X328037Y169126D01*
X328295Y168935D01*
X328399Y168705D01*
Y168321D01*
X328554Y167976D01*
X328864Y167746D01*
X329225Y167670D01*
X329587Y167746D01*
X329845Y167938D01*
X330000Y168245D01*
X330052Y168513D01*
G01X326952Y171613D02*
X327055Y171306D01*
X327314Y171076D01*
X327624Y170923D01*
X328037Y170808D01*
X328502Y170770D01*
X328967Y170808D01*
X329380Y170923D01*
X329690Y171076D01*
X329949Y171306D01*
X330052Y171613D01*
X329949Y171920D01*
X329690Y172150D01*
X329380Y172303D01*
X328967Y172418D01*
X328502Y172456D01*
X328037Y172418D01*
X327624Y172303D01*
X327314Y172150D01*
X327055Y171920D01*
X326952Y171613D01*
G01X334062Y164646D02*
X330962D01*
Y165605D01*
X331117Y165911D01*
X331324Y166103D01*
X331737Y166180D01*
X332150Y166103D01*
X332409Y165873D01*
X332564Y165605D01*
Y164646D01*
G01Y165605D02*
X334062Y166180D01*
G01Y168973D02*
X330962D01*
X333184Y167555D01*
Y169471D01*
G01X333700Y170961D02*
X333959Y171230D01*
X334062Y171536D01*
X333959Y171843D01*
X333649Y172111D01*
X333184Y172303D01*
X332719Y172380D01*
X332150D01*
X331685Y172303D01*
X331272Y172111D01*
X331065Y171881D01*
X330962Y171613D01*
X331065Y171306D01*
X331272Y171076D01*
X331582Y170923D01*
X331995Y170846D01*
X332357Y170923D01*
X332719Y171115D01*
X332925Y171345D01*
X332977Y171613D01*
X332874Y171920D01*
X332615Y172150D01*
X332150Y172380D01*
G01X334062Y174636D02*
X333390Y174713D01*
X332822Y174828D01*
X332305Y174981D01*
X331737Y175173D01*
X330962Y175480D01*
Y173946D01*
G01X338062Y164646D02*
X334962D01*
Y165605D01*
X335117Y165911D01*
X335324Y166103D01*
X335737Y166180D01*
X336150Y166103D01*
X336409Y165873D01*
X336564Y165605D01*
Y164646D01*
G01Y165605D02*
X338062Y166180D01*
G01Y168513D02*
X338010Y168781D01*
X337855Y169088D01*
X337597Y169280D01*
X337235Y169356D01*
X336874Y169280D01*
X336564Y169050D01*
X336409Y168705D01*
Y168321D01*
X336305Y168091D01*
X336047Y167900D01*
X335685Y167823D01*
X335324Y167938D01*
X335065Y168206D01*
X334962Y168513D01*
X335065Y168820D01*
X335324Y169088D01*
X335685Y169203D01*
X336047Y169126D01*
X336305Y168935D01*
X336409Y168705D01*
Y168321D01*
X336564Y167976D01*
X336874Y167746D01*
X337235Y167670D01*
X337597Y167746D01*
X337855Y167938D01*
X338010Y168245D01*
X338062Y168513D01*
G01X335479Y170885D02*
X335169Y171115D01*
X335014Y171383D01*
X334962Y171690D01*
X335065Y172073D01*
X335324Y172341D01*
X335634Y172418D01*
X335944Y172380D01*
X336202Y172226D01*
X336719Y171460D01*
X337080Y171115D01*
X337597Y170885D01*
X338062Y170808D01*
Y172418D01*
G01X324580Y174230D02*
Y180660D01*
G01X329161Y230570D02*
X326061D01*
Y231529D01*
X326216Y231835D01*
X326423Y232027D01*
X326836Y232104D01*
X327249Y232027D01*
X327508Y231797D01*
X327663Y231529D01*
Y230570D01*
G01Y231529D02*
X329161Y232104D01*
G01Y234437D02*
X326061D01*
X326681Y233977D01*
G01X329161D02*
Y234897D01*
G01X326061Y237537D02*
X326164Y237230D01*
X326423Y237000D01*
X326733Y236847D01*
X327146Y236732D01*
X327611Y236694D01*
X328076Y236732D01*
X328489Y236847D01*
X328799Y237000D01*
X329058Y237230D01*
X329161Y237537D01*
X329058Y237844D01*
X328799Y238074D01*
X328489Y238227D01*
X328076Y238342D01*
X327611Y238380D01*
X327146Y238342D01*
X326733Y238227D01*
X326423Y238074D01*
X326164Y237844D01*
X326061Y237537D01*
G01X328541Y239794D02*
X328903Y240024D01*
X329109Y240330D01*
X329161Y240675D01*
X329109Y240982D01*
X328851Y241289D01*
X328541Y241480D01*
X328231Y241519D01*
X327869Y241442D01*
X327611Y241174D01*
X327508Y240905D01*
Y240560D01*
G01Y240905D02*
X327353Y241135D01*
X327094Y241327D01*
X326784Y241404D01*
X326474Y241327D01*
X326216Y241135D01*
X326061Y240790D01*
X326113Y240445D01*
X326319Y240100D01*
G01X333161Y230570D02*
X330061D01*
Y231529D01*
X330216Y231835D01*
X330423Y232027D01*
X330836Y232104D01*
X331249Y232027D01*
X331508Y231797D01*
X331663Y231529D01*
Y230570D01*
G01Y231529D02*
X333161Y232104D01*
G01Y234437D02*
X330061D01*
X330681Y233977D01*
G01X333161D02*
Y234897D01*
G01Y237537D02*
X330061D01*
X330681Y237077D01*
G01X333161D02*
Y237997D01*
G01X332541Y239794D02*
X332903Y240024D01*
X333109Y240330D01*
X333161Y240675D01*
X333109Y240982D01*
X332851Y241289D01*
X332541Y241480D01*
X332231Y241519D01*
X331869Y241442D01*
X331611Y241174D01*
X331508Y240905D01*
Y240560D01*
G01Y240905D02*
X331353Y241135D01*
X331094Y241327D01*
X330784Y241404D01*
X330474Y241327D01*
X330216Y241135D01*
X330061Y240790D01*
X330113Y240445D01*
X330319Y240100D01*
G01X321876Y250384D02*
X321721Y250154D01*
X321618Y249886D01*
Y249579D01*
X321773Y249234D01*
X322031Y248966D01*
X322341Y248774D01*
X322858Y248621D01*
X323323Y248583D01*
X323788Y248659D01*
X324098Y248774D01*
X324408Y249004D01*
X324615Y249273D01*
X324718Y249541D01*
Y249809D01*
X324615Y250078D01*
X324460Y250308D01*
X324253Y250499D01*
G01X324718Y252641D02*
X324666Y252909D01*
X324511Y253216D01*
X324253Y253408D01*
X323891Y253484D01*
X323530Y253408D01*
X323220Y253178D01*
X323065Y252833D01*
Y252449D01*
X322961Y252219D01*
X322703Y252028D01*
X322341Y251951D01*
X321980Y252066D01*
X321721Y252334D01*
X321618Y252641D01*
X321721Y252948D01*
X321980Y253216D01*
X322341Y253331D01*
X322703Y253254D01*
X322961Y253063D01*
X323065Y252833D01*
Y252449D01*
X323220Y252104D01*
X323530Y251874D01*
X323891Y251798D01*
X324253Y251874D01*
X324511Y252066D01*
X324666Y252373D01*
X324718Y252641D01*
G01X322135Y255013D02*
X321825Y255243D01*
X321670Y255511D01*
X321618Y255818D01*
X321721Y256201D01*
X321980Y256469D01*
X322290Y256546D01*
X322600Y256508D01*
X322858Y256354D01*
X323375Y255588D01*
X323736Y255243D01*
X324253Y255013D01*
X324718Y254936D01*
Y256546D01*
G01X325876Y250384D02*
X325721Y250154D01*
X325618Y249886D01*
Y249579D01*
X325773Y249234D01*
X326031Y248966D01*
X326341Y248774D01*
X326858Y248621D01*
X327323Y248583D01*
X327788Y248659D01*
X328098Y248774D01*
X328408Y249004D01*
X328615Y249273D01*
X328718Y249541D01*
Y249809D01*
X328615Y250078D01*
X328460Y250308D01*
X328253Y250499D01*
G01X328718Y252641D02*
X328666Y252909D01*
X328511Y253216D01*
X328253Y253408D01*
X327891Y253484D01*
X327530Y253408D01*
X327220Y253178D01*
X327065Y252833D01*
Y252449D01*
X326961Y252219D01*
X326703Y252028D01*
X326341Y251951D01*
X325980Y252066D01*
X325721Y252334D01*
X325618Y252641D01*
X325721Y252948D01*
X325980Y253216D01*
X326341Y253331D01*
X326703Y253254D01*
X326961Y253063D01*
X327065Y252833D01*
Y252449D01*
X327220Y252104D01*
X327530Y251874D01*
X327891Y251798D01*
X328253Y251874D01*
X328511Y252066D01*
X328666Y252373D01*
X328718Y252641D01*
G01X328356Y255089D02*
X328615Y255358D01*
X328718Y255664D01*
X328615Y255971D01*
X328305Y256239D01*
X327840Y256431D01*
X327375Y256508D01*
X326806D01*
X326341Y256431D01*
X325928Y256239D01*
X325721Y256009D01*
X325618Y255741D01*
X325721Y255434D01*
X325928Y255204D01*
X326238Y255051D01*
X326651Y254974D01*
X327013Y255051D01*
X327375Y255243D01*
X327581Y255473D01*
X327633Y255741D01*
X327530Y256048D01*
X327271Y256278D01*
X326806Y256508D01*
G01X329876Y250384D02*
X329721Y250154D01*
X329618Y249886D01*
Y249579D01*
X329773Y249234D01*
X330031Y248966D01*
X330341Y248774D01*
X330858Y248621D01*
X331323Y248583D01*
X331788Y248659D01*
X332098Y248774D01*
X332408Y249004D01*
X332615Y249273D01*
X332718Y249541D01*
Y249809D01*
X332615Y250078D01*
X332460Y250308D01*
X332253Y250499D01*
G01X332718Y252641D02*
X332666Y252909D01*
X332511Y253216D01*
X332253Y253408D01*
X331891Y253484D01*
X331530Y253408D01*
X331220Y253178D01*
X331065Y252833D01*
Y252449D01*
X330961Y252219D01*
X330703Y252028D01*
X330341Y251951D01*
X329980Y252066D01*
X329721Y252334D01*
X329618Y252641D01*
X329721Y252948D01*
X329980Y253216D01*
X330341Y253331D01*
X330703Y253254D01*
X330961Y253063D01*
X331065Y252833D01*
Y252449D01*
X331220Y252104D01*
X331530Y251874D01*
X331891Y251798D01*
X332253Y251874D01*
X332511Y252066D01*
X332666Y252373D01*
X332718Y252641D01*
G01Y255741D02*
X332666Y256009D01*
X332511Y256316D01*
X332253Y256508D01*
X331891Y256584D01*
X331530Y256508D01*
X331220Y256278D01*
X331065Y255933D01*
Y255549D01*
X330961Y255319D01*
X330703Y255128D01*
X330341Y255051D01*
X329980Y255166D01*
X329721Y255434D01*
X329618Y255741D01*
X329721Y256048D01*
X329980Y256316D01*
X330341Y256431D01*
X330703Y256354D01*
X330961Y256163D01*
X331065Y255933D01*
Y255549D01*
X331220Y255204D01*
X331530Y254974D01*
X331891Y254898D01*
X332253Y254974D01*
X332511Y255166D01*
X332666Y255473D01*
X332718Y255741D01*
G01X333876Y250384D02*
X333721Y250154D01*
X333618Y249886D01*
Y249579D01*
X333773Y249234D01*
X334031Y248966D01*
X334341Y248774D01*
X334858Y248621D01*
X335323Y248583D01*
X335788Y248659D01*
X336098Y248774D01*
X336408Y249004D01*
X336615Y249273D01*
X336718Y249541D01*
Y249809D01*
X336615Y250078D01*
X336460Y250308D01*
X336253Y250499D01*
G01X336356Y251989D02*
X336615Y252258D01*
X336718Y252564D01*
X336615Y252871D01*
X336305Y253139D01*
X335840Y253331D01*
X335375Y253408D01*
X334806D01*
X334341Y253331D01*
X333928Y253139D01*
X333721Y252909D01*
X333618Y252641D01*
X333721Y252334D01*
X333928Y252104D01*
X334238Y251951D01*
X334651Y251874D01*
X335013Y251951D01*
X335375Y252143D01*
X335581Y252373D01*
X335633Y252641D01*
X335530Y252948D01*
X335271Y253178D01*
X334806Y253408D01*
G01X333618Y255741D02*
X333721Y255434D01*
X333980Y255204D01*
X334290Y255051D01*
X334703Y254936D01*
X335168Y254898D01*
X335633Y254936D01*
X336046Y255051D01*
X336356Y255204D01*
X336615Y255434D01*
X336718Y255741D01*
X336615Y256048D01*
X336356Y256278D01*
X336046Y256431D01*
X335633Y256546D01*
X335168Y256584D01*
X334703Y256546D01*
X334290Y256431D01*
X333980Y256278D01*
X333721Y256048D01*
X333618Y255741D01*
G01X339397Y264993D02*
X338002D01*
X336297Y264226D01*
G01Y265760D02*
X338002Y264993D01*
G01X336814Y267365D02*
X336504Y267595D01*
X336349Y267863D01*
X336297Y268170D01*
X336400Y268553D01*
X336659Y268821D01*
X336969Y268898D01*
X337279Y268860D01*
X337537Y268706D01*
X338054Y267940D01*
X338415Y267595D01*
X338932Y267365D01*
X339397Y267288D01*
Y268898D01*
G01X331549Y259899D02*
X331394Y259669D01*
X331291Y259401D01*
Y259094D01*
X331446Y258749D01*
X331704Y258481D01*
X332014Y258289D01*
X332531Y258136D01*
X332996Y258098D01*
X333461Y258174D01*
X333771Y258289D01*
X334081Y258519D01*
X334288Y258788D01*
X334391Y259056D01*
Y259324D01*
X334288Y259593D01*
X334133Y259823D01*
X333926Y260014D01*
G01X331808Y261428D02*
X331498Y261658D01*
X331343Y261926D01*
X331291Y262233D01*
X331394Y262616D01*
X331653Y262884D01*
X331963Y262961D01*
X332273Y262923D01*
X332531Y262769D01*
X333048Y262003D01*
X333409Y261658D01*
X333926Y261428D01*
X334391Y261351D01*
Y262961D01*
G01Y265716D02*
X331291D01*
X333513Y264298D01*
Y266214D01*
G01X329795Y263253D02*
X326695D01*
Y264212D01*
X326850Y264518D01*
X327057Y264710D01*
X327470Y264787D01*
X327883Y264710D01*
X328142Y264480D01*
X328297Y264212D01*
Y263253D01*
G01Y264212D02*
X329795Y264787D01*
G01X328503Y266392D02*
X328142Y266660D01*
X327935Y266890D01*
X327832Y267197D01*
X327935Y267465D01*
X328142Y267657D01*
X328452Y267810D01*
X328813Y267848D01*
X329123Y267810D01*
X329433Y267657D01*
X329692Y267427D01*
X329795Y267158D01*
X329692Y266852D01*
X329382Y266583D01*
X328917Y266430D01*
X328400Y266392D01*
X327728Y266468D01*
X327367Y266583D01*
X327005Y266775D01*
X326747Y267043D01*
X326695Y267312D01*
X326798Y267580D01*
X327057Y267772D01*
G01X329795Y270680D02*
X326695D01*
X328917Y269262D01*
Y271178D01*
G01X327040Y276630D02*
X340350D01*
G01X327040Y313630D02*
Y276630D01*
G01X331734Y269241D02*
X331579Y269011D01*
X331476Y268743D01*
Y268436D01*
X331631Y268091D01*
X331889Y267823D01*
X332199Y267631D01*
X332716Y267478D01*
X333181Y267440D01*
X333646Y267516D01*
X333956Y267631D01*
X334266Y267861D01*
X334473Y268130D01*
X334576Y268398D01*
Y268666D01*
X334473Y268935D01*
X334318Y269165D01*
X334111Y269356D01*
G01X331993Y270770D02*
X331683Y271000D01*
X331528Y271268D01*
X331476Y271575D01*
X331579Y271958D01*
X331838Y272226D01*
X332148Y272303D01*
X332458Y272265D01*
X332716Y272111D01*
X333233Y271345D01*
X333594Y271000D01*
X334111Y270770D01*
X334576Y270693D01*
Y272303D01*
G01X334111Y273755D02*
X334369Y273985D01*
X334524Y274253D01*
X334576Y274598D01*
X334473Y274943D01*
X334266Y275211D01*
X333904Y275403D01*
X333491Y275441D01*
X333078Y275365D01*
X332819Y275173D01*
X332613Y274905D01*
X332561Y274636D01*
X332613Y274368D01*
X332819Y274023D01*
X331476Y274138D01*
Y275173D01*
G01X321974Y297328D02*
Y291128D01*
G01X339234Y293933D02*
X336134D01*
Y294892D01*
X336289Y295198D01*
X336496Y295390D01*
X336909Y295467D01*
X337322Y295390D01*
X337581Y295160D01*
X337736Y294892D01*
Y293933D01*
G01Y294892D02*
X339234Y295467D01*
G01Y297800D02*
X336134D01*
X336754Y297340D01*
G01X339234D02*
Y298260D01*
G01X336134Y300900D02*
X336237Y300593D01*
X336496Y300363D01*
X336806Y300210D01*
X337219Y300095D01*
X337684Y300057D01*
X338149Y300095D01*
X338562Y300210D01*
X338872Y300363D01*
X339131Y300593D01*
X339234Y300900D01*
X339131Y301207D01*
X338872Y301437D01*
X338562Y301590D01*
X338149Y301705D01*
X337684Y301743D01*
X337219Y301705D01*
X336806Y301590D01*
X336496Y301437D01*
X336237Y301207D01*
X336134Y300900D01*
G01X339234Y304460D02*
X336134D01*
X338356Y303042D01*
Y304958D01*
G01X338872Y306448D02*
X339131Y306717D01*
X339234Y307023D01*
X339131Y307330D01*
X338821Y307598D01*
X338356Y307790D01*
X337891Y307867D01*
X337322D01*
X336857Y307790D01*
X336444Y307598D01*
X336237Y307368D01*
X336134Y307100D01*
X336237Y306793D01*
X336444Y306563D01*
X336754Y306410D01*
X337167Y306333D01*
X337529Y306410D01*
X337891Y306602D01*
X338097Y306832D01*
X338149Y307100D01*
X338046Y307407D01*
X337787Y307637D01*
X337322Y307867D01*
G01X322841Y297289D02*
X326041D01*
G01D02*
Y291089D01*
G01D02*
X322841D01*
G01D02*
Y297289D01*
G01X330748Y312427D02*
X333948D01*
G01X330748Y306227D02*
Y312427D01*
G01X333948D02*
Y306227D01*
G01D02*
X330748D01*
G01X334830Y313630D02*
X327040D01*
G01X334830Y323410D02*
Y313630D01*
G01X337510Y323410D02*
X334830D01*
G01X336593Y342089D02*
Y324763D01*
G01D02*
X332340D01*
G01X328387Y342089D02*
Y324763D01*
G01D02*
X332440D01*
G01X324240Y320752D02*
Y314552D01*
G01X325040Y320752D02*
X328240D01*
G01X325040Y314552D02*
Y320752D01*
G01X328240Y314552D02*
X325040D01*
G01X328240Y320752D02*
Y314552D01*
G01X325140Y317652D02*
X328140D01*
G01X329040Y320752D02*
X332240D01*
G01Y314552D02*
X329040D01*
G01X332240Y320752D02*
Y314552D01*
G01X329140Y317652D02*
X332140D01*
G01X329040Y314552D02*
Y320752D01*
G01X324100Y326196D02*
Y332396D01*
G01X327300D02*
Y326196D01*
G01D02*
X324100D01*
G01X332040Y342089D02*
X336593D01*
G01X332040D02*
X328387D01*
G01X324200Y336376D02*
X327200D01*
G01X324100Y339476D02*
X327300D01*
G01D02*
Y333276D01*
G01D02*
X324100D01*
G01D02*
Y339476D01*
G01X327200Y329296D02*
X324200D01*
G01X324100Y332396D02*
X327300D01*
G01X322709Y335536D02*
Y329336D01*
G01X323987Y343860D02*
Y346360D01*
X324653D01*
X324867Y346235D01*
X325000Y346068D01*
X325053Y345735D01*
X325000Y345402D01*
X324840Y345193D01*
X324653Y345068D01*
X323987D01*
G01X324653D02*
X325053Y343860D01*
G01X326720D02*
Y346360D01*
X326400Y345860D01*
G01Y343860D02*
X327040D01*
G01X328333Y344360D02*
X328493Y344068D01*
X328707Y343902D01*
X328947Y343860D01*
X329160Y343902D01*
X329373Y344110D01*
X329507Y344360D01*
X329533Y344610D01*
X329480Y344902D01*
X329293Y345110D01*
X329107Y345193D01*
X328867D01*
G01X329107D02*
X329267Y345318D01*
X329400Y345527D01*
X329453Y345777D01*
X329400Y346027D01*
X329267Y346235D01*
X329027Y346360D01*
X328787Y346318D01*
X328547Y346152D01*
G01X330613Y344902D02*
X330800Y345193D01*
X330960Y345360D01*
X331173Y345443D01*
X331360Y345360D01*
X331493Y345193D01*
X331600Y344943D01*
X331627Y344652D01*
X331600Y344402D01*
X331493Y344152D01*
X331333Y343943D01*
X331147Y343860D01*
X330933Y343943D01*
X330747Y344193D01*
X330640Y344568D01*
X330613Y344985D01*
X330667Y345527D01*
X330747Y345818D01*
X330880Y346110D01*
X331067Y346318D01*
X331253Y346360D01*
X331440Y346277D01*
X331573Y346068D01*
G01X338625Y360944D02*
X338395Y361099D01*
X338127Y361202D01*
X337820D01*
X337475Y361047D01*
X337207Y360789D01*
X337015Y360479D01*
X336862Y359962D01*
X336824Y359497D01*
X336900Y359032D01*
X337015Y358722D01*
X337245Y358412D01*
X337514Y358205D01*
X337782Y358102D01*
X338050D01*
X338319Y358205D01*
X338549Y358360D01*
X338740Y358567D01*
G01X340882Y358102D02*
Y361202D01*
X340422Y360582D01*
G01Y358102D02*
X341342D01*
G01X343982D02*
Y361202D01*
X343522Y360582D01*
G01Y358102D02*
X344442D01*
G01X347082Y361202D02*
X346775Y361099D01*
X346545Y360840D01*
X346392Y360530D01*
X346277Y360117D01*
X346239Y359652D01*
X346277Y359187D01*
X346392Y358774D01*
X346545Y358464D01*
X346775Y358205D01*
X347082Y358102D01*
X347389Y358205D01*
X347619Y358464D01*
X347772Y358774D01*
X347887Y359187D01*
X347925Y359652D01*
X347887Y360117D01*
X347772Y360530D01*
X347619Y360840D01*
X347389Y361099D01*
X347082Y361202D01*
G01X323545Y356765D02*
Y359265D01*
X324211D01*
X324425Y359140D01*
X324558Y358973D01*
X324611Y358640D01*
X324558Y358307D01*
X324398Y358098D01*
X324211Y357973D01*
X323545D01*
G01X324211D02*
X324611Y356765D01*
G01X326278D02*
Y359265D01*
X325958Y358765D01*
G01Y356765D02*
X326598D01*
G01X327891Y357265D02*
X328051Y356973D01*
X328265Y356807D01*
X328505Y356765D01*
X328718Y356807D01*
X328931Y357015D01*
X329065Y357265D01*
X329091Y357515D01*
X329038Y357807D01*
X328851Y358015D01*
X328665Y358098D01*
X328425D01*
G01X328665D02*
X328825Y358223D01*
X328958Y358432D01*
X329011Y358682D01*
X328958Y358932D01*
X328825Y359140D01*
X328585Y359265D01*
X328345Y359223D01*
X328105Y359057D01*
G01X330678Y356765D02*
X330865Y356807D01*
X331078Y356932D01*
X331211Y357140D01*
X331265Y357432D01*
X331211Y357723D01*
X331051Y357973D01*
X330811Y358098D01*
X330545D01*
X330385Y358182D01*
X330251Y358390D01*
X330198Y358682D01*
X330278Y358973D01*
X330465Y359182D01*
X330678Y359265D01*
X330891Y359182D01*
X331078Y358973D01*
X331158Y358682D01*
X331105Y358390D01*
X330971Y358182D01*
X330811Y358098D01*
X330545D01*
X330305Y357973D01*
X330145Y357723D01*
X330091Y357432D01*
X330145Y357140D01*
X330278Y356932D01*
X330491Y356807D01*
X330678Y356765D01*
G01X325533Y355401D02*
X331733D01*
G01D02*
Y352201D01*
G01D02*
X325533D01*
G01D02*
Y355401D01*
G01X325483Y350821D02*
X331683D01*
G01D02*
Y347621D01*
G01D02*
X325483D01*
G01D02*
Y350821D01*
G01X334644Y374498D02*
Y376998D01*
X334324Y376498D01*
G01Y374498D02*
X334964D01*
G01X335819Y374526D02*
Y416652D01*
G01X373339Y374526D02*
X335819D01*
G01X338483Y372997D02*
X338253Y373152D01*
X337985Y373255D01*
X337678D01*
X337333Y373100D01*
X337065Y372842D01*
X336873Y372532D01*
X336720Y372015D01*
X336682Y371550D01*
X336758Y371085D01*
X336873Y370775D01*
X337103Y370465D01*
X337372Y370258D01*
X337640Y370155D01*
X337908D01*
X338177Y370258D01*
X338407Y370413D01*
X338598Y370620D01*
G01X340740Y370155D02*
X341008Y370207D01*
X341315Y370362D01*
X341507Y370620D01*
X341583Y370982D01*
X341507Y371343D01*
X341277Y371653D01*
X340932Y371808D01*
X340548D01*
X340318Y371912D01*
X340127Y372170D01*
X340050Y372532D01*
X340165Y372893D01*
X340433Y373152D01*
X340740Y373255D01*
X341047Y373152D01*
X341315Y372893D01*
X341430Y372532D01*
X341353Y372170D01*
X341162Y371912D01*
X340932Y371808D01*
X340548D01*
X340203Y371653D01*
X339973Y371343D01*
X339897Y370982D01*
X339973Y370620D01*
X340165Y370362D01*
X340472Y370207D01*
X340740Y370155D01*
G01X344300D02*
Y373255D01*
X342882Y371033D01*
X344798D01*
G01X346940Y370155D02*
Y373255D01*
X346480Y372635D01*
G01Y370155D02*
X347400D01*
G01X332696Y361347D02*
X322496D01*
G01D02*
Y365947D01*
G01D02*
X332696D01*
G01D02*
Y361347D01*
G01X327596D02*
Y365947D01*
G01X338625Y364944D02*
X338395Y365099D01*
X338127Y365202D01*
X337820D01*
X337475Y365047D01*
X337207Y364789D01*
X337015Y364479D01*
X336862Y363962D01*
X336824Y363497D01*
X336900Y363032D01*
X337015Y362722D01*
X337245Y362412D01*
X337514Y362205D01*
X337782Y362102D01*
X338050D01*
X338319Y362205D01*
X338549Y362360D01*
X338740Y362567D01*
G01X340882Y362102D02*
Y365202D01*
X340422Y364582D01*
G01Y362102D02*
X341342D01*
G01X343982Y365202D02*
X343675Y365099D01*
X343445Y364840D01*
X343292Y364530D01*
X343177Y364117D01*
X343139Y363652D01*
X343177Y363187D01*
X343292Y362774D01*
X343445Y362464D01*
X343675Y362205D01*
X343982Y362102D01*
X344289Y362205D01*
X344519Y362464D01*
X344672Y362774D01*
X344787Y363187D01*
X344825Y363652D01*
X344787Y364117D01*
X344672Y364530D01*
X344519Y364840D01*
X344289Y365099D01*
X343982Y365202D01*
G01X346430Y362464D02*
X346699Y362205D01*
X347005Y362102D01*
X347312Y362205D01*
X347580Y362515D01*
X347772Y362980D01*
X347849Y363445D01*
Y364014D01*
X347772Y364479D01*
X347580Y364892D01*
X347350Y365099D01*
X347082Y365202D01*
X346775Y365099D01*
X346545Y364892D01*
X346392Y364582D01*
X346315Y364169D01*
X346392Y363807D01*
X346584Y363445D01*
X346814Y363239D01*
X347082Y363187D01*
X347389Y363290D01*
X347619Y363549D01*
X347849Y364014D01*
G01X322496Y371447D02*
X332696D01*
G01Y366847D02*
X322496D01*
G01D02*
Y371447D01*
G01X332696D02*
Y366847D01*
G01X327596D02*
Y371447D01*
G01X338483Y368997D02*
X338253Y369152D01*
X337985Y369255D01*
X337678D01*
X337333Y369100D01*
X337065Y368842D01*
X336873Y368532D01*
X336720Y368015D01*
X336682Y367550D01*
X336758Y367085D01*
X336873Y366775D01*
X337103Y366465D01*
X337372Y366258D01*
X337640Y366155D01*
X337908D01*
X338177Y366258D01*
X338407Y366413D01*
X338598Y366620D01*
G01X340740Y366155D02*
Y369255D01*
X340280Y368635D01*
G01Y366155D02*
X341200D01*
G01X343840Y369255D02*
X343533Y369152D01*
X343303Y368893D01*
X343150Y368583D01*
X343035Y368170D01*
X342997Y367705D01*
X343035Y367240D01*
X343150Y366827D01*
X343303Y366517D01*
X343533Y366258D01*
X343840Y366155D01*
X344147Y366258D01*
X344377Y366517D01*
X344530Y366827D01*
X344645Y367240D01*
X344683Y367705D01*
X344645Y368170D01*
X344530Y368583D01*
X344377Y368893D01*
X344147Y369152D01*
X343840Y369255D01*
G01X346940Y366155D02*
X347208Y366207D01*
X347515Y366362D01*
X347707Y366620D01*
X347783Y366982D01*
X347707Y367343D01*
X347477Y367653D01*
X347132Y367808D01*
X346748D01*
X346518Y367912D01*
X346327Y368170D01*
X346250Y368532D01*
X346365Y368893D01*
X346633Y369152D01*
X346940Y369255D01*
X347247Y369152D01*
X347515Y368893D01*
X347630Y368532D01*
X347553Y368170D01*
X347362Y367912D01*
X347132Y367808D01*
X346748D01*
X346403Y367653D01*
X346173Y367343D01*
X346097Y366982D01*
X346173Y366620D01*
X346365Y366362D01*
X346672Y366207D01*
X346940Y366155D01*
G01X332732Y372342D02*
X322532D01*
G01D02*
Y376942D01*
G01X332732D02*
Y372342D01*
G01X327632D02*
Y376942D01*
G01X324439Y382634D02*
X334639D01*
G01D02*
Y378034D01*
G01D02*
X324439D01*
G01D02*
Y382634D01*
G01X329539D02*
Y378034D01*
G01X322532Y376942D02*
X332732D01*
G01X321655Y382171D02*
Y378971D01*
G01X333207Y391267D02*
X333155Y390960D01*
X332949Y390692D01*
X332639Y390462D01*
X332277Y390309D01*
X331864Y390232D01*
X331450D01*
X331037Y390309D01*
X330675Y390462D01*
X330365Y390692D01*
X330159Y390960D01*
X330107Y391267D01*
X330159Y391574D01*
X330365Y391842D01*
X330675Y392072D01*
X331037Y392225D01*
X331450Y392302D01*
X331864D01*
X332277Y392225D01*
X332639Y392072D01*
X332949Y391842D01*
X333155Y391574D01*
X333207Y391267D01*
G01X332380Y391574D02*
X333207Y392034D01*
G01X332587Y393524D02*
X332949Y393754D01*
X333155Y394060D01*
X333207Y394405D01*
X333155Y394712D01*
X332897Y395019D01*
X332587Y395210D01*
X332277Y395249D01*
X331915Y395172D01*
X331657Y394904D01*
X331554Y394635D01*
Y394290D01*
G01Y394635D02*
X331399Y394865D01*
X331140Y395057D01*
X330830Y395134D01*
X330520Y395057D01*
X330262Y394865D01*
X330107Y394520D01*
X330159Y394175D01*
X330365Y393830D01*
G01X333207Y397467D02*
X330107D01*
X330727Y397007D01*
G01X333207D02*
Y397927D01*
G01X328589Y390241D02*
Y385735D01*
G01D02*
X327884D01*
G01Y397546D02*
X328589D01*
G01D02*
Y393041D01*
G01X333781Y404803D02*
X334314D01*
Y404053D01*
X334154Y403803D01*
X333968Y403636D01*
X333701Y403553D01*
X333434Y403636D01*
X333248Y403803D01*
X333088Y404053D01*
X332981Y404345D01*
X332928Y404678D01*
Y404970D01*
X332981Y405220D01*
X333088Y405511D01*
X333248Y405761D01*
X333408Y405928D01*
X333621Y406053D01*
X333808D01*
X334021Y405970D01*
X334181Y405803D01*
G01X334873Y408173D02*
X334821Y407866D01*
X334615Y407598D01*
X334305Y407368D01*
X333943Y407215D01*
X333530Y407138D01*
X333116D01*
X332703Y407215D01*
X332341Y407368D01*
X332031Y407598D01*
X331825Y407866D01*
X331773Y408173D01*
X331825Y408480D01*
X332031Y408748D01*
X332341Y408978D01*
X332703Y409131D01*
X333116Y409208D01*
X333530D01*
X333943Y409131D01*
X334305Y408978D01*
X334615Y408748D01*
X334821Y408480D01*
X334873Y408173D01*
G01X334046Y408480D02*
X334873Y408940D01*
G01X334253Y410430D02*
X334615Y410660D01*
X334821Y410966D01*
X334873Y411311D01*
X334821Y411618D01*
X334563Y411925D01*
X334253Y412116D01*
X333943Y412155D01*
X333581Y412078D01*
X333323Y411810D01*
X333220Y411541D01*
Y411196D01*
G01Y411541D02*
X333065Y411771D01*
X332806Y411963D01*
X332496Y412040D01*
X332186Y411963D01*
X331928Y411771D01*
X331773Y411426D01*
X331825Y411081D01*
X332031Y410736D01*
G01X332290Y413645D02*
X331980Y413875D01*
X331825Y414143D01*
X331773Y414450D01*
X331876Y414833D01*
X332135Y415101D01*
X332445Y415178D01*
X332755Y415140D01*
X333013Y414986D01*
X333530Y414220D01*
X333891Y413875D01*
X334408Y413645D01*
X334873Y413568D01*
Y415178D01*
G01X331160Y418004D02*
Y405380D01*
G01X333178Y415886D02*
X333365Y415928D01*
X333578Y416053D01*
X333711Y416261D01*
X333765Y416553D01*
X333711Y416844D01*
X333551Y417094D01*
X333311Y417219D01*
X333045D01*
X332885Y417303D01*
X332751Y417511D01*
X332698Y417803D01*
X332778Y418094D01*
X332965Y418303D01*
X333178Y418386D01*
X333391Y418303D01*
X333578Y418094D01*
X333658Y417803D01*
X333605Y417511D01*
X333471Y417303D01*
X333311Y417219D01*
X333045D01*
X332805Y417094D01*
X332645Y416844D01*
X332591Y416553D01*
X332645Y416261D01*
X332778Y416053D01*
X332991Y415928D01*
X333178Y415886D01*
G01X335819Y416652D02*
X373339D01*
G01X328715Y419444D02*
Y422544D01*
X329674D01*
X329980Y422389D01*
X330172Y422182D01*
X330249Y421769D01*
X330172Y421356D01*
X329942Y421097D01*
X329674Y420942D01*
X328715D01*
G01X329674D02*
X330249Y419444D01*
G01X332582D02*
Y422544D01*
X332122Y421924D01*
G01Y419444D02*
X333042D01*
G01X335682D02*
Y422544D01*
X335222Y421924D01*
G01Y419444D02*
X336142D01*
G01X338782Y422544D02*
X338475Y422441D01*
X338245Y422182D01*
X338092Y421872D01*
X337977Y421459D01*
X337939Y420994D01*
X337977Y420529D01*
X338092Y420116D01*
X338245Y419806D01*
X338475Y419547D01*
X338782Y419444D01*
X339089Y419547D01*
X339319Y419806D01*
X339472Y420116D01*
X339587Y420529D01*
X339625Y420994D01*
X339587Y421459D01*
X339472Y421872D01*
X339319Y422182D01*
X339089Y422441D01*
X338782Y422544D01*
G01X341882Y419444D02*
Y422544D01*
X341422Y421924D01*
G01Y419444D02*
X342342D01*
G01X327274Y423243D02*
Y420043D01*
G01X327380Y438269D02*
X327633Y438519D01*
X327823Y438935D01*
X327950Y439519D01*
X327823Y440019D01*
X327570Y440352D01*
X327126Y440602D01*
X325416D01*
Y435602D01*
X327506D01*
X327950Y435935D01*
X328203Y436435D01*
X328330Y437019D01*
X328203Y437602D01*
X327823Y438102D01*
X327380Y438269D01*
X325416D01*
G01X331213Y440602D02*
X332733D01*
G01X331973D02*
Y435602D01*
G01X331213D02*
X332733D01*
G01X337073D02*
X336566Y435685D01*
X336123Y436019D01*
X335743Y436519D01*
X335490Y437102D01*
X335363Y437769D01*
Y438435D01*
X335490Y439102D01*
X335743Y439685D01*
X336123Y440185D01*
X336566Y440519D01*
X337073Y440602D01*
X337580Y440519D01*
X338023Y440185D01*
X338403Y439685D01*
X338656Y439102D01*
X338783Y438435D01*
Y437769D01*
X338656Y437102D01*
X338403Y436519D01*
X338023Y436019D01*
X337580Y435685D01*
X337073Y435602D01*
G01X340843Y436269D02*
X341350Y435852D01*
X341920Y435602D01*
X342426D01*
X342933Y435852D01*
X343313Y436269D01*
X343503Y436852D01*
X343376Y437435D01*
X343060Y437935D01*
X342490Y438269D01*
X341730Y438435D01*
X341286Y438769D01*
X341096Y439352D01*
X341223Y439935D01*
X341540Y440352D01*
X341983Y440602D01*
X342426D01*
X342870Y440435D01*
X343250Y440019D01*
G01X351043Y436269D02*
X351550Y435852D01*
X352120Y435602D01*
X352626D01*
X353133Y435852D01*
X353513Y436269D01*
X353703Y436852D01*
X353576Y437435D01*
X353260Y437935D01*
X352690Y438269D01*
X351930Y438435D01*
X351486Y438769D01*
X351296Y439352D01*
X351423Y439935D01*
X351740Y440352D01*
X352183Y440602D01*
X352626D01*
X353070Y440435D01*
X353450Y440019D01*
G01X357473Y435602D02*
X356966Y435685D01*
X356523Y436019D01*
X356143Y436519D01*
X355890Y437102D01*
X355763Y437769D01*
Y438435D01*
X355890Y439102D01*
X356143Y439685D01*
X356523Y440185D01*
X356966Y440519D01*
X357473Y440602D01*
X357980Y440519D01*
X358423Y440185D01*
X358803Y439685D01*
X359056Y439102D01*
X359183Y438435D01*
Y437769D01*
X359056Y437102D01*
X358803Y436519D01*
X358423Y436019D01*
X357980Y435685D01*
X357473Y435602D01*
G01X363966Y440185D02*
X363586Y440435D01*
X363143Y440602D01*
X362636D01*
X362066Y440352D01*
X361623Y439935D01*
X361306Y439435D01*
X361053Y438602D01*
X360990Y437852D01*
X361116Y437102D01*
X361306Y436602D01*
X361686Y436102D01*
X362130Y435769D01*
X362573Y435602D01*
X363016D01*
X363460Y435769D01*
X363840Y436019D01*
X364156Y436352D01*
G01X366280Y435602D02*
Y440602D01*
G01X368686D02*
X366280Y437519D01*
G01X369066Y435602D02*
X367356Y438935D01*
G01X374040Y435602D02*
X371506D01*
Y440602D01*
X374040D01*
G01X373026Y438185D02*
X371506D01*
G01X377873Y440602D02*
Y435602D01*
G01X376416Y440602D02*
X379330D01*
G01X380806Y442289D02*
Y434210D01*
X324642D01*
Y442289D01*
X380806D01*
G01X338380Y430535D02*
X338150Y430690D01*
X337882Y430793D01*
X337575D01*
X337230Y430638D01*
X336962Y430380D01*
X336770Y430070D01*
X336617Y429553D01*
X336579Y429088D01*
X336655Y428623D01*
X336770Y428313D01*
X337000Y428003D01*
X337269Y427796D01*
X337537Y427693D01*
X337805D01*
X338074Y427796D01*
X338304Y427951D01*
X338495Y428158D01*
G01X341097Y427693D02*
Y430793D01*
X339679Y428571D01*
X341595D01*
G01X343009Y430276D02*
X343239Y430586D01*
X343507Y430741D01*
X343814Y430793D01*
X344197Y430690D01*
X344465Y430431D01*
X344542Y430121D01*
X344504Y429811D01*
X344350Y429553D01*
X343584Y429036D01*
X343239Y428675D01*
X343009Y428158D01*
X342932Y427693D01*
X344542D01*
G01X324174Y431083D02*
Y428083D01*
G01X327274Y431183D02*
Y427983D01*
G01Y427185D02*
Y423985D01*
G01X332902Y425245D02*
X329702D01*
G01X332902Y431445D02*
Y425245D01*
G01X329702D02*
Y431445D01*
G01D02*
X332902D01*
G01X323294Y452199D02*
X325516D01*
X325981Y452352D01*
X326291Y452659D01*
X326394Y453042D01*
X326291Y453425D01*
X325981Y453732D01*
X325516Y453885D01*
X323294D01*
G01X326394Y456142D02*
X323294D01*
X323914Y455682D01*
G01X326394D02*
Y456602D01*
G01Y459242D02*
X323294D01*
X323914Y458782D01*
G01X326394D02*
Y459702D01*
G01X325929Y461499D02*
X326187Y461729D01*
X326342Y461997D01*
X326394Y462342D01*
X326291Y462687D01*
X326084Y462955D01*
X325722Y463147D01*
X325309Y463185D01*
X324896Y463109D01*
X324637Y462917D01*
X324431Y462649D01*
X324379Y462380D01*
X324431Y462112D01*
X324637Y461767D01*
X323294Y461882D01*
Y462917D01*
G01X334040Y449146D02*
Y452246D01*
X333580Y451626D01*
G01Y449146D02*
X334500D01*
G01X336297Y449766D02*
X336527Y449404D01*
X336833Y449198D01*
X337178Y449146D01*
X337485Y449198D01*
X337792Y449456D01*
X337983Y449766D01*
X338022Y450076D01*
X337945Y450438D01*
X337677Y450696D01*
X337408Y450799D01*
X337063D01*
G01X337408D02*
X337638Y450954D01*
X337830Y451213D01*
X337907Y451523D01*
X337830Y451833D01*
X337638Y452091D01*
X337293Y452246D01*
X336948Y452194D01*
X336603Y451988D01*
G01X328600Y458990D02*
Y462090D01*
X328140Y461470D01*
G01Y458990D02*
X329060D01*
G01X330972Y461573D02*
X331202Y461883D01*
X331470Y462038D01*
X331777Y462090D01*
X332160Y461987D01*
X332428Y461728D01*
X332505Y461418D01*
X332467Y461108D01*
X332313Y460850D01*
X331547Y460333D01*
X331202Y459972D01*
X330972Y459455D01*
X330895Y458990D01*
X332505D01*
G01X333415Y462451D02*
X360415D01*
G01X333415Y486951D02*
Y462451D01*
G01X321638Y465389D02*
Y462189D01*
G01X326515Y478904D02*
X323415D01*
G01X321631Y477219D02*
Y474019D01*
G01X330220Y495018D02*
Y498118D01*
X328802Y495896D01*
X330718D01*
G01X332860Y495018D02*
X333128Y495070D01*
X333435Y495225D01*
X333627Y495483D01*
X333703Y495845D01*
X333627Y496206D01*
X333397Y496516D01*
X333052Y496671D01*
X332668D01*
X332438Y496775D01*
X332247Y497033D01*
X332170Y497395D01*
X332285Y497756D01*
X332553Y498015D01*
X332860Y498118D01*
X333167Y498015D01*
X333435Y497756D01*
X333550Y497395D01*
X333473Y497033D01*
X333282Y496775D01*
X333052Y496671D01*
X332668D01*
X332323Y496516D01*
X332093Y496206D01*
X332017Y495845D01*
X332093Y495483D01*
X332285Y495225D01*
X332592Y495070D01*
X332860Y495018D01*
G01X335915Y489451D02*
X333415Y486951D01*
G01X360415Y489451D02*
X335915D01*
G01X325200Y513228D02*
Y512232D01*
G01X326382Y517461D02*
X321982D01*
G01D02*
Y519261D01*
G01X326382Y517461D02*
Y519261D01*
G01X325810Y514861D02*
G02I-1628J0D01*
G01X327680Y514038D02*
Y513042D01*
G01X332382Y517461D02*
X327982D01*
G01D02*
Y519261D01*
G01X332382Y517461D02*
Y519261D01*
G01X331810Y514861D02*
G02I-1628J0D01*
G01X333320Y515076D02*
Y514080D01*
G01X325164Y503818D02*
X322064D01*
Y504584D01*
X322219Y504891D01*
X322426Y505121D01*
X322736Y505313D01*
X323097Y505466D01*
X323614Y505504D01*
X324131Y505466D01*
X324492Y505313D01*
X324802Y505121D01*
X325009Y504891D01*
X325164Y504584D01*
Y503818D01*
G01X324544Y506918D02*
X324906Y507148D01*
X325112Y507454D01*
X325164Y507799D01*
X325112Y508106D01*
X324854Y508413D01*
X324544Y508604D01*
X324234Y508643D01*
X323872Y508566D01*
X323614Y508298D01*
X323511Y508029D01*
Y507684D01*
G01Y508029D02*
X323356Y508259D01*
X323097Y508451D01*
X322787Y508528D01*
X322477Y508451D01*
X322219Y508259D01*
X322064Y507914D01*
X322116Y507569D01*
X322322Y507224D01*
G01X325164Y511321D02*
X322064D01*
X324286Y509903D01*
Y511819D01*
G01X338382Y517461D02*
X333982D01*
G01D02*
Y519261D01*
G01X337810Y514861D02*
G02I-1628J0D01*
G01X335412Y510969D02*
X338612D01*
G01X335412Y504769D02*
Y510969D01*
G01X338612Y504769D02*
X335412D01*
G01X330912Y510969D02*
X334112D01*
G01X330912Y504769D02*
Y510969D01*
G01X334112Y504769D02*
X330912D01*
G01X334112Y510969D02*
Y504769D01*
G01X326139Y511181D02*
X329339D01*
G01X326139Y504981D02*
Y511181D01*
G01X329339Y504981D02*
X326139D01*
G01X329339Y511181D02*
Y504981D01*
G01X324270Y530031D02*
Y535031D01*
X323510Y534031D01*
G01Y530031D02*
X325030D01*
G01X330557Y534605D02*
X330937Y535105D01*
X331380Y535355D01*
X331887Y535438D01*
X332520Y535271D01*
X332963Y534855D01*
X333090Y534355D01*
X333027Y533855D01*
X332773Y533438D01*
X331507Y532605D01*
X330937Y532021D01*
X330557Y531188D01*
X330430Y530438D01*
X333090D01*
G01X334887Y531327D02*
X335267Y530744D01*
X335773Y530410D01*
X336343Y530327D01*
X336850Y530410D01*
X337357Y530827D01*
X337673Y531327D01*
X337737Y531827D01*
X337610Y532410D01*
X337167Y532827D01*
X336723Y532994D01*
X336153D01*
G01X336723D02*
X337103Y533244D01*
X337420Y533660D01*
X337547Y534160D01*
X337420Y534660D01*
X337103Y535077D01*
X336533Y535327D01*
X335963Y535244D01*
X335393Y534910D01*
G01X321982Y529661D02*
X326382D01*
G01X321982Y519261D02*
Y529661D01*
G01X326382Y519261D02*
X321982D01*
G01X326382Y529661D02*
Y519261D01*
G01Y518661D02*
X321982D01*
G01Y518061D02*
X326382D01*
G01X327982Y529661D02*
X332382D01*
G01X327982Y519261D02*
Y529661D01*
G01X332382Y519261D02*
X327982D01*
G01X332382Y529661D02*
Y519261D01*
G01Y518661D02*
X327982D01*
G01Y518061D02*
X332382D01*
G01X333982Y529661D02*
X338382D01*
G01X333982Y519261D02*
Y529661D01*
G01X338382Y519261D02*
X333982D01*
G01X338382Y518661D02*
X333982D01*
G01Y518061D02*
X338382D01*
G01X342652Y548446D02*
X356288D01*
Y564379D01*
X342504D01*
Y543999D01*
X329016D01*
Y539701D01*
X323014D01*
Y536033D01*
G01X328943Y534995D02*
X326609D01*
G01X324537Y549804D02*
Y543004D01*
G01X338288Y536303D02*
X335088D01*
G01D02*
Y542503D01*
G01D02*
X338288D01*
G01X330488Y536403D02*
Y542603D01*
G01X333688Y536403D02*
X330488D01*
G01X333688Y542603D02*
Y536403D01*
G01X330488Y542603D02*
X333688D01*
G01X329187Y545361D02*
Y547861D01*
X328867Y547361D01*
G01Y545361D02*
X329507D01*
G01X335582Y547240D02*
X335742Y547032D01*
X335929Y546907D01*
X336169Y546865D01*
X336409Y546948D01*
X336596Y547115D01*
X336729Y547407D01*
X336756Y547740D01*
X336702Y548073D01*
X336569Y548282D01*
X336382Y548448D01*
X336196Y548490D01*
X336009Y548448D01*
X335769Y548282D01*
X335849Y549365D01*
X336569D01*
G01X321632Y558088D02*
Y554888D01*
G01Y553788D02*
Y550588D01*
G01X324417Y564856D02*
Y567356D01*
X324097Y566856D01*
G01Y564856D02*
X324737D01*
G01X326617Y567356D02*
X326404Y567273D01*
X326244Y567064D01*
X326137Y566814D01*
X326057Y566481D01*
X326030Y566106D01*
X326057Y565731D01*
X326137Y565398D01*
X326244Y565148D01*
X326404Y564939D01*
X326617Y564856D01*
X326830Y564939D01*
X326990Y565148D01*
X327097Y565398D01*
X327177Y565731D01*
X327204Y566106D01*
X327177Y566481D01*
X327097Y566814D01*
X326990Y567064D01*
X326830Y567273D01*
X326617Y567356D01*
G01X335734Y564375D02*
X335921Y564666D01*
X336081Y564833D01*
X336294Y564916D01*
X336481Y564833D01*
X336614Y564666D01*
X336721Y564416D01*
X336748Y564125D01*
X336721Y563875D01*
X336614Y563625D01*
X336454Y563416D01*
X336268Y563333D01*
X336054Y563416D01*
X335868Y563666D01*
X335761Y564041D01*
X335734Y564458D01*
X335788Y565000D01*
X335868Y565291D01*
X336001Y565583D01*
X336188Y565791D01*
X336374Y565833D01*
X336561Y565750D01*
X336694Y565541D01*
G01X324421Y562310D02*
Y550302D01*
G01Y552906D02*
Y550302D01*
G01D02*
X325225D01*
G01X324421Y562310D02*
Y560006D01*
G01X325225Y562310D02*
X324421D01*
G01X336429D02*
Y550302D01*
G01D02*
Y552806D01*
G01X335625Y550302D02*
X336429D01*
G01Y562310D02*
X335625D01*
G01X336429Y560206D02*
Y562310D01*
G01X325588Y568503D02*
Y575103D01*
G01X333088Y575203D02*
Y568403D01*
G01X334767Y571102D02*
X337767D01*
G01X334667Y568002D02*
Y574202D01*
G01X337867Y568002D02*
X334667D01*
G01Y574202D02*
X337867D01*
G01X329183Y597512D02*
Y600612D01*
X330103D01*
X330410Y600457D01*
X330640Y600095D01*
X330717Y599682D01*
X330640Y599269D01*
X330448Y598959D01*
X330103Y598804D01*
X329183D01*
G01X333893Y600354D02*
X333663Y600509D01*
X333395Y600612D01*
X333088D01*
X332743Y600457D01*
X332475Y600199D01*
X332283Y599889D01*
X332130Y599372D01*
X332092Y598907D01*
X332168Y598442D01*
X332283Y598132D01*
X332513Y597822D01*
X332782Y597615D01*
X333050Y597512D01*
X333318D01*
X333587Y597615D01*
X333817Y597770D01*
X334008Y597977D01*
G01X336150Y597512D02*
Y600612D01*
X335690Y599992D01*
G01Y597512D02*
X336610D01*
G01X339250Y600612D02*
X338943Y600509D01*
X338713Y600250D01*
X338560Y599940D01*
X338445Y599527D01*
X338407Y599062D01*
X338445Y598597D01*
X338560Y598184D01*
X338713Y597874D01*
X338943Y597615D01*
X339250Y597512D01*
X339557Y597615D01*
X339787Y597874D01*
X339940Y598184D01*
X340055Y598597D01*
X340093Y599062D01*
X340055Y599527D01*
X339940Y599940D01*
X339787Y600250D01*
X339557Y600509D01*
X339250Y600612D01*
G01X329183Y593192D02*
Y596292D01*
X330103D01*
X330410Y596137D01*
X330640Y595775D01*
X330717Y595362D01*
X330640Y594949D01*
X330448Y594639D01*
X330103Y594484D01*
X329183D01*
G01X332283Y593192D02*
Y596292D01*
X333242D01*
X333548Y596137D01*
X333740Y595930D01*
X333817Y595517D01*
X333740Y595104D01*
X333510Y594845D01*
X333242Y594690D01*
X332283D01*
G01X333242D02*
X333817Y593192D01*
G01X335307Y593812D02*
X335537Y593450D01*
X335843Y593244D01*
X336188Y593192D01*
X336495Y593244D01*
X336802Y593502D01*
X336993Y593812D01*
X337032Y594122D01*
X336955Y594484D01*
X336687Y594742D01*
X336418Y594845D01*
X336073D01*
G01X336418D02*
X336648Y595000D01*
X336840Y595259D01*
X336917Y595569D01*
X336840Y595879D01*
X336648Y596137D01*
X336303Y596292D01*
X335958Y596240D01*
X335613Y596034D01*
G01X327624Y598798D02*
Y595598D01*
G01X325973Y613106D02*
Y616206D01*
X326893D01*
X327200Y616051D01*
X327430Y615689D01*
X327507Y615276D01*
X327430Y614863D01*
X327238Y614553D01*
X326893Y614398D01*
X325973D01*
G01X330683Y615948D02*
X330453Y616103D01*
X330185Y616206D01*
X329878D01*
X329533Y616051D01*
X329265Y615793D01*
X329073Y615483D01*
X328920Y614966D01*
X328882Y614501D01*
X328958Y614036D01*
X329073Y613726D01*
X329303Y613416D01*
X329572Y613209D01*
X329840Y613106D01*
X330108D01*
X330377Y613209D01*
X330607Y613364D01*
X330798Y613571D01*
G01X332288Y613468D02*
X332557Y613209D01*
X332863Y613106D01*
X333170Y613209D01*
X333438Y613519D01*
X333630Y613984D01*
X333707Y614449D01*
Y615018D01*
X333630Y615483D01*
X333438Y615896D01*
X333208Y616103D01*
X332940Y616206D01*
X332633Y616103D01*
X332403Y615896D01*
X332250Y615586D01*
X332173Y615173D01*
X332250Y614811D01*
X332442Y614449D01*
X332672Y614243D01*
X332940Y614191D01*
X333247Y614294D01*
X333477Y614553D01*
X333707Y615018D01*
G01X324636Y618688D02*
Y612488D01*
G01X330061Y607141D02*
Y610241D01*
X330981D01*
X331288Y610086D01*
X331518Y609724D01*
X331595Y609311D01*
X331518Y608898D01*
X331326Y608588D01*
X330981Y608433D01*
X330061D01*
G01X334771Y609983D02*
X334541Y610138D01*
X334273Y610241D01*
X333966D01*
X333621Y610086D01*
X333353Y609828D01*
X333161Y609518D01*
X333008Y609001D01*
X332970Y608536D01*
X333046Y608071D01*
X333161Y607761D01*
X333391Y607451D01*
X333660Y607244D01*
X333928Y607141D01*
X334196D01*
X334465Y607244D01*
X334695Y607399D01*
X334886Y607606D01*
G01X337028Y607141D02*
X337296Y607193D01*
X337603Y607348D01*
X337795Y607606D01*
X337871Y607968D01*
X337795Y608329D01*
X337565Y608639D01*
X337220Y608794D01*
X336836D01*
X336606Y608898D01*
X336415Y609156D01*
X336338Y609518D01*
X336453Y609879D01*
X336721Y610138D01*
X337028Y610241D01*
X337335Y610138D01*
X337603Y609879D01*
X337718Y609518D01*
X337641Y609156D01*
X337450Y608898D01*
X337220Y608794D01*
X336836D01*
X336491Y608639D01*
X336261Y608329D01*
X336185Y607968D01*
X336261Y607606D01*
X336453Y607348D01*
X336760Y607193D01*
X337028Y607141D01*
G01X325148Y610980D02*
Y607980D01*
G01X328248Y611080D02*
Y607880D01*
G01X322048Y611080D02*
X328248D01*
G01X322048Y607880D02*
Y611080D01*
G01X328248Y607880D02*
X322048D01*
G01X327624Y602721D02*
Y599521D01*
G01X324524Y599621D02*
Y602621D01*
G01X329953Y602727D02*
Y605827D01*
X330873D01*
X331180Y605672D01*
X331410Y605310D01*
X331487Y604897D01*
X331410Y604484D01*
X331218Y604174D01*
X330873Y604019D01*
X329953D01*
G01X333053Y602727D02*
Y605827D01*
X334012D01*
X334318Y605672D01*
X334510Y605465D01*
X334587Y605052D01*
X334510Y604639D01*
X334280Y604380D01*
X334012Y604225D01*
X333053D01*
G01X334012D02*
X334587Y602727D01*
G01X337380D02*
Y605827D01*
X335962Y603605D01*
X337878D01*
G01X328153Y606964D02*
Y603764D01*
G01X321953Y606964D02*
X328153D01*
G01X321953Y603764D02*
Y606964D01*
G01X328153Y603764D02*
X321953D01*
G01X337374Y619663D02*
X334274D01*
Y620583D01*
X334429Y620890D01*
X334791Y621120D01*
X335204Y621197D01*
X335617Y621120D01*
X335927Y620928D01*
X336082Y620583D01*
Y619663D01*
G01X337374Y622763D02*
X334274D01*
Y623722D01*
X334429Y624028D01*
X334636Y624220D01*
X335049Y624297D01*
X335462Y624220D01*
X335721Y623990D01*
X335876Y623722D01*
Y622763D01*
G01Y623722D02*
X337374Y624297D01*
G01Y626630D02*
X334274D01*
X334894Y626170D01*
G01X337374D02*
Y627090D01*
G01X333554Y619603D02*
X330454D01*
Y620523D01*
X330609Y620830D01*
X330971Y621060D01*
X331384Y621137D01*
X331797Y621060D01*
X332107Y620868D01*
X332262Y620523D01*
Y619603D01*
G01X333554Y622703D02*
X330454D01*
Y623662D01*
X330609Y623968D01*
X330816Y624160D01*
X331229Y624237D01*
X331642Y624160D01*
X331901Y623930D01*
X332056Y623662D01*
Y622703D01*
G01Y623662D02*
X333554Y624237D01*
G01X330971Y625842D02*
X330661Y626072D01*
X330506Y626340D01*
X330454Y626647D01*
X330557Y627030D01*
X330816Y627298D01*
X331126Y627375D01*
X331436Y627337D01*
X331694Y627183D01*
X332211Y626417D01*
X332572Y626072D01*
X333089Y625842D01*
X333554Y625765D01*
Y627375D01*
G01X329414Y628113D02*
X326314D01*
Y629072D01*
X326469Y629378D01*
X326676Y629570D01*
X327089Y629647D01*
X327502Y629570D01*
X327761Y629340D01*
X327916Y629072D01*
Y628113D01*
G01Y629072D02*
X329414Y629647D01*
G01X329052Y631328D02*
X329311Y631597D01*
X329414Y631903D01*
X329311Y632210D01*
X329001Y632478D01*
X328536Y632670D01*
X328071Y632747D01*
X327502D01*
X327037Y632670D01*
X326624Y632478D01*
X326417Y632248D01*
X326314Y631980D01*
X326417Y631673D01*
X326624Y631443D01*
X326934Y631290D01*
X327347Y631213D01*
X327709Y631290D01*
X328071Y631482D01*
X328277Y631712D01*
X328329Y631980D01*
X328226Y632287D01*
X327967Y632517D01*
X327502Y632747D01*
G01X328794Y634237D02*
X329156Y634467D01*
X329362Y634773D01*
X329414Y635118D01*
X329362Y635425D01*
X329104Y635732D01*
X328794Y635923D01*
X328484Y635962D01*
X328122Y635885D01*
X327864Y635617D01*
X327761Y635348D01*
Y635003D01*
G01Y635348D02*
X327606Y635578D01*
X327347Y635770D01*
X327037Y635847D01*
X326727Y635770D01*
X326469Y635578D01*
X326314Y635233D01*
X326366Y634888D01*
X326572Y634543D01*
G01X328949Y637337D02*
X329207Y637567D01*
X329362Y637835D01*
X329414Y638180D01*
X329311Y638525D01*
X329104Y638793D01*
X328742Y638985D01*
X328329Y639023D01*
X327916Y638947D01*
X327657Y638755D01*
X327451Y638487D01*
X327399Y638218D01*
X327451Y637950D01*
X327657Y637605D01*
X326314Y637720D01*
Y638755D01*
G01X327840Y619679D02*
X324740D01*
Y620599D01*
X324895Y620906D01*
X325257Y621136D01*
X325670Y621213D01*
X326083Y621136D01*
X326393Y620944D01*
X326548Y620599D01*
Y619679D01*
G01X327220Y622779D02*
X327530Y622971D01*
X327737Y623201D01*
X327840Y623469D01*
X327737Y623776D01*
X327530Y624006D01*
X327220Y624236D01*
X326807Y624313D01*
X324740D01*
G01X327840Y626646D02*
X324740D01*
X325360Y626186D01*
G01X327840D02*
Y627106D01*
G01X332420Y637562D02*
Y635340D01*
X332573Y634875D01*
X332880Y634565D01*
X333263Y634462D01*
X333646Y634565D01*
X333953Y634875D01*
X334106Y635340D01*
Y637562D01*
G01X336363Y634462D02*
Y637562D01*
X335903Y636942D01*
G01Y634462D02*
X336823D01*
G01X338735Y637045D02*
X338965Y637355D01*
X339233Y637510D01*
X339540Y637562D01*
X339923Y637459D01*
X340191Y637200D01*
X340268Y636890D01*
X340230Y636580D01*
X340076Y636322D01*
X339310Y635805D01*
X338965Y635444D01*
X338735Y634927D01*
X338658Y634462D01*
X340268D01*
G01X342563D02*
X342831Y634514D01*
X343138Y634669D01*
X343330Y634927D01*
X343406Y635289D01*
X343330Y635650D01*
X343100Y635960D01*
X342755Y636115D01*
X342371D01*
X342141Y636219D01*
X341950Y636477D01*
X341873Y636839D01*
X341988Y637200D01*
X342256Y637459D01*
X342563Y637562D01*
X342870Y637459D01*
X343138Y637200D01*
X343253Y636839D01*
X343176Y636477D01*
X342985Y636219D01*
X342755Y636115D01*
X342371D01*
X342026Y635960D01*
X341796Y635650D01*
X341720Y635289D01*
X341796Y634927D01*
X341988Y634669D01*
X342295Y634514D01*
X342563Y634462D01*
G01X325183Y634914D02*
X321983D01*
G01X325183Y641114D02*
Y634914D01*
G01X321983Y641114D02*
X325183D01*
G01X321983Y634914D02*
Y641114D01*
G01X337417Y714814D02*
Y717314D01*
X337097Y716814D01*
G01Y714814D02*
X337737D01*
G01X330740Y711956D02*
Y716956D01*
G01X326112Y715943D02*
X325957Y715713D01*
X325854Y715445D01*
Y715138D01*
X326009Y714793D01*
X326267Y714525D01*
X326577Y714333D01*
X327094Y714180D01*
X327559Y714142D01*
X328024Y714218D01*
X328334Y714333D01*
X328644Y714563D01*
X328851Y714832D01*
X328954Y715100D01*
Y715368D01*
X328851Y715637D01*
X328696Y715867D01*
X328489Y716058D01*
G01Y717357D02*
X328747Y717587D01*
X328902Y717855D01*
X328954Y718200D01*
X328851Y718545D01*
X328644Y718813D01*
X328282Y719005D01*
X327869Y719043D01*
X327456Y718967D01*
X327197Y718775D01*
X326991Y718507D01*
X326939Y718238D01*
X326991Y717970D01*
X327197Y717625D01*
X325854Y717740D01*
Y718775D01*
G01X328954Y721300D02*
X328902Y721568D01*
X328747Y721875D01*
X328489Y722067D01*
X328127Y722143D01*
X327766Y722067D01*
X327456Y721837D01*
X327301Y721492D01*
Y721108D01*
X327197Y720878D01*
X326939Y720687D01*
X326577Y720610D01*
X326216Y720725D01*
X325957Y720993D01*
X325854Y721300D01*
X325957Y721607D01*
X326216Y721875D01*
X326577Y721990D01*
X326939Y721913D01*
X327197Y721722D01*
X327301Y721492D01*
Y721108D01*
X327456Y720763D01*
X327766Y720533D01*
X328127Y720457D01*
X328489Y720533D01*
X328747Y720725D01*
X328902Y721032D01*
X328954Y721300D01*
G01X327662Y723672D02*
X327301Y723940D01*
X327094Y724170D01*
X326991Y724477D01*
X327094Y724745D01*
X327301Y724937D01*
X327611Y725090D01*
X327972Y725128D01*
X328282Y725090D01*
X328592Y724937D01*
X328851Y724707D01*
X328954Y724438D01*
X328851Y724132D01*
X328541Y723863D01*
X328076Y723710D01*
X327559Y723672D01*
X326887Y723748D01*
X326526Y723863D01*
X326164Y724055D01*
X325906Y724323D01*
X325854Y724592D01*
X325957Y724860D01*
X326216Y725052D01*
G01X324540Y721256D02*
Y715056D01*
G01X340040Y737556D02*
X336840D01*
G01D02*
Y743756D01*
G01X326540Y737556D02*
X323340D01*
G01D02*
Y743756D01*
G01X326540D02*
Y737556D01*
G01X335540D02*
X332340D01*
G01X335540Y743756D02*
Y737556D01*
G01X332340D02*
Y743756D01*
G01X331040Y737556D02*
X327840D01*
G01D02*
Y743756D01*
G01X331040D02*
Y737556D01*
G01X322040Y743756D02*
Y737556D01*
G01X336840Y732256D02*
X340040D01*
G01X336840Y726056D02*
Y732256D01*
G01X340040Y726056D02*
X336840D01*
G01X323340Y732256D02*
X326540D01*
G01X323340Y726056D02*
Y732256D01*
G01X326540Y726056D02*
X323340D01*
G01X326540Y732256D02*
Y726056D01*
G01X332340Y732256D02*
X335540D01*
G01X332340Y726056D02*
Y732256D01*
G01X335540Y726056D02*
X332340D01*
G01X335540Y732256D02*
Y726056D01*
G01X327840Y732256D02*
X331040D01*
G01X327840Y726056D02*
Y732256D01*
G01X331040Y726056D02*
X327840D01*
G01X331040Y732256D02*
Y726056D01*
G01X322040Y732256D02*
Y726056D01*
G01X333156Y747677D02*
X333001Y747447D01*
X332898Y747179D01*
Y746872D01*
X333053Y746527D01*
X333311Y746259D01*
X333621Y746067D01*
X334138Y745914D01*
X334603Y745876D01*
X335068Y745952D01*
X335378Y746067D01*
X335688Y746297D01*
X335895Y746566D01*
X335998Y746834D01*
Y747102D01*
X335895Y747371D01*
X335740Y747601D01*
X335533Y747792D01*
G01X335998Y749857D02*
X335326Y749934D01*
X334758Y750049D01*
X334241Y750202D01*
X333673Y750394D01*
X332898Y750701D01*
Y749167D01*
G01X335998Y753034D02*
X332898D01*
X333518Y752574D01*
G01X335998D02*
Y753494D01*
G01Y756594D02*
X332898D01*
X335120Y755176D01*
Y757092D01*
G01X339940Y740656D02*
X336940D01*
G01X336840Y743756D02*
X340040D01*
G01X326440Y740656D02*
X323440D01*
G01X323340Y743756D02*
X326540D01*
G01X335440Y740656D02*
X332440D01*
G01X332340Y743756D02*
X335540D01*
G01X330940Y740656D02*
X327940D01*
G01X327840Y743756D02*
X331040D01*
G01X331637Y746067D02*
X328537D01*
Y747026D01*
X328692Y747332D01*
X328899Y747524D01*
X329312Y747601D01*
X329725Y747524D01*
X329984Y747294D01*
X330139Y747026D01*
Y746067D01*
G01Y747026D02*
X331637Y747601D01*
G01X331275Y749282D02*
X331534Y749551D01*
X331637Y749857D01*
X331534Y750164D01*
X331224Y750432D01*
X330759Y750624D01*
X330294Y750701D01*
X329725D01*
X329260Y750624D01*
X328847Y750432D01*
X328640Y750202D01*
X328537Y749934D01*
X328640Y749627D01*
X328847Y749397D01*
X329157Y749244D01*
X329570Y749167D01*
X329932Y749244D01*
X330294Y749436D01*
X330500Y749666D01*
X330552Y749934D01*
X330449Y750241D01*
X330190Y750471D01*
X329725Y750701D01*
G01X331172Y752191D02*
X331430Y752421D01*
X331585Y752689D01*
X331637Y753034D01*
X331534Y753379D01*
X331327Y753647D01*
X330965Y753839D01*
X330552Y753877D01*
X330139Y753801D01*
X329880Y753609D01*
X329674Y753341D01*
X329622Y753072D01*
X329674Y752804D01*
X329880Y752459D01*
X328537Y752574D01*
Y753609D01*
G01X331637Y756594D02*
X328537D01*
X330759Y755176D01*
Y757092D01*
G01X327677Y746067D02*
X324577D01*
Y747026D01*
X324732Y747332D01*
X324939Y747524D01*
X325352Y747601D01*
X325765Y747524D01*
X326024Y747294D01*
X326179Y747026D01*
Y746067D01*
G01Y747026D02*
X327677Y747601D01*
G01Y749934D02*
X327625Y750202D01*
X327470Y750509D01*
X327212Y750701D01*
X326850Y750777D01*
X326489Y750701D01*
X326179Y750471D01*
X326024Y750126D01*
Y749742D01*
X325920Y749512D01*
X325662Y749321D01*
X325300Y749244D01*
X324939Y749359D01*
X324680Y749627D01*
X324577Y749934D01*
X324680Y750241D01*
X324939Y750509D01*
X325300Y750624D01*
X325662Y750547D01*
X325920Y750356D01*
X326024Y750126D01*
Y749742D01*
X326179Y749397D01*
X326489Y749167D01*
X326850Y749091D01*
X327212Y749167D01*
X327470Y749359D01*
X327625Y749666D01*
X327677Y749934D01*
G01X325094Y752306D02*
X324784Y752536D01*
X324629Y752804D01*
X324577Y753111D01*
X324680Y753494D01*
X324939Y753762D01*
X325249Y753839D01*
X325559Y753801D01*
X325817Y753647D01*
X326334Y752881D01*
X326695Y752536D01*
X327212Y752306D01*
X327677Y752229D01*
Y753839D01*
G01Y756594D02*
X324577D01*
X326799Y755176D01*
Y757092D01*
G01X329781Y760558D02*
X329626Y760328D01*
X329523Y760060D01*
Y759753D01*
X329678Y759408D01*
X329936Y759140D01*
X330246Y758948D01*
X330763Y758795D01*
X331228Y758757D01*
X331693Y758833D01*
X332003Y758948D01*
X332313Y759178D01*
X332520Y759447D01*
X332623Y759715D01*
Y759983D01*
X332520Y760252D01*
X332365Y760482D01*
X332158Y760673D01*
G01X332623Y762738D02*
X331951Y762815D01*
X331383Y762930D01*
X330866Y763083D01*
X330298Y763275D01*
X329523Y763582D01*
Y762048D01*
G01X332623Y765915D02*
X329523D01*
X330143Y765455D01*
G01X332623D02*
Y766375D01*
G01Y768938D02*
X331951Y769015D01*
X331383Y769130D01*
X330866Y769283D01*
X330298Y769475D01*
X329523Y769782D01*
Y768248D01*
G01X324981Y760558D02*
X324826Y760328D01*
X324723Y760060D01*
Y759753D01*
X324878Y759408D01*
X325136Y759140D01*
X325446Y758948D01*
X325963Y758795D01*
X326428Y758757D01*
X326893Y758833D01*
X327203Y758948D01*
X327513Y759178D01*
X327720Y759447D01*
X327823Y759715D01*
Y759983D01*
X327720Y760252D01*
X327565Y760482D01*
X327358Y760673D01*
G01Y761972D02*
X327616Y762202D01*
X327771Y762470D01*
X327823Y762815D01*
X327720Y763160D01*
X327513Y763428D01*
X327151Y763620D01*
X326738Y763658D01*
X326325Y763582D01*
X326066Y763390D01*
X325860Y763122D01*
X325808Y762853D01*
X325860Y762585D01*
X326066Y762240D01*
X324723Y762355D01*
Y763390D01*
G01X327461Y765263D02*
X327720Y765532D01*
X327823Y765838D01*
X327720Y766145D01*
X327410Y766413D01*
X326945Y766605D01*
X326480Y766682D01*
X325911D01*
X325446Y766605D01*
X325033Y766413D01*
X324826Y766183D01*
X324723Y765915D01*
X324826Y765608D01*
X325033Y765378D01*
X325343Y765225D01*
X325756Y765148D01*
X326118Y765225D01*
X326480Y765417D01*
X326686Y765647D01*
X326738Y765915D01*
X326635Y766222D01*
X326376Y766452D01*
X325911Y766682D01*
G01X327203Y768172D02*
X327565Y768402D01*
X327771Y768708D01*
X327823Y769053D01*
X327771Y769360D01*
X327513Y769667D01*
X327203Y769858D01*
X326893Y769897D01*
X326531Y769820D01*
X326273Y769552D01*
X326170Y769283D01*
Y768938D01*
G01Y769283D02*
X326015Y769513D01*
X325756Y769705D01*
X325446Y769782D01*
X325136Y769705D01*
X324878Y769513D01*
X324723Y769168D01*
X324775Y768823D01*
X324981Y768478D01*
G01X336715Y758948D02*
X333615D01*
Y759907D01*
X333770Y760213D01*
X333977Y760405D01*
X334390Y760482D01*
X334803Y760405D01*
X335062Y760175D01*
X335217Y759907D01*
Y758948D01*
G01Y759907D02*
X336715Y760482D01*
G01X336353Y762163D02*
X336612Y762432D01*
X336715Y762738D01*
X336612Y763045D01*
X336302Y763313D01*
X335837Y763505D01*
X335372Y763582D01*
X334803D01*
X334338Y763505D01*
X333925Y763313D01*
X333718Y763083D01*
X333615Y762815D01*
X333718Y762508D01*
X333925Y762278D01*
X334235Y762125D01*
X334648Y762048D01*
X335010Y762125D01*
X335372Y762317D01*
X335578Y762547D01*
X335630Y762815D01*
X335527Y763122D01*
X335268Y763352D01*
X334803Y763582D01*
G01X336250Y765072D02*
X336508Y765302D01*
X336663Y765570D01*
X336715Y765915D01*
X336612Y766260D01*
X336405Y766528D01*
X336043Y766720D01*
X335630Y766758D01*
X335217Y766682D01*
X334958Y766490D01*
X334752Y766222D01*
X334700Y765953D01*
X334752Y765685D01*
X334958Y765340D01*
X333615Y765455D01*
Y766490D01*
G01X336715Y769015D02*
X333615D01*
X334235Y768555D01*
G01X336715D02*
Y769475D01*
G01X325964Y785343D02*
X326071Y785468D01*
X326151Y785677D01*
X326204Y785968D01*
X326151Y786218D01*
X326044Y786385D01*
X325858Y786510D01*
X325138D01*
Y784010D01*
X326018D01*
X326204Y784177D01*
X326311Y784427D01*
X326364Y784718D01*
X326311Y785010D01*
X326151Y785260D01*
X325964Y785343D01*
X325138D01*
G01X327951Y784010D02*
Y786510D01*
X327631Y786010D01*
G01Y784010D02*
X328271D01*
G01X329644Y786093D02*
X329804Y786343D01*
X329991Y786468D01*
X330204Y786510D01*
X330471Y786427D01*
X330658Y786218D01*
X330711Y785968D01*
X330684Y785718D01*
X330578Y785510D01*
X330044Y785093D01*
X329804Y784802D01*
X329644Y784385D01*
X329591Y784010D01*
X330711D01*
G01X337775Y785343D02*
X337882Y785468D01*
X337962Y785677D01*
X338015Y785968D01*
X337962Y786218D01*
X337855Y786385D01*
X337669Y786510D01*
X336949D01*
Y784010D01*
X337829D01*
X338015Y784177D01*
X338122Y784427D01*
X338175Y784718D01*
X338122Y785010D01*
X337962Y785260D01*
X337775Y785343D01*
X336949D01*
G01X339762Y784010D02*
Y786510D01*
X339442Y786010D01*
G01Y784010D02*
X340082D01*
G01X341962D02*
Y786510D01*
X341642Y786010D01*
G01Y784010D02*
X342282D01*
G01X328878Y792439D02*
G03X336594I3858J0D01*
G01X328878D02*
Y819152D01*
G01X336594Y792439D02*
Y819152D01*
G01X328878D02*
X326378Y821652D01*
G01X336594Y819152D02*
X339094Y821652D01*
G01X340819Y10721D02*
Y13821D01*
X341739D01*
X342046Y13666D01*
X342276Y13304D01*
X342353Y12891D01*
X342276Y12478D01*
X342084Y12168D01*
X341739Y12013D01*
X340819D01*
G01X345529Y13563D02*
X345299Y13718D01*
X345031Y13821D01*
X344724D01*
X344379Y13666D01*
X344111Y13408D01*
X343919Y13098D01*
X343766Y12581D01*
X343728Y12116D01*
X343804Y11651D01*
X343919Y11341D01*
X344149Y11031D01*
X344418Y10824D01*
X344686Y10721D01*
X344954D01*
X345223Y10824D01*
X345453Y10979D01*
X345644Y11186D01*
G01X348246Y10721D02*
Y13821D01*
X346828Y11599D01*
X348744D01*
G01X350886Y10721D02*
X351154Y10773D01*
X351461Y10928D01*
X351653Y11186D01*
X351729Y11548D01*
X351653Y11909D01*
X351423Y12219D01*
X351078Y12374D01*
X350694D01*
X350464Y12478D01*
X350273Y12736D01*
X350196Y13098D01*
X350311Y13459D01*
X350579Y13718D01*
X350886Y13821D01*
X351193Y13718D01*
X351461Y13459D01*
X351576Y13098D01*
X351499Y12736D01*
X351308Y12478D01*
X351078Y12374D01*
X350694D01*
X350349Y12219D01*
X350119Y11909D01*
X350043Y11548D01*
X350119Y11186D01*
X350311Y10928D01*
X350618Y10773D01*
X350886Y10721D01*
G01X339309Y1656D02*
Y4756D01*
X340229D01*
X340536Y4601D01*
X340766Y4239D01*
X340843Y3826D01*
X340766Y3413D01*
X340574Y3103D01*
X340229Y2948D01*
X339309D01*
G01X344019Y4498D02*
X343789Y4653D01*
X343521Y4756D01*
X343214D01*
X342869Y4601D01*
X342601Y4343D01*
X342409Y4033D01*
X342256Y3516D01*
X342218Y3051D01*
X342294Y2586D01*
X342409Y2276D01*
X342639Y1966D01*
X342908Y1759D01*
X343176Y1656D01*
X343444D01*
X343713Y1759D01*
X343943Y1914D01*
X344134Y2121D01*
G01X346276Y1656D02*
Y4756D01*
X345816Y4136D01*
G01Y1656D02*
X346736D01*
G01X348533Y2276D02*
X348763Y1914D01*
X349069Y1708D01*
X349414Y1656D01*
X349721Y1708D01*
X350028Y1966D01*
X350219Y2276D01*
X350258Y2586D01*
X350181Y2948D01*
X349913Y3206D01*
X349644Y3309D01*
X349299D01*
G01X349644D02*
X349874Y3464D01*
X350066Y3723D01*
X350143Y4033D01*
X350066Y4343D01*
X349874Y4601D01*
X349529Y4756D01*
X349184Y4704D01*
X348839Y4498D01*
G01X352476Y1656D02*
Y4756D01*
X352016Y4136D01*
G01Y1656D02*
X352936D01*
G01X338883Y13930D02*
Y7130D01*
G01X340819Y14724D02*
Y17824D01*
X341739D01*
X342046Y17669D01*
X342276Y17307D01*
X342353Y16894D01*
X342276Y16481D01*
X342084Y16171D01*
X341739Y16016D01*
X340819D01*
G01X345529Y17566D02*
X345299Y17721D01*
X345031Y17824D01*
X344724D01*
X344379Y17669D01*
X344111Y17411D01*
X343919Y17101D01*
X343766Y16584D01*
X343728Y16119D01*
X343804Y15654D01*
X343919Y15344D01*
X344149Y15034D01*
X344418Y14827D01*
X344686Y14724D01*
X344954D01*
X345223Y14827D01*
X345453Y14982D01*
X345644Y15189D01*
G01X346943D02*
X347173Y14931D01*
X347441Y14776D01*
X347786Y14724D01*
X348131Y14827D01*
X348399Y15034D01*
X348591Y15396D01*
X348629Y15809D01*
X348553Y16222D01*
X348361Y16481D01*
X348093Y16687D01*
X347824Y16739D01*
X347556Y16687D01*
X347211Y16481D01*
X347326Y17824D01*
X348361D01*
G01X350886D02*
X350579Y17721D01*
X350349Y17462D01*
X350196Y17152D01*
X350081Y16739D01*
X350043Y16274D01*
X350081Y15809D01*
X350196Y15396D01*
X350349Y15086D01*
X350579Y14827D01*
X350886Y14724D01*
X351193Y14827D01*
X351423Y15086D01*
X351576Y15396D01*
X351691Y15809D01*
X351729Y16274D01*
X351691Y16739D01*
X351576Y17152D01*
X351423Y17462D01*
X351193Y17721D01*
X350886Y17824D01*
G01X340819Y6636D02*
Y9736D01*
X341739D01*
X342046Y9581D01*
X342276Y9219D01*
X342353Y8806D01*
X342276Y8393D01*
X342084Y8083D01*
X341739Y7928D01*
X340819D01*
G01X345529Y9478D02*
X345299Y9633D01*
X345031Y9736D01*
X344724D01*
X344379Y9581D01*
X344111Y9323D01*
X343919Y9013D01*
X343766Y8496D01*
X343728Y8031D01*
X343804Y7566D01*
X343919Y7256D01*
X344149Y6946D01*
X344418Y6739D01*
X344686Y6636D01*
X344954D01*
X345223Y6739D01*
X345453Y6894D01*
X345644Y7101D01*
G01X348246Y6636D02*
Y9736D01*
X346828Y7514D01*
X348744D01*
G01X350234Y6998D02*
X350503Y6739D01*
X350809Y6636D01*
X351116Y6739D01*
X351384Y7049D01*
X351576Y7514D01*
X351653Y7979D01*
Y8548D01*
X351576Y9013D01*
X351384Y9426D01*
X351154Y9633D01*
X350886Y9736D01*
X350579Y9633D01*
X350349Y9426D01*
X350196Y9116D01*
X350119Y8703D01*
X350196Y8341D01*
X350388Y7979D01*
X350618Y7773D01*
X350886Y7721D01*
X351193Y7824D01*
X351423Y8083D01*
X351653Y8548D01*
G01X338883Y29930D02*
Y23130D01*
G01Y21930D02*
Y15130D01*
G01X346203Y21547D02*
Y24047D01*
X345883Y23547D01*
G01Y21547D02*
X346523D01*
G01X348723D02*
Y24047D01*
X347736Y22255D01*
X349070D01*
G01X341257Y26152D02*
Y50956D01*
G01X347883Y26152D02*
X341257D01*
G01X355733D02*
X352933D01*
G01X340764Y53696D02*
X340609Y53466D01*
X340506Y53198D01*
Y52891D01*
X340661Y52546D01*
X340919Y52278D01*
X341229Y52086D01*
X341746Y51933D01*
X342211Y51895D01*
X342676Y51971D01*
X342986Y52086D01*
X343296Y52316D01*
X343503Y52585D01*
X343606Y52853D01*
Y53121D01*
X343503Y53390D01*
X343348Y53620D01*
X343141Y53811D01*
G01X343606Y55953D02*
X340506D01*
X341126Y55493D01*
G01X343606D02*
Y56413D01*
G01Y59513D02*
X340506D01*
X342728Y58095D01*
Y60011D01*
G01X343606Y62153D02*
X343554Y62421D01*
X343399Y62728D01*
X343141Y62920D01*
X342779Y62996D01*
X342418Y62920D01*
X342108Y62690D01*
X341953Y62345D01*
Y61961D01*
X341849Y61731D01*
X341591Y61540D01*
X341229Y61463D01*
X340868Y61578D01*
X340609Y61846D01*
X340506Y62153D01*
X340609Y62460D01*
X340868Y62728D01*
X341229Y62843D01*
X341591Y62766D01*
X341849Y62575D01*
X341953Y62345D01*
Y61961D01*
X342108Y61616D01*
X342418Y61386D01*
X342779Y61310D01*
X343141Y61386D01*
X343399Y61578D01*
X343554Y61885D01*
X343606Y62153D01*
G01X344764Y53696D02*
X344609Y53466D01*
X344506Y53198D01*
Y52891D01*
X344661Y52546D01*
X344919Y52278D01*
X345229Y52086D01*
X345746Y51933D01*
X346211Y51895D01*
X346676Y51971D01*
X346986Y52086D01*
X347296Y52316D01*
X347503Y52585D01*
X347606Y52853D01*
Y53121D01*
X347503Y53390D01*
X347348Y53620D01*
X347141Y53811D01*
G01X347606Y55953D02*
X344506D01*
X345126Y55493D01*
G01X347606D02*
Y56413D01*
G01X347141Y58210D02*
X347399Y58440D01*
X347554Y58708D01*
X347606Y59053D01*
X347503Y59398D01*
X347296Y59666D01*
X346934Y59858D01*
X346521Y59896D01*
X346108Y59820D01*
X345849Y59628D01*
X345643Y59360D01*
X345591Y59091D01*
X345643Y58823D01*
X345849Y58478D01*
X344506Y58593D01*
Y59628D01*
G01Y62153D02*
X344609Y61846D01*
X344868Y61616D01*
X345178Y61463D01*
X345591Y61348D01*
X346056Y61310D01*
X346521Y61348D01*
X346934Y61463D01*
X347244Y61616D01*
X347503Y61846D01*
X347606Y62153D01*
X347503Y62460D01*
X347244Y62690D01*
X346934Y62843D01*
X346521Y62958D01*
X346056Y62996D01*
X345591Y62958D01*
X345178Y62843D01*
X344868Y62690D01*
X344609Y62460D01*
X344506Y62153D01*
G01X347891Y59122D02*
Y65322D01*
X351089D01*
Y59122D01*
X347891D01*
G01X349400Y53637D02*
Y56137D01*
X349080Y55637D01*
G01Y53637D02*
X349720D01*
G01X351013Y54137D02*
X351173Y53845D01*
X351387Y53679D01*
X351627Y53637D01*
X351840Y53679D01*
X352053Y53887D01*
X352187Y54137D01*
X352213Y54387D01*
X352160Y54679D01*
X351973Y54887D01*
X351787Y54970D01*
X351547D01*
G01X351787D02*
X351947Y55095D01*
X352080Y55304D01*
X352133Y55554D01*
X352080Y55804D01*
X351947Y56012D01*
X351707Y56137D01*
X351467Y56095D01*
X351227Y55929D01*
G01X341257Y50956D02*
X347883D01*
G01X352983D02*
X355783D01*
G01X338943Y67440D02*
Y70540D01*
X339902D01*
X340208Y70385D01*
X340400Y70178D01*
X340477Y69765D01*
X340400Y69352D01*
X340170Y69093D01*
X339902Y68938D01*
X338943D01*
G01X339902D02*
X340477Y67440D01*
G01X342082Y70023D02*
X342312Y70333D01*
X342580Y70488D01*
X342887Y70540D01*
X343270Y70437D01*
X343538Y70178D01*
X343615Y69868D01*
X343577Y69558D01*
X343423Y69300D01*
X342657Y68783D01*
X342312Y68422D01*
X342082Y67905D01*
X342005Y67440D01*
X343615D01*
G01X345910Y70540D02*
X345603Y70437D01*
X345373Y70178D01*
X345220Y69868D01*
X345105Y69455D01*
X345067Y68990D01*
X345105Y68525D01*
X345220Y68112D01*
X345373Y67802D01*
X345603Y67543D01*
X345910Y67440D01*
X346217Y67543D01*
X346447Y67802D01*
X346600Y68112D01*
X346715Y68525D01*
X346753Y68990D01*
X346715Y69455D01*
X346600Y69868D01*
X346447Y70178D01*
X346217Y70437D01*
X345910Y70540D01*
G01X348933Y67440D02*
X349010Y68112D01*
X349125Y68680D01*
X349278Y69197D01*
X349470Y69765D01*
X349777Y70540D01*
X348243D01*
G01X351053Y70905D02*
X357253D01*
G01Y67705D02*
X351053D01*
G01D02*
Y70905D01*
G01X346096Y164646D02*
X342996D01*
Y165605D01*
X343151Y165911D01*
X343358Y166103D01*
X343771Y166180D01*
X344184Y166103D01*
X344443Y165873D01*
X344598Y165605D01*
Y164646D01*
G01Y165605D02*
X346096Y166180D01*
G01X345631Y167670D02*
X345889Y167900D01*
X346044Y168168D01*
X346096Y168513D01*
X345993Y168858D01*
X345786Y169126D01*
X345424Y169318D01*
X345011Y169356D01*
X344598Y169280D01*
X344339Y169088D01*
X344133Y168820D01*
X344081Y168551D01*
X344133Y168283D01*
X344339Y167938D01*
X342996Y168053D01*
Y169088D01*
G01X345631Y170770D02*
X345889Y171000D01*
X346044Y171268D01*
X346096Y171613D01*
X345993Y171958D01*
X345786Y172226D01*
X345424Y172418D01*
X345011Y172456D01*
X344598Y172380D01*
X344339Y172188D01*
X344133Y171920D01*
X344081Y171651D01*
X344133Y171383D01*
X344339Y171038D01*
X342996Y171153D01*
Y172188D01*
G01X342096Y164646D02*
X338996D01*
Y165605D01*
X339151Y165911D01*
X339358Y166103D01*
X339771Y166180D01*
X340184Y166103D01*
X340443Y165873D01*
X340598Y165605D01*
Y164646D01*
G01Y165605D02*
X342096Y166180D01*
G01Y168973D02*
X338996D01*
X341218Y167555D01*
Y169471D01*
G01X342096Y171536D02*
X341424Y171613D01*
X340856Y171728D01*
X340339Y171881D01*
X339771Y172073D01*
X338996Y172380D01*
Y170846D01*
G01X350290Y164646D02*
X347190D01*
Y165605D01*
X347345Y165911D01*
X347552Y166103D01*
X347965Y166180D01*
X348378Y166103D01*
X348637Y165873D01*
X348792Y165605D01*
Y164646D01*
G01Y165605D02*
X350290Y166180D01*
G01X349825Y167670D02*
X350083Y167900D01*
X350238Y168168D01*
X350290Y168513D01*
X350187Y168858D01*
X349980Y169126D01*
X349618Y169318D01*
X349205Y169356D01*
X348792Y169280D01*
X348533Y169088D01*
X348327Y168820D01*
X348275Y168551D01*
X348327Y168283D01*
X348533Y167938D01*
X347190Y168053D01*
Y169088D01*
G01X348998Y170885D02*
X348637Y171153D01*
X348430Y171383D01*
X348327Y171690D01*
X348430Y171958D01*
X348637Y172150D01*
X348947Y172303D01*
X349308Y172341D01*
X349618Y172303D01*
X349928Y172150D01*
X350187Y171920D01*
X350290Y171651D01*
X350187Y171345D01*
X349877Y171076D01*
X349412Y170923D01*
X348895Y170885D01*
X348223Y170961D01*
X347862Y171076D01*
X347500Y171268D01*
X347242Y171536D01*
X347190Y171805D01*
X347293Y172073D01*
X347552Y172265D01*
G01X354427Y164646D02*
X351327D01*
Y165605D01*
X351482Y165911D01*
X351689Y166103D01*
X352102Y166180D01*
X352515Y166103D01*
X352774Y165873D01*
X352929Y165605D01*
Y164646D01*
G01Y165605D02*
X354427Y166180D01*
G01X353962Y167670D02*
X354220Y167900D01*
X354375Y168168D01*
X354427Y168513D01*
X354324Y168858D01*
X354117Y169126D01*
X353755Y169318D01*
X353342Y169356D01*
X352929Y169280D01*
X352670Y169088D01*
X352464Y168820D01*
X352412Y168551D01*
X352464Y168283D01*
X352670Y167938D01*
X351327Y168053D01*
Y169088D01*
G01X351844Y170885D02*
X351534Y171115D01*
X351379Y171383D01*
X351327Y171690D01*
X351430Y172073D01*
X351689Y172341D01*
X351999Y172418D01*
X352309Y172380D01*
X352567Y172226D01*
X353084Y171460D01*
X353445Y171115D01*
X353962Y170885D01*
X354427Y170808D01*
Y172418D01*
G01X340850Y180840D02*
X406580D01*
G01X341550Y176720D02*
Y179820D01*
X342509D01*
X342815Y179665D01*
X343007Y179458D01*
X343084Y179045D01*
X343007Y178632D01*
X342777Y178373D01*
X342509Y178218D01*
X341550D01*
G01X342509D02*
X343084Y176720D01*
G01X345417D02*
Y179820D01*
X344957Y179200D01*
G01Y176720D02*
X345877D01*
G01X348517Y179820D02*
X348210Y179717D01*
X347980Y179458D01*
X347827Y179148D01*
X347712Y178735D01*
X347674Y178270D01*
X347712Y177805D01*
X347827Y177392D01*
X347980Y177082D01*
X348210Y176823D01*
X348517Y176720D01*
X348824Y176823D01*
X349054Y177082D01*
X349207Y177392D01*
X349322Y177805D01*
X349360Y178270D01*
X349322Y178735D01*
X349207Y179148D01*
X349054Y179458D01*
X348824Y179717D01*
X348517Y179820D01*
G01X350965Y177082D02*
X351234Y176823D01*
X351540Y176720D01*
X351847Y176823D01*
X352115Y177133D01*
X352307Y177598D01*
X352384Y178063D01*
Y178632D01*
X352307Y179097D01*
X352115Y179510D01*
X351885Y179717D01*
X351617Y179820D01*
X351310Y179717D01*
X351080Y179510D01*
X350927Y179200D01*
X350850Y178787D01*
X350927Y178425D01*
X351119Y178063D01*
X351349Y177857D01*
X351617Y177805D01*
X351924Y177908D01*
X352154Y178167D01*
X352384Y178632D01*
G01X353874Y177340D02*
X354104Y176978D01*
X354410Y176772D01*
X354755Y176720D01*
X355062Y176772D01*
X355369Y177030D01*
X355560Y177340D01*
X355599Y177650D01*
X355522Y178012D01*
X355254Y178270D01*
X354985Y178373D01*
X354640D01*
G01X354985D02*
X355215Y178528D01*
X355407Y178787D01*
X355484Y179097D01*
X355407Y179407D01*
X355215Y179665D01*
X354870Y179820D01*
X354525Y179768D01*
X354180Y179562D01*
G01X340350Y276630D02*
Y228990D01*
G01X363431Y247244D02*
G02I-9100J0D01*
G01X345220Y300766D02*
Y297766D01*
G01X348320Y297666D02*
X342120D01*
G01D02*
Y300866D01*
G01D02*
X348320D01*
G01D02*
Y297666D01*
G01X350520Y301638D02*
X340320D01*
G01D02*
Y306238D01*
G01D02*
X350520D01*
G01D02*
Y301638D01*
G01X345420D02*
Y306238D01*
G01X344624Y311112D02*
Y314312D01*
G01X343924Y311112D02*
Y314312D01*
G01X347374D02*
Y311112D01*
G01D02*
X341174D01*
G01D02*
Y314312D01*
G01X341851Y310327D02*
X348051D01*
G01X345301Y307127D02*
Y310327D01*
G01X344601Y307127D02*
Y310327D01*
G01X348051D02*
Y307127D01*
G01D02*
X341851D01*
G01D02*
Y310327D01*
G01X337510Y342600D02*
Y323410D01*
G01X355670Y327776D02*
X340670D01*
G01D02*
Y334576D01*
G01X348170Y334476D02*
Y327876D01*
G01X350843Y324189D02*
X350613Y324344D01*
X350345Y324447D01*
X350038D01*
X349693Y324292D01*
X349425Y324034D01*
X349233Y323724D01*
X349080Y323207D01*
X349042Y322742D01*
X349118Y322277D01*
X349233Y321967D01*
X349463Y321657D01*
X349732Y321450D01*
X350000Y321347D01*
X350268D01*
X350537Y321450D01*
X350767Y321605D01*
X350958Y321812D01*
G01X353023Y321347D02*
X353100Y322019D01*
X353215Y322587D01*
X353368Y323104D01*
X353560Y323672D01*
X353867Y324447D01*
X352333D01*
G01X355548Y321709D02*
X355817Y321450D01*
X356123Y321347D01*
X356430Y321450D01*
X356698Y321760D01*
X356890Y322225D01*
X356967Y322690D01*
Y323259D01*
X356890Y323724D01*
X356698Y324137D01*
X356468Y324344D01*
X356200Y324447D01*
X355893Y324344D01*
X355663Y324137D01*
X355510Y323827D01*
X355433Y323414D01*
X355510Y323052D01*
X355702Y322690D01*
X355932Y322484D01*
X356200Y322432D01*
X356507Y322535D01*
X356737Y322794D01*
X356967Y323259D01*
G01X340896Y324072D02*
X347096D01*
G01X343996Y323972D02*
Y320972D01*
G01X347096Y320872D02*
X340896D01*
G01D02*
Y324072D01*
G01X347096D02*
Y320872D01*
G01X351353Y319219D02*
X351123Y319374D01*
X350855Y319477D01*
X350548D01*
X350203Y319322D01*
X349935Y319064D01*
X349743Y318754D01*
X349590Y318237D01*
X349552Y317772D01*
X349628Y317307D01*
X349743Y316997D01*
X349973Y316687D01*
X350242Y316480D01*
X350510Y316377D01*
X350778D01*
X351047Y316480D01*
X351277Y316635D01*
X351468Y316842D01*
G01X353533Y316377D02*
X353610Y317049D01*
X353725Y317617D01*
X353878Y318134D01*
X354070Y318702D01*
X354377Y319477D01*
X352843D01*
G01X356710Y316377D02*
X356978Y316429D01*
X357285Y316584D01*
X357477Y316842D01*
X357553Y317204D01*
X357477Y317565D01*
X357247Y317875D01*
X356902Y318030D01*
X356518D01*
X356288Y318134D01*
X356097Y318392D01*
X356020Y318754D01*
X356135Y319115D01*
X356403Y319374D01*
X356710Y319477D01*
X357017Y319374D01*
X357285Y319115D01*
X357400Y318754D01*
X357323Y318392D01*
X357132Y318134D01*
X356902Y318030D01*
X356518D01*
X356173Y317875D01*
X355943Y317565D01*
X355867Y317204D01*
X355943Y316842D01*
X356135Y316584D01*
X356442Y316429D01*
X356710Y316377D01*
G01X348926Y315297D02*
X338726D01*
G01D02*
Y319897D01*
G01D02*
X348926D01*
G01D02*
Y315297D01*
G01X343826D02*
Y319897D01*
G01X341174Y314312D02*
X347374D01*
G01X341873Y338875D02*
X341643Y339030D01*
X341375Y339133D01*
X341068D01*
X340723Y338978D01*
X340455Y338720D01*
X340263Y338410D01*
X340110Y337893D01*
X340072Y337428D01*
X340148Y336963D01*
X340263Y336653D01*
X340493Y336343D01*
X340762Y336136D01*
X341030Y336033D01*
X341298D01*
X341567Y336136D01*
X341797Y336291D01*
X341988Y336498D01*
G01X344130Y336033D02*
X344398Y336085D01*
X344705Y336240D01*
X344897Y336498D01*
X344973Y336860D01*
X344897Y337221D01*
X344667Y337531D01*
X344322Y337686D01*
X343938D01*
X343708Y337790D01*
X343517Y338048D01*
X343440Y338410D01*
X343555Y338771D01*
X343823Y339030D01*
X344130Y339133D01*
X344437Y339030D01*
X344705Y338771D01*
X344820Y338410D01*
X344743Y338048D01*
X344552Y337790D01*
X344322Y337686D01*
X343938D01*
X343593Y337531D01*
X343363Y337221D01*
X343287Y336860D01*
X343363Y336498D01*
X343555Y336240D01*
X343862Y336085D01*
X344130Y336033D01*
G01X347230D02*
Y339133D01*
X346770Y338513D01*
G01Y336033D02*
X347690D01*
G01X349487Y336653D02*
X349717Y336291D01*
X350023Y336085D01*
X350368Y336033D01*
X350675Y336085D01*
X350982Y336343D01*
X351173Y336653D01*
X351212Y336963D01*
X351135Y337325D01*
X350867Y337583D01*
X350598Y337686D01*
X350253D01*
G01X350598D02*
X350828Y337841D01*
X351020Y338100D01*
X351097Y338410D01*
X351020Y338720D01*
X350828Y338978D01*
X350483Y339133D01*
X350138Y339081D01*
X349793Y338875D01*
G01X340670Y334576D02*
X355670D01*
G01X363431Y349606D02*
G02I-9100J0D01*
G01X347979Y387736D02*
G02I-1000J0D01*
G01X343988Y385400D02*
Y394061D01*
G01X365170Y385400D02*
X343988D01*
G01Y397211D02*
Y405872D01*
G01X347079Y395636D02*
X343988Y397211D01*
G01Y394061D02*
X347079Y395636D01*
G01X343988Y405872D02*
X365170D01*
G01X341112Y423350D02*
Y426350D01*
G01X338012Y423250D02*
Y426450D01*
G01X344212Y423250D02*
X338012D01*
G01X344212Y426450D02*
Y423250D01*
G01X355707Y422960D02*
X349507D01*
G01D02*
Y426160D01*
G01X338012Y426450D02*
X344212D01*
G01X348307Y427670D02*
Y430770D01*
X349266D01*
X349572Y430615D01*
X349764Y430408D01*
X349841Y429995D01*
X349764Y429582D01*
X349534Y429323D01*
X349266Y429168D01*
X348307D01*
G01X349266D02*
X349841Y427670D01*
G01X352174D02*
Y430770D01*
X351714Y430150D01*
G01Y427670D02*
X352634D01*
G01X355197D02*
X355274Y428342D01*
X355389Y428910D01*
X355542Y429427D01*
X355734Y429995D01*
X356041Y430770D01*
X354507D01*
G01X358297Y427670D02*
X358374Y428342D01*
X358489Y428910D01*
X358642Y429427D01*
X358834Y429995D01*
X359141Y430770D01*
X357607D01*
G01X349507Y426160D02*
X355707D01*
G01X340115Y455282D02*
Y451345D01*
G01X349615Y455282D02*
Y449376D01*
G01X341973Y445266D02*
Y448366D01*
X342932D01*
X343238Y448211D01*
X343430Y448004D01*
X343507Y447591D01*
X343430Y447178D01*
X343200Y446919D01*
X342932Y446764D01*
X341973D01*
G01X342932D02*
X343507Y445266D01*
G01X345840D02*
Y448366D01*
X345380Y447746D01*
G01Y445266D02*
X346300D01*
G01X348212Y447849D02*
X348442Y448159D01*
X348710Y448314D01*
X349017Y448366D01*
X349400Y448263D01*
X349668Y448004D01*
X349745Y447694D01*
X349707Y447384D01*
X349553Y447126D01*
X348787Y446609D01*
X348442Y446248D01*
X348212Y445731D01*
X348135Y445266D01*
X349745D01*
G01X351197Y445731D02*
X351427Y445473D01*
X351695Y445318D01*
X352040Y445266D01*
X352385Y445369D01*
X352653Y445576D01*
X352845Y445938D01*
X352883Y446351D01*
X352807Y446764D01*
X352615Y447023D01*
X352347Y447229D01*
X352078Y447281D01*
X351810Y447229D01*
X351465Y447023D01*
X351580Y448366D01*
X352615D01*
G01X355063Y445266D02*
X355140Y445938D01*
X355255Y446506D01*
X355408Y447023D01*
X355600Y447591D01*
X355907Y448366D01*
X354373D01*
G01X351715Y502526D02*
Y496620D01*
G01X342115Y500557D02*
Y496620D01*
G01X338382Y517461D02*
Y519261D01*
G01X339540Y514557D02*
Y513561D01*
G01X344382Y517461D02*
X339982D01*
G01D02*
Y519261D01*
G01X343810Y514861D02*
G02I-1628J0D01*
G01X344382Y517461D02*
Y519261D01*
G01X351150Y516335D02*
Y515339D01*
G01X356382Y517461D02*
X351982D01*
G01X355810Y514861D02*
G02I-1628J0D01*
G01X351982Y517461D02*
Y519261D01*
G01X345030Y513297D02*
Y512301D01*
G01X348948Y514800D02*
G02I-1628J0D01*
G01X350382Y517461D02*
X345982D01*
G01D02*
Y519261D01*
G01X350382Y517461D02*
Y519261D01*
G01X338612Y510969D02*
Y504769D01*
G01X339912Y510969D02*
X343112D01*
G01X339912Y504769D02*
Y510969D01*
G01X343112Y504769D02*
X339912D01*
G01X343112Y510969D02*
Y504769D01*
G01X344412Y510969D02*
X347612D01*
G01X344412Y504769D02*
Y510969D01*
G01X347612Y504769D02*
X344412D01*
G01X347612Y510969D02*
Y504769D01*
G01X348912Y510969D02*
X352112D01*
G01X348912Y504769D02*
Y510969D01*
G01X352112Y504769D02*
X348912D01*
G01X352112Y510969D02*
Y504769D01*
G01X344340Y530031D02*
Y535031D01*
X341997Y531448D01*
X345163D01*
G01X346557Y530744D02*
X346937Y530327D01*
X347380Y530077D01*
X347950Y529994D01*
X348520Y530161D01*
X348963Y530494D01*
X349280Y531077D01*
X349343Y531744D01*
X349217Y532411D01*
X348900Y532827D01*
X348457Y533161D01*
X348013Y533244D01*
X347570Y533161D01*
X347000Y532827D01*
X347190Y534994D01*
X348900D01*
G01X352977Y532262D02*
X353420Y532846D01*
X353800Y533179D01*
X354307Y533346D01*
X354750Y533179D01*
X355067Y532846D01*
X355320Y532346D01*
X355383Y531762D01*
X355320Y531262D01*
X355067Y530762D01*
X354687Y530346D01*
X354243Y530179D01*
X353737Y530346D01*
X353293Y530846D01*
X353040Y531596D01*
X352977Y532429D01*
X353103Y533512D01*
X353293Y534096D01*
X353610Y534679D01*
X354053Y535096D01*
X354497Y535179D01*
X354940Y535012D01*
X355257Y534596D01*
G01X338382Y529661D02*
Y519261D01*
G01X339982Y529661D02*
X344382D01*
G01X339982Y519261D02*
Y529661D01*
G01X344382Y519261D02*
X339982D01*
G01X344382Y518661D02*
X339982D01*
G01Y518061D02*
X344382D01*
G01Y529661D02*
Y519261D01*
G01X356382D02*
X351982D01*
G01X356382Y518661D02*
X351982D01*
G01Y518061D02*
X356382D01*
G01X351982Y519261D02*
Y529661D01*
G01D02*
X356382D01*
G01X345982Y519261D02*
Y529661D01*
G01X350382Y519261D02*
X345982D01*
G01X350382Y529661D02*
Y519261D01*
G01Y518661D02*
X345982D01*
G01Y518061D02*
X350382D01*
G01X345982Y529661D02*
X350382D01*
G01X342282Y543777D02*
Y534477D01*
X339170D01*
G01X346358Y538648D02*
X343258D01*
Y539414D01*
X343413Y539721D01*
X343620Y539951D01*
X343930Y540143D01*
X344291Y540296D01*
X344808Y540334D01*
X345325Y540296D01*
X345686Y540143D01*
X345996Y539951D01*
X346203Y539721D01*
X346358Y539414D01*
Y538648D01*
G01X345738Y541748D02*
X346100Y541978D01*
X346306Y542284D01*
X346358Y542629D01*
X346306Y542936D01*
X346048Y543243D01*
X345738Y543434D01*
X345428Y543473D01*
X345066Y543396D01*
X344808Y543128D01*
X344705Y542859D01*
Y542514D01*
G01Y542859D02*
X344550Y543089D01*
X344291Y543281D01*
X343981Y543358D01*
X343671Y543281D01*
X343413Y543089D01*
X343258Y542744D01*
X343310Y542399D01*
X343516Y542054D01*
G01X345893Y544848D02*
X346151Y545078D01*
X346306Y545346D01*
X346358Y545691D01*
X346255Y546036D01*
X346048Y546304D01*
X345686Y546496D01*
X345273Y546534D01*
X344860Y546458D01*
X344601Y546266D01*
X344395Y545998D01*
X344343Y545729D01*
X344395Y545461D01*
X344601Y545116D01*
X343258Y545231D01*
Y546266D01*
G01X350288Y538871D02*
X347188D01*
Y539637D01*
X347343Y539944D01*
X347550Y540174D01*
X347860Y540366D01*
X348221Y540519D01*
X348738Y540557D01*
X349255Y540519D01*
X349616Y540366D01*
X349926Y540174D01*
X350133Y539944D01*
X350288Y539637D01*
Y538871D01*
G01X349668Y541971D02*
X350030Y542201D01*
X350236Y542507D01*
X350288Y542852D01*
X350236Y543159D01*
X349978Y543466D01*
X349668Y543657D01*
X349358Y543696D01*
X348996Y543619D01*
X348738Y543351D01*
X348635Y543082D01*
Y542737D01*
G01Y543082D02*
X348480Y543312D01*
X348221Y543504D01*
X347911Y543581D01*
X347601Y543504D01*
X347343Y543312D01*
X347188Y542967D01*
X347240Y542622D01*
X347446Y542277D01*
G01X350288Y545837D02*
X349616Y545914D01*
X349048Y546029D01*
X348531Y546182D01*
X347963Y546374D01*
X347188Y546681D01*
Y545147D01*
G01X354358Y538871D02*
X351258D01*
Y539637D01*
X351413Y539944D01*
X351620Y540174D01*
X351930Y540366D01*
X352291Y540519D01*
X352808Y540557D01*
X353325Y540519D01*
X353686Y540366D01*
X353996Y540174D01*
X354203Y539944D01*
X354358Y539637D01*
Y538871D01*
G01X353738Y541971D02*
X354100Y542201D01*
X354306Y542507D01*
X354358Y542852D01*
X354306Y543159D01*
X354048Y543466D01*
X353738Y543657D01*
X353428Y543696D01*
X353066Y543619D01*
X352808Y543351D01*
X352705Y543082D01*
Y542737D01*
G01Y543082D02*
X352550Y543312D01*
X352291Y543504D01*
X351981Y543581D01*
X351671Y543504D01*
X351413Y543312D01*
X351258Y542967D01*
X351310Y542622D01*
X351516Y542277D01*
G01X353066Y545186D02*
X352705Y545454D01*
X352498Y545684D01*
X352395Y545991D01*
X352498Y546259D01*
X352705Y546451D01*
X353015Y546604D01*
X353376Y546642D01*
X353686Y546604D01*
X353996Y546451D01*
X354255Y546221D01*
X354358Y545952D01*
X354255Y545646D01*
X353945Y545377D01*
X353480Y545224D01*
X352963Y545186D01*
X352291Y545262D01*
X351930Y545377D01*
X351568Y545569D01*
X351310Y545837D01*
X351258Y546106D01*
X351361Y546374D01*
X351620Y546566D01*
G01X354368Y549777D02*
X351268D01*
Y550736D01*
X351423Y551042D01*
X351630Y551234D01*
X352043Y551311D01*
X352456Y551234D01*
X352715Y551004D01*
X352870Y550736D01*
Y549777D01*
G01Y550736D02*
X354368Y551311D01*
G01Y553644D02*
X351268D01*
X351888Y553184D01*
G01X354368D02*
Y554104D01*
G01X351268Y556744D02*
X351371Y556437D01*
X351630Y556207D01*
X351940Y556054D01*
X352353Y555939D01*
X352818Y555901D01*
X353283Y555939D01*
X353696Y556054D01*
X354006Y556207D01*
X354265Y556437D01*
X354368Y556744D01*
X354265Y557051D01*
X354006Y557281D01*
X353696Y557434D01*
X353283Y557549D01*
X352818Y557587D01*
X352353Y557549D01*
X351940Y557434D01*
X351630Y557281D01*
X351371Y557051D01*
X351268Y556744D01*
G01X354006Y559192D02*
X354265Y559461D01*
X354368Y559767D01*
X354265Y560074D01*
X353955Y560342D01*
X353490Y560534D01*
X353025Y560611D01*
X352456D01*
X351991Y560534D01*
X351578Y560342D01*
X351371Y560112D01*
X351268Y559844D01*
X351371Y559537D01*
X351578Y559307D01*
X351888Y559154D01*
X352301Y559077D01*
X352663Y559154D01*
X353025Y559346D01*
X353231Y559576D01*
X353283Y559844D01*
X353180Y560151D01*
X352921Y560381D01*
X352456Y560611D01*
G01X353076Y562216D02*
X352715Y562484D01*
X352508Y562714D01*
X352405Y563021D01*
X352508Y563289D01*
X352715Y563481D01*
X353025Y563634D01*
X353386Y563672D01*
X353696Y563634D01*
X354006Y563481D01*
X354265Y563251D01*
X354368Y562982D01*
X354265Y562676D01*
X353955Y562407D01*
X353490Y562254D01*
X352973Y562216D01*
X352301Y562292D01*
X351940Y562407D01*
X351578Y562599D01*
X351320Y562867D01*
X351268Y563136D01*
X351371Y563404D01*
X351630Y563596D01*
G01X338288Y542503D02*
Y536303D01*
G01X350368Y549777D02*
X347268D01*
Y550736D01*
X347423Y551042D01*
X347630Y551234D01*
X348043Y551311D01*
X348456Y551234D01*
X348715Y551004D01*
X348870Y550736D01*
Y549777D01*
G01Y550736D02*
X350368Y551311D01*
G01Y553644D02*
X347268D01*
X347888Y553184D01*
G01X350368D02*
Y554104D01*
G01X347268Y556744D02*
X347371Y556437D01*
X347630Y556207D01*
X347940Y556054D01*
X348353Y555939D01*
X348818Y555901D01*
X349283Y555939D01*
X349696Y556054D01*
X350006Y556207D01*
X350265Y556437D01*
X350368Y556744D01*
X350265Y557051D01*
X350006Y557281D01*
X349696Y557434D01*
X349283Y557549D01*
X348818Y557587D01*
X348353Y557549D01*
X347940Y557434D01*
X347630Y557281D01*
X347371Y557051D01*
X347268Y556744D01*
G01X350006Y559192D02*
X350265Y559461D01*
X350368Y559767D01*
X350265Y560074D01*
X349955Y560342D01*
X349490Y560534D01*
X349025Y560611D01*
X348456D01*
X347991Y560534D01*
X347578Y560342D01*
X347371Y560112D01*
X347268Y559844D01*
X347371Y559537D01*
X347578Y559307D01*
X347888Y559154D01*
X348301Y559077D01*
X348663Y559154D01*
X349025Y559346D01*
X349231Y559576D01*
X349283Y559844D01*
X349180Y560151D01*
X348921Y560381D01*
X348456Y560611D01*
G01X350368Y562867D02*
X349696Y562944D01*
X349128Y563059D01*
X348611Y563212D01*
X348043Y563404D01*
X347268Y563711D01*
Y562177D01*
G01X345754Y549682D02*
X346064Y549874D01*
X346271Y550104D01*
X346374Y550372D01*
X346271Y550679D01*
X346064Y550909D01*
X345754Y551139D01*
X345341Y551216D01*
X343274D01*
G01X343791Y552821D02*
X343481Y553051D01*
X343326Y553319D01*
X343274Y553626D01*
X343377Y554009D01*
X343636Y554277D01*
X343946Y554354D01*
X344256Y554316D01*
X344514Y554162D01*
X345031Y553396D01*
X345392Y553051D01*
X345909Y552821D01*
X346374Y552744D01*
Y554354D01*
G01X345754Y555806D02*
X346116Y556036D01*
X346322Y556342D01*
X346374Y556687D01*
X346322Y556994D01*
X346064Y557301D01*
X345754Y557492D01*
X345444Y557531D01*
X345082Y557454D01*
X344824Y557186D01*
X344721Y556917D01*
Y556572D01*
G01Y556917D02*
X344566Y557147D01*
X344307Y557339D01*
X343997Y557416D01*
X343687Y557339D01*
X343429Y557147D01*
X343274Y556802D01*
X343326Y556457D01*
X343532Y556112D01*
G01X343556Y566398D02*
X343401Y566168D01*
X343298Y565900D01*
Y565593D01*
X343453Y565248D01*
X343711Y564980D01*
X344021Y564788D01*
X344538Y564635D01*
X345003Y564597D01*
X345468Y564673D01*
X345778Y564788D01*
X346088Y565018D01*
X346295Y565287D01*
X346398Y565555D01*
Y565823D01*
X346295Y566092D01*
X346140Y566322D01*
X345933Y566513D01*
G01X346398Y568655D02*
X346346Y568923D01*
X346191Y569230D01*
X345933Y569422D01*
X345571Y569498D01*
X345210Y569422D01*
X344900Y569192D01*
X344745Y568847D01*
Y568463D01*
X344641Y568233D01*
X344383Y568042D01*
X344021Y567965D01*
X343660Y568080D01*
X343401Y568348D01*
X343298Y568655D01*
X343401Y568962D01*
X343660Y569230D01*
X344021Y569345D01*
X344383Y569268D01*
X344641Y569077D01*
X344745Y568847D01*
Y568463D01*
X344900Y568118D01*
X345210Y567888D01*
X345571Y567812D01*
X345933Y567888D01*
X346191Y568080D01*
X346346Y568387D01*
X346398Y568655D01*
G01X345778Y570912D02*
X346140Y571142D01*
X346346Y571448D01*
X346398Y571793D01*
X346346Y572100D01*
X346088Y572407D01*
X345778Y572598D01*
X345468Y572637D01*
X345106Y572560D01*
X344848Y572292D01*
X344745Y572023D01*
Y571678D01*
G01Y572023D02*
X344590Y572253D01*
X344331Y572445D01*
X344021Y572522D01*
X343711Y572445D01*
X343453Y572253D01*
X343298Y571908D01*
X343350Y571563D01*
X343556Y571218D01*
G01X346398Y574778D02*
X345726Y574855D01*
X345158Y574970D01*
X344641Y575123D01*
X344073Y575315D01*
X343298Y575622D01*
Y574088D01*
G01X350808Y565108D02*
X347708D01*
Y566067D01*
X347863Y566373D01*
X348070Y566565D01*
X348483Y566642D01*
X348896Y566565D01*
X349155Y566335D01*
X349310Y566067D01*
Y565108D01*
G01Y566067D02*
X350808Y566642D01*
G01Y568975D02*
X347708D01*
X348328Y568515D01*
G01X350808D02*
Y569435D01*
G01X348225Y571347D02*
X347915Y571577D01*
X347760Y571845D01*
X347708Y572152D01*
X347811Y572535D01*
X348070Y572803D01*
X348380Y572880D01*
X348690Y572842D01*
X348948Y572688D01*
X349465Y571922D01*
X349826Y571577D01*
X350343Y571347D01*
X350808Y571270D01*
Y572880D01*
G01X350188Y574332D02*
X350550Y574562D01*
X350756Y574868D01*
X350808Y575213D01*
X350756Y575520D01*
X350498Y575827D01*
X350188Y576018D01*
X349878Y576057D01*
X349516Y575980D01*
X349258Y575712D01*
X349155Y575443D01*
Y575098D01*
G01Y575443D02*
X349000Y575673D01*
X348741Y575865D01*
X348431Y575942D01*
X348121Y575865D01*
X347863Y575673D01*
X347708Y575328D01*
X347760Y574983D01*
X347966Y574638D01*
G01X350808Y578735D02*
X347708D01*
X349930Y577317D01*
Y579233D01*
G01X338363Y550289D02*
X340585D01*
X341050Y550442D01*
X341360Y550749D01*
X341463Y551132D01*
X341360Y551515D01*
X341050Y551822D01*
X340585Y551975D01*
X338363D01*
G01X341463Y554232D02*
X338363D01*
X338983Y553772D01*
G01X341463D02*
Y554692D01*
G01X338880Y556604D02*
X338570Y556834D01*
X338415Y557102D01*
X338363Y557409D01*
X338466Y557792D01*
X338725Y558060D01*
X339035Y558137D01*
X339345Y558099D01*
X339603Y557945D01*
X340120Y557179D01*
X340481Y556834D01*
X340998Y556604D01*
X341463Y556527D01*
Y558137D01*
G01X338880Y559704D02*
X338570Y559934D01*
X338415Y560202D01*
X338363Y560509D01*
X338466Y560892D01*
X338725Y561160D01*
X339035Y561237D01*
X339345Y561199D01*
X339603Y561045D01*
X340120Y560279D01*
X340481Y559934D01*
X340998Y559704D01*
X341463Y559627D01*
Y561237D01*
G01X341979Y581208D02*
Y584308D01*
X342899D01*
X343206Y584153D01*
X343436Y583791D01*
X343513Y583378D01*
X343436Y582965D01*
X343244Y582655D01*
X342899Y582500D01*
X341979D01*
G01X346689Y584050D02*
X346459Y584205D01*
X346191Y584308D01*
X345884D01*
X345539Y584153D01*
X345271Y583895D01*
X345079Y583585D01*
X344926Y583068D01*
X344888Y582603D01*
X344964Y582138D01*
X345079Y581828D01*
X345309Y581518D01*
X345578Y581311D01*
X345846Y581208D01*
X346114D01*
X346383Y581311D01*
X346613Y581466D01*
X346804Y581673D01*
G01X348103Y581828D02*
X348333Y581466D01*
X348639Y581260D01*
X348984Y581208D01*
X349291Y581260D01*
X349598Y581518D01*
X349789Y581828D01*
X349828Y582138D01*
X349751Y582500D01*
X349483Y582758D01*
X349214Y582861D01*
X348869D01*
G01X349214D02*
X349444Y583016D01*
X349636Y583275D01*
X349713Y583585D01*
X349636Y583895D01*
X349444Y584153D01*
X349099Y584308D01*
X348754Y584256D01*
X348409Y584050D01*
G01X351394Y581570D02*
X351663Y581311D01*
X351969Y581208D01*
X352276Y581311D01*
X352544Y581621D01*
X352736Y582086D01*
X352813Y582551D01*
Y583120D01*
X352736Y583585D01*
X352544Y583998D01*
X352314Y584205D01*
X352046Y584308D01*
X351739Y584205D01*
X351509Y583998D01*
X351356Y583688D01*
X351279Y583275D01*
X351356Y582913D01*
X351548Y582551D01*
X351778Y582345D01*
X352046Y582293D01*
X352353Y582396D01*
X352583Y582655D01*
X352813Y583120D01*
G01X337867Y574202D02*
Y568002D01*
G01X341988Y568045D02*
X338788D01*
G01X341988Y574245D02*
Y568045D01*
G01X338788Y574245D02*
X341988D01*
G01X338788Y568045D02*
Y574245D01*
G01X341979Y593435D02*
Y596535D01*
X342899D01*
X343206Y596380D01*
X343436Y596018D01*
X343513Y595605D01*
X343436Y595192D01*
X343244Y594882D01*
X342899Y594727D01*
X341979D01*
G01X346689Y596277D02*
X346459Y596432D01*
X346191Y596535D01*
X345884D01*
X345539Y596380D01*
X345271Y596122D01*
X345079Y595812D01*
X344926Y595295D01*
X344888Y594830D01*
X344964Y594365D01*
X345079Y594055D01*
X345309Y593745D01*
X345578Y593538D01*
X345846Y593435D01*
X346114D01*
X346383Y593538D01*
X346613Y593693D01*
X346804Y593900D01*
G01X348946Y593435D02*
Y596535D01*
X348486Y595915D01*
G01Y593435D02*
X349406D01*
G01X351203Y594055D02*
X351433Y593693D01*
X351739Y593487D01*
X352084Y593435D01*
X352391Y593487D01*
X352698Y593745D01*
X352889Y594055D01*
X352928Y594365D01*
X352851Y594727D01*
X352583Y594985D01*
X352314Y595088D01*
X351969D01*
G01X352314D02*
X352544Y595243D01*
X352736Y595502D01*
X352813Y595812D01*
X352736Y596122D01*
X352544Y596380D01*
X352199Y596535D01*
X351854Y596483D01*
X351509Y596277D01*
G01X355146Y596535D02*
X354839Y596432D01*
X354609Y596173D01*
X354456Y595863D01*
X354341Y595450D01*
X354303Y594985D01*
X354341Y594520D01*
X354456Y594107D01*
X354609Y593797D01*
X354839Y593538D01*
X355146Y593435D01*
X355453Y593538D01*
X355683Y593797D01*
X355836Y594107D01*
X355951Y594520D01*
X355989Y594985D01*
X355951Y595450D01*
X355836Y595863D01*
X355683Y596173D01*
X355453Y596432D01*
X355146Y596535D01*
G01X341979Y589436D02*
Y592536D01*
X342899D01*
X343206Y592381D01*
X343436Y592019D01*
X343513Y591606D01*
X343436Y591193D01*
X343244Y590883D01*
X342899Y590728D01*
X341979D01*
G01X346689Y592278D02*
X346459Y592433D01*
X346191Y592536D01*
X345884D01*
X345539Y592381D01*
X345271Y592123D01*
X345079Y591813D01*
X344926Y591296D01*
X344888Y590831D01*
X344964Y590366D01*
X345079Y590056D01*
X345309Y589746D01*
X345578Y589539D01*
X345846Y589436D01*
X346114D01*
X346383Y589539D01*
X346613Y589694D01*
X346804Y589901D01*
G01X348103Y590056D02*
X348333Y589694D01*
X348639Y589488D01*
X348984Y589436D01*
X349291Y589488D01*
X349598Y589746D01*
X349789Y590056D01*
X349828Y590366D01*
X349751Y590728D01*
X349483Y590986D01*
X349214Y591089D01*
X348869D01*
G01X349214D02*
X349444Y591244D01*
X349636Y591503D01*
X349713Y591813D01*
X349636Y592123D01*
X349444Y592381D01*
X349099Y592536D01*
X348754Y592484D01*
X348409Y592278D01*
G01X351969Y589436D02*
X352046Y590108D01*
X352161Y590676D01*
X352314Y591193D01*
X352506Y591761D01*
X352813Y592536D01*
X351279D01*
G01X341979Y585208D02*
Y588308D01*
X342899D01*
X343206Y588153D01*
X343436Y587791D01*
X343513Y587378D01*
X343436Y586965D01*
X343244Y586655D01*
X342899Y586500D01*
X341979D01*
G01X346689Y588050D02*
X346459Y588205D01*
X346191Y588308D01*
X345884D01*
X345539Y588153D01*
X345271Y587895D01*
X345079Y587585D01*
X344926Y587068D01*
X344888Y586603D01*
X344964Y586138D01*
X345079Y585828D01*
X345309Y585518D01*
X345578Y585311D01*
X345846Y585208D01*
X346114D01*
X346383Y585311D01*
X346613Y585466D01*
X346804Y585673D01*
G01X348103Y585828D02*
X348333Y585466D01*
X348639Y585260D01*
X348984Y585208D01*
X349291Y585260D01*
X349598Y585518D01*
X349789Y585828D01*
X349828Y586138D01*
X349751Y586500D01*
X349483Y586758D01*
X349214Y586861D01*
X348869D01*
G01X349214D02*
X349444Y587016D01*
X349636Y587275D01*
X349713Y587585D01*
X349636Y587895D01*
X349444Y588153D01*
X349099Y588308D01*
X348754Y588256D01*
X348409Y588050D01*
G01X352046Y585208D02*
X352314Y585260D01*
X352621Y585415D01*
X352813Y585673D01*
X352889Y586035D01*
X352813Y586396D01*
X352583Y586706D01*
X352238Y586861D01*
X351854D01*
X351624Y586965D01*
X351433Y587223D01*
X351356Y587585D01*
X351471Y587946D01*
X351739Y588205D01*
X352046Y588308D01*
X352353Y588205D01*
X352621Y587946D01*
X352736Y587585D01*
X352659Y587223D01*
X352468Y586965D01*
X352238Y586861D01*
X351854D01*
X351509Y586706D01*
X351279Y586396D01*
X351203Y586035D01*
X351279Y585673D01*
X351471Y585415D01*
X351778Y585260D01*
X352046Y585208D01*
G01X347372Y609713D02*
Y616313D01*
G01X339872Y609613D02*
Y616413D01*
G01X354872Y609613D02*
X339872D01*
G01X344225Y597612D02*
Y600812D01*
G01X350425Y597612D02*
X344225D01*
G01Y600812D02*
X350425D01*
G01X347325Y597712D02*
Y600712D01*
G01X350425Y600812D02*
Y597612D01*
G01X347372Y601713D02*
Y608313D01*
G01X339872Y608413D02*
X354872D01*
G01X339872Y601613D02*
Y608413D01*
G01X354872Y601613D02*
X339872D01*
G01X348220Y625360D02*
Y647570D01*
G01X371800Y625360D02*
X348220D01*
G01X347372Y617713D02*
Y624313D01*
G01X339872Y624413D02*
X354872D01*
G01X339872Y617613D02*
Y624413D01*
G01X354872Y617613D02*
X339872D01*
G01Y616413D02*
X354872D01*
G01X350798Y626132D02*
Y641132D01*
G01X363798Y626132D02*
X350798D01*
G01X340588Y644712D02*
X340641Y645254D01*
X340721Y645712D01*
X340828Y646129D01*
X340961Y646587D01*
X341174Y647212D01*
X340108D01*
G01X342254Y645087D02*
X342414Y644879D01*
X342601Y644754D01*
X342841Y644712D01*
X343081Y644795D01*
X343268Y644962D01*
X343401Y645254D01*
X343428Y645587D01*
X343374Y645920D01*
X343241Y646129D01*
X343054Y646295D01*
X342868Y646337D01*
X342681Y646295D01*
X342441Y646129D01*
X342521Y647212D01*
X343241D01*
G01X338640Y638356D02*
Y643356D01*
G01X352142Y642566D02*
Y645766D01*
G01X358342Y642566D02*
X352142D01*
G01X349116Y630871D02*
Y633371D01*
X349650D01*
X349863Y633246D01*
X350023Y633079D01*
X350156Y632829D01*
X350263Y632538D01*
X350290Y632121D01*
X350263Y631704D01*
X350156Y631413D01*
X350023Y631163D01*
X349863Y630996D01*
X349650Y630871D01*
X349116D01*
G01X348869Y637617D02*
X349082Y637409D01*
X349322Y637284D01*
X349536D01*
X349749Y637409D01*
X349909Y637617D01*
X349989Y637909D01*
X349936Y638201D01*
X349802Y638451D01*
X349562Y638617D01*
X349242Y638701D01*
X349056Y638867D01*
X348976Y639159D01*
X349029Y639451D01*
X349162Y639659D01*
X349349Y639784D01*
X349536D01*
X349722Y639701D01*
X349882Y639492D01*
G01X350798Y641132D02*
X363798D01*
G01X348220Y647570D02*
X353510D01*
G01X347443Y650371D02*
X347496Y650913D01*
X347576Y651371D01*
X347683Y651788D01*
X347816Y652246D01*
X348029Y652871D01*
X346963D01*
G01X349189Y651413D02*
X349376Y651704D01*
X349536Y651871D01*
X349749Y651954D01*
X349936Y651871D01*
X350069Y651704D01*
X350176Y651454D01*
X350203Y651163D01*
X350176Y650913D01*
X350069Y650663D01*
X349909Y650454D01*
X349723Y650371D01*
X349509Y650454D01*
X349323Y650704D01*
X349216Y651079D01*
X349189Y651496D01*
X349243Y652038D01*
X349323Y652329D01*
X349456Y652621D01*
X349643Y652829D01*
X349829Y652871D01*
X350016Y652788D01*
X350149Y652579D01*
G01X339740Y701156D02*
Y652856D01*
G01X352142Y645766D02*
X358342D01*
G01X354240Y671856D02*
X349240D01*
G01X361340Y661956D02*
X349140D01*
G01X361340Y681556D02*
X349140D01*
G01X344081Y712585D02*
Y705902D01*
X344060D01*
X341867Y708095D01*
X341888Y708116D01*
X346716D01*
X344481Y705881D01*
X344144D01*
G01X343034Y702566D02*
Y705066D01*
X342714Y704566D01*
G01Y702566D02*
X343354D01*
G01X345234Y705066D02*
X345021Y704983D01*
X344861Y704774D01*
X344754Y704524D01*
X344674Y704191D01*
X344647Y703816D01*
X344674Y703441D01*
X344754Y703108D01*
X344861Y702858D01*
X345021Y702649D01*
X345234Y702566D01*
X345447Y702649D01*
X345607Y702858D01*
X345714Y703108D01*
X345794Y703441D01*
X345821Y703816D01*
X345794Y704191D01*
X345714Y704524D01*
X345607Y704774D01*
X345447Y704983D01*
X345234Y705066D01*
G01X347434D02*
X347221Y704983D01*
X347061Y704774D01*
X346954Y704524D01*
X346874Y704191D01*
X346847Y703816D01*
X346874Y703441D01*
X346954Y703108D01*
X347061Y702858D01*
X347221Y702649D01*
X347434Y702566D01*
X347647Y702649D01*
X347807Y702858D01*
X347914Y703108D01*
X347994Y703441D01*
X348021Y703816D01*
X347994Y704191D01*
X347914Y704524D01*
X347807Y704774D01*
X347647Y704983D01*
X347434Y705066D01*
G01X354140Y691356D02*
X349140D01*
G01X361440Y701356D02*
X349240D01*
G01X338440Y702456D02*
X339740Y701156D01*
G01X352774Y703097D02*
X350274D01*
Y703763D01*
X350399Y703977D01*
X350566Y704110D01*
X350899Y704163D01*
X351232Y704110D01*
X351441Y703950D01*
X351566Y703763D01*
Y703097D01*
G01Y703763D02*
X352774Y704163D01*
G01Y705830D02*
X350274D01*
X350774Y705510D01*
G01X352774D02*
Y706150D01*
G01Y708030D02*
X350274D01*
X350774Y707710D01*
G01X352774D02*
Y708350D01*
G01Y710177D02*
X352232Y710230D01*
X351774Y710310D01*
X351357Y710417D01*
X350899Y710550D01*
X350274Y710763D01*
Y709697D01*
G01X352774Y712377D02*
X352232Y712430D01*
X351774Y712510D01*
X351357Y712617D01*
X350899Y712750D01*
X350274Y712963D01*
Y711897D01*
G01X347087Y720285D02*
X346707Y720535D01*
X346264Y720702D01*
X345757D01*
X345187Y720452D01*
X344744Y720035D01*
X344427Y719535D01*
X344174Y718702D01*
X344111Y717952D01*
X344237Y717202D01*
X344427Y716702D01*
X344807Y716202D01*
X345251Y715869D01*
X345694Y715702D01*
X346137D01*
X346581Y715869D01*
X346961Y716119D01*
X347277Y716452D01*
G01X349527Y715702D02*
Y720702D01*
X351047D01*
X351554Y720452D01*
X351934Y719869D01*
X352061Y719202D01*
X351934Y718535D01*
X351617Y718035D01*
X351047Y717785D01*
X349527D01*
G01X354627Y720702D02*
Y715702D01*
X357161D01*
G01X359601D02*
Y720702D01*
X360867D01*
X361374Y720452D01*
X361754Y720119D01*
X362071Y719619D01*
X362324Y719035D01*
X362387Y718202D01*
X362324Y717369D01*
X362071Y716785D01*
X361754Y716285D01*
X361374Y715952D01*
X360867Y715702D01*
X359601D01*
G01X364891Y719869D02*
X365271Y720369D01*
X365714Y720619D01*
X366221Y720702D01*
X366854Y720535D01*
X367297Y720119D01*
X367424Y719619D01*
X367361Y719119D01*
X367107Y718702D01*
X365841Y717869D01*
X365271Y717285D01*
X364891Y716452D01*
X364764Y715702D01*
X367424D01*
G01X344880Y721461D02*
X369206D01*
Y715008D01*
X342307D01*
Y721461D01*
X344880D01*
G01X346006Y714874D02*
X349206D01*
G01X346006Y708674D02*
Y714874D01*
G01X349206Y708674D02*
X346006D01*
G01X349206Y714874D02*
Y708674D01*
G01X348540Y737556D02*
X345340D01*
G01X348540Y743756D02*
Y737556D01*
G01X345340D02*
Y743756D01*
G01X344440Y729156D02*
X341440D01*
G01X344540Y726056D02*
X341340D01*
G01X344540Y732256D02*
Y726056D01*
G01X341340Y732256D02*
X344540D01*
G01X341340Y726056D02*
Y732256D01*
G01X340040Y743756D02*
Y737556D01*
G01X353440Y729156D02*
X350440D01*
G01X353540Y726056D02*
X350340D01*
G01Y732256D02*
X353540D01*
G01X350340Y726056D02*
Y732256D01*
G01X341340Y737556D02*
Y743756D01*
G01X344540Y737556D02*
X341340D01*
G01X344540Y743756D02*
Y737556D01*
G01X345840Y732256D02*
X349040D01*
G01X345840Y726056D02*
Y732256D01*
G01X349040Y726056D02*
X345840D01*
G01X349040Y732256D02*
Y726056D01*
G01X340040Y732256D02*
Y726056D01*
G01X349340Y737556D02*
Y743756D01*
G01X352540Y737556D02*
X349340D01*
G01X352540Y743756D02*
Y737556D01*
G01X348440Y740656D02*
X345440D01*
G01X345340Y743756D02*
X348540D01*
G01X354923Y756899D02*
X354693Y757054D01*
X354425Y757157D01*
X354118D01*
X353773Y757002D01*
X353505Y756744D01*
X353313Y756434D01*
X353160Y755917D01*
X353122Y755452D01*
X353198Y754987D01*
X353313Y754677D01*
X353543Y754367D01*
X353812Y754160D01*
X354080Y754057D01*
X354348D01*
X354617Y754160D01*
X354847Y754315D01*
X355038Y754522D01*
G01X356452Y755349D02*
X356720Y755710D01*
X356950Y755917D01*
X357257Y756020D01*
X357525Y755917D01*
X357717Y755710D01*
X357870Y755400D01*
X357908Y755039D01*
X357870Y754729D01*
X357717Y754419D01*
X357487Y754160D01*
X357218Y754057D01*
X356912Y754160D01*
X356643Y754470D01*
X356490Y754935D01*
X356452Y755452D01*
X356528Y756124D01*
X356643Y756485D01*
X356835Y756847D01*
X357103Y757105D01*
X357372Y757157D01*
X357640Y757054D01*
X357832Y756795D01*
G01X360280Y754057D02*
X360548Y754109D01*
X360855Y754264D01*
X361047Y754522D01*
X361123Y754884D01*
X361047Y755245D01*
X360817Y755555D01*
X360472Y755710D01*
X360088D01*
X359858Y755814D01*
X359667Y756072D01*
X359590Y756434D01*
X359705Y756795D01*
X359973Y757054D01*
X360280Y757157D01*
X360587Y757054D01*
X360855Y756795D01*
X360970Y756434D01*
X360893Y756072D01*
X360702Y755814D01*
X360472Y755710D01*
X360088D01*
X359743Y755555D01*
X359513Y755245D01*
X359437Y754884D01*
X359513Y754522D01*
X359705Y754264D01*
X360012Y754109D01*
X360280Y754057D01*
G01X363303D02*
X363380Y754729D01*
X363495Y755297D01*
X363648Y755814D01*
X363840Y756382D01*
X364147Y757157D01*
X362613D01*
G01X354923Y753439D02*
X354693Y753594D01*
X354425Y753697D01*
X354118D01*
X353773Y753542D01*
X353505Y753284D01*
X353313Y752974D01*
X353160Y752457D01*
X353122Y751992D01*
X353198Y751527D01*
X353313Y751217D01*
X353543Y750907D01*
X353812Y750700D01*
X354080Y750597D01*
X354348D01*
X354617Y750700D01*
X354847Y750855D01*
X355038Y751062D01*
G01X356452Y751889D02*
X356720Y752250D01*
X356950Y752457D01*
X357257Y752560D01*
X357525Y752457D01*
X357717Y752250D01*
X357870Y751940D01*
X357908Y751579D01*
X357870Y751269D01*
X357717Y750959D01*
X357487Y750700D01*
X357218Y750597D01*
X356912Y750700D01*
X356643Y751010D01*
X356490Y751475D01*
X356452Y751992D01*
X356528Y752664D01*
X356643Y753025D01*
X356835Y753387D01*
X357103Y753645D01*
X357372Y753697D01*
X357640Y753594D01*
X357832Y753335D01*
G01X359628Y750959D02*
X359897Y750700D01*
X360203Y750597D01*
X360510Y750700D01*
X360778Y751010D01*
X360970Y751475D01*
X361047Y751940D01*
Y752509D01*
X360970Y752974D01*
X360778Y753387D01*
X360548Y753594D01*
X360280Y753697D01*
X359973Y753594D01*
X359743Y753387D01*
X359590Y753077D01*
X359513Y752664D01*
X359590Y752302D01*
X359782Y751940D01*
X360012Y751734D01*
X360280Y751682D01*
X360587Y751785D01*
X360817Y752044D01*
X361047Y752509D01*
G01X362537Y751217D02*
X362767Y750855D01*
X363073Y750649D01*
X363418Y750597D01*
X363725Y750649D01*
X364032Y750907D01*
X364223Y751217D01*
X364262Y751527D01*
X364185Y751889D01*
X363917Y752147D01*
X363648Y752250D01*
X363303D01*
G01X363648D02*
X363878Y752405D01*
X364070Y752664D01*
X364147Y752974D01*
X364070Y753284D01*
X363878Y753542D01*
X363533Y753697D01*
X363188Y753645D01*
X362843Y753439D01*
G01X342010Y747677D02*
X341855Y747447D01*
X341752Y747179D01*
Y746872D01*
X341907Y746527D01*
X342165Y746259D01*
X342475Y746067D01*
X342992Y745914D01*
X343457Y745876D01*
X343922Y745952D01*
X344232Y746067D01*
X344542Y746297D01*
X344749Y746566D01*
X344852Y746834D01*
Y747102D01*
X344749Y747371D01*
X344594Y747601D01*
X344387Y747792D01*
G01X344852Y749857D02*
X344180Y749934D01*
X343612Y750049D01*
X343095Y750202D01*
X342527Y750394D01*
X341752Y750701D01*
Y749167D01*
G01Y753034D02*
X341855Y752727D01*
X342114Y752497D01*
X342424Y752344D01*
X342837Y752229D01*
X343302Y752191D01*
X343767Y752229D01*
X344180Y752344D01*
X344490Y752497D01*
X344749Y752727D01*
X344852Y753034D01*
X344749Y753341D01*
X344490Y753571D01*
X344180Y753724D01*
X343767Y753839D01*
X343302Y753877D01*
X342837Y753839D01*
X342424Y753724D01*
X342114Y753571D01*
X341855Y753341D01*
X341752Y753034D01*
G01X344852Y756134D02*
X344800Y756402D01*
X344645Y756709D01*
X344387Y756901D01*
X344025Y756977D01*
X343664Y756901D01*
X343354Y756671D01*
X343199Y756326D01*
Y755942D01*
X343095Y755712D01*
X342837Y755521D01*
X342475Y755444D01*
X342114Y755559D01*
X341855Y755827D01*
X341752Y756134D01*
X341855Y756441D01*
X342114Y756709D01*
X342475Y756824D01*
X342837Y756747D01*
X343095Y756556D01*
X343199Y756326D01*
Y755942D01*
X343354Y755597D01*
X343664Y755367D01*
X344025Y755291D01*
X344387Y755367D01*
X344645Y755559D01*
X344800Y755866D01*
X344852Y756134D01*
G01X341340Y743756D02*
X344540D01*
G01X340526Y746067D02*
X337426D01*
Y747026D01*
X337581Y747332D01*
X337788Y747524D01*
X338201Y747601D01*
X338614Y747524D01*
X338873Y747294D01*
X339028Y747026D01*
Y746067D01*
G01Y747026D02*
X340526Y747601D01*
G01X340164Y749282D02*
X340423Y749551D01*
X340526Y749857D01*
X340423Y750164D01*
X340113Y750432D01*
X339648Y750624D01*
X339183Y750701D01*
X338614D01*
X338149Y750624D01*
X337736Y750432D01*
X337529Y750202D01*
X337426Y749934D01*
X337529Y749627D01*
X337736Y749397D01*
X338046Y749244D01*
X338459Y749167D01*
X338821Y749244D01*
X339183Y749436D01*
X339389Y749666D01*
X339441Y749934D01*
X339338Y750241D01*
X339079Y750471D01*
X338614Y750701D01*
G01X340526Y753494D02*
X337426D01*
X339648Y752076D01*
Y753992D01*
G01X340526Y756134D02*
X340474Y756402D01*
X340319Y756709D01*
X340061Y756901D01*
X339699Y756977D01*
X339338Y756901D01*
X339028Y756671D01*
X338873Y756326D01*
Y755942D01*
X338769Y755712D01*
X338511Y755521D01*
X338149Y755444D01*
X337788Y755559D01*
X337529Y755827D01*
X337426Y756134D01*
X337529Y756441D01*
X337788Y756709D01*
X338149Y756824D01*
X338511Y756747D01*
X338769Y756556D01*
X338873Y756326D01*
Y755942D01*
X339028Y755597D01*
X339338Y755367D01*
X339699Y755291D01*
X340061Y755367D01*
X340319Y755559D01*
X340474Y755866D01*
X340526Y756134D01*
G01X349340Y743756D02*
X352540D01*
G01X355003Y769702D02*
X354773Y769857D01*
X354505Y769960D01*
X354198D01*
X353853Y769805D01*
X353585Y769547D01*
X353393Y769237D01*
X353240Y768720D01*
X353202Y768255D01*
X353278Y767790D01*
X353393Y767480D01*
X353623Y767170D01*
X353892Y766963D01*
X354160Y766860D01*
X354428D01*
X354697Y766963D01*
X354927Y767118D01*
X355118Y767325D01*
G01X356532Y768152D02*
X356800Y768513D01*
X357030Y768720D01*
X357337Y768823D01*
X357605Y768720D01*
X357797Y768513D01*
X357950Y768203D01*
X357988Y767842D01*
X357950Y767532D01*
X357797Y767222D01*
X357567Y766963D01*
X357298Y766860D01*
X356992Y766963D01*
X356723Y767273D01*
X356570Y767738D01*
X356532Y768255D01*
X356608Y768927D01*
X356723Y769288D01*
X356915Y769650D01*
X357183Y769908D01*
X357452Y769960D01*
X357720Y769857D01*
X357912Y769598D01*
G01X360360Y766860D02*
X360628Y766912D01*
X360935Y767067D01*
X361127Y767325D01*
X361203Y767687D01*
X361127Y768048D01*
X360897Y768358D01*
X360552Y768513D01*
X360168D01*
X359938Y768617D01*
X359747Y768875D01*
X359670Y769237D01*
X359785Y769598D01*
X360053Y769857D01*
X360360Y769960D01*
X360667Y769857D01*
X360935Y769598D01*
X361050Y769237D01*
X360973Y768875D01*
X360782Y768617D01*
X360552Y768513D01*
X360168D01*
X359823Y768358D01*
X359593Y768048D01*
X359517Y767687D01*
X359593Y767325D01*
X359785Y767067D01*
X360092Y766912D01*
X360360Y766860D01*
G01X363460D02*
Y769960D01*
X363000Y769340D01*
G01Y766860D02*
X363920D01*
G01X337863Y760558D02*
X337708Y760328D01*
X337605Y760060D01*
Y759753D01*
X337760Y759408D01*
X338018Y759140D01*
X338328Y758948D01*
X338845Y758795D01*
X339310Y758757D01*
X339775Y758833D01*
X340085Y758948D01*
X340395Y759178D01*
X340602Y759447D01*
X340705Y759715D01*
Y759983D01*
X340602Y760252D01*
X340447Y760482D01*
X340240Y760673D01*
G01X340705Y762738D02*
X340033Y762815D01*
X339465Y762930D01*
X338948Y763083D01*
X338380Y763275D01*
X337605Y763582D01*
Y762048D01*
G01X340705Y765915D02*
X337605D01*
X338225Y765455D01*
G01X340705D02*
Y766375D01*
G01Y769015D02*
X337605D01*
X338225Y768555D01*
G01X340705D02*
Y769475D01*
G01X355003Y765752D02*
X354773Y765907D01*
X354505Y766010D01*
X354198D01*
X353853Y765855D01*
X353585Y765597D01*
X353393Y765287D01*
X353240Y764770D01*
X353202Y764305D01*
X353278Y763840D01*
X353393Y763530D01*
X353623Y763220D01*
X353892Y763013D01*
X354160Y762910D01*
X354428D01*
X354697Y763013D01*
X354927Y763168D01*
X355118Y763375D01*
G01X356532Y764202D02*
X356800Y764563D01*
X357030Y764770D01*
X357337Y764873D01*
X357605Y764770D01*
X357797Y764563D01*
X357950Y764253D01*
X357988Y763892D01*
X357950Y763582D01*
X357797Y763272D01*
X357567Y763013D01*
X357298Y762910D01*
X356992Y763013D01*
X356723Y763323D01*
X356570Y763788D01*
X356532Y764305D01*
X356608Y764977D01*
X356723Y765338D01*
X356915Y765700D01*
X357183Y765958D01*
X357452Y766010D01*
X357720Y765907D01*
X357912Y765648D01*
G01X360360Y762910D02*
X360628Y762962D01*
X360935Y763117D01*
X361127Y763375D01*
X361203Y763737D01*
X361127Y764098D01*
X360897Y764408D01*
X360552Y764563D01*
X360168D01*
X359938Y764667D01*
X359747Y764925D01*
X359670Y765287D01*
X359785Y765648D01*
X360053Y765907D01*
X360360Y766010D01*
X360667Y765907D01*
X360935Y765648D01*
X361050Y765287D01*
X360973Y764925D01*
X360782Y764667D01*
X360552Y764563D01*
X360168D01*
X359823Y764408D01*
X359593Y764098D01*
X359517Y763737D01*
X359593Y763375D01*
X359785Y763117D01*
X360092Y762962D01*
X360360Y762910D01*
G01X363920D02*
Y766010D01*
X362502Y763788D01*
X364418D01*
G01X355003Y773492D02*
X354773Y773647D01*
X354505Y773750D01*
X354198D01*
X353853Y773595D01*
X353585Y773337D01*
X353393Y773027D01*
X353240Y772510D01*
X353202Y772045D01*
X353278Y771580D01*
X353393Y771270D01*
X353623Y770960D01*
X353892Y770753D01*
X354160Y770650D01*
X354428D01*
X354697Y770753D01*
X354927Y770908D01*
X355118Y771115D01*
G01X356532Y771942D02*
X356800Y772303D01*
X357030Y772510D01*
X357337Y772613D01*
X357605Y772510D01*
X357797Y772303D01*
X357950Y771993D01*
X357988Y771632D01*
X357950Y771322D01*
X357797Y771012D01*
X357567Y770753D01*
X357298Y770650D01*
X356992Y770753D01*
X356723Y771063D01*
X356570Y771528D01*
X356532Y772045D01*
X356608Y772717D01*
X356723Y773078D01*
X356915Y773440D01*
X357183Y773698D01*
X357452Y773750D01*
X357720Y773647D01*
X357912Y773388D01*
G01X360283Y770650D02*
X360360Y771322D01*
X360475Y771890D01*
X360628Y772407D01*
X360820Y772975D01*
X361127Y773750D01*
X359593D01*
G01X362732Y773233D02*
X362962Y773543D01*
X363230Y773698D01*
X363537Y773750D01*
X363920Y773647D01*
X364188Y773388D01*
X364265Y773078D01*
X364227Y772768D01*
X364073Y772510D01*
X363307Y771993D01*
X362962Y771632D01*
X362732Y771115D01*
X362655Y770650D01*
X364265D01*
G01X344698Y758948D02*
X341598D01*
Y759907D01*
X341753Y760213D01*
X341960Y760405D01*
X342373Y760482D01*
X342786Y760405D01*
X343045Y760175D01*
X343200Y759907D01*
Y758948D01*
G01Y759907D02*
X344698Y760482D01*
G01X344336Y762163D02*
X344595Y762432D01*
X344698Y762738D01*
X344595Y763045D01*
X344285Y763313D01*
X343820Y763505D01*
X343355Y763582D01*
X342786D01*
X342321Y763505D01*
X341908Y763313D01*
X341701Y763083D01*
X341598Y762815D01*
X341701Y762508D01*
X341908Y762278D01*
X342218Y762125D01*
X342631Y762048D01*
X342993Y762125D01*
X343355Y762317D01*
X343561Y762547D01*
X343613Y762815D01*
X343510Y763122D01*
X343251Y763352D01*
X342786Y763582D01*
G01X344698Y766375D02*
X341598D01*
X343820Y764957D01*
Y766873D01*
G01X344233Y768172D02*
X344491Y768402D01*
X344646Y768670D01*
X344698Y769015D01*
X344595Y769360D01*
X344388Y769628D01*
X344026Y769820D01*
X343613Y769858D01*
X343200Y769782D01*
X342941Y769590D01*
X342735Y769322D01*
X342683Y769053D01*
X342735Y768785D01*
X342941Y768440D01*
X341598Y768555D01*
Y769590D01*
G01X339094Y821652D02*
X378071D01*
G01X359093Y-237697D02*
X359693Y-236897D01*
X360393Y-236497D01*
X361193Y-236364D01*
X362193Y-236631D01*
X362893Y-237297D01*
X363093Y-238097D01*
X362993Y-238898D01*
X362593Y-239564D01*
X360593Y-240897D01*
X359693Y-241831D01*
X359093Y-243164D01*
X358893Y-244364D01*
X363093D01*
G01X368993Y-236364D02*
X368193Y-236631D01*
X367593Y-237297D01*
X367193Y-238097D01*
X366893Y-239164D01*
X366793Y-240364D01*
X366893Y-241564D01*
X367193Y-242631D01*
X367593Y-243431D01*
X368193Y-244097D01*
X368993Y-244364D01*
X369793Y-244097D01*
X370393Y-243431D01*
X370793Y-242631D01*
X371093Y-241564D01*
X371193Y-240364D01*
X371093Y-239164D01*
X370793Y-238097D01*
X370393Y-237297D01*
X369793Y-236631D01*
X368993Y-236364D01*
G01X376993Y-244364D02*
Y-236364D01*
X375793Y-237964D01*
G01Y-244364D02*
X378193D01*
G01X383093Y-237697D02*
X383693Y-236897D01*
X384393Y-236497D01*
X385193Y-236364D01*
X386193Y-236631D01*
X386893Y-237297D01*
X387093Y-238097D01*
X386993Y-238898D01*
X386593Y-239564D01*
X384593Y-240897D01*
X383693Y-241831D01*
X383093Y-243164D01*
X382893Y-244364D01*
X387093D01*
G01X391193Y-244631D02*
X394793Y-236364D01*
G01X400993Y-244364D02*
Y-236364D01*
X399793Y-237964D01*
G01Y-244364D02*
X402193D01*
G01X408993Y-236364D02*
X408193Y-236631D01*
X407593Y-237297D01*
X407193Y-238097D01*
X406893Y-239164D01*
X406793Y-240364D01*
X406893Y-241564D01*
X407193Y-242631D01*
X407593Y-243431D01*
X408193Y-244097D01*
X408993Y-244364D01*
X409793Y-244097D01*
X410393Y-243431D01*
X410793Y-242631D01*
X411093Y-241564D01*
X411193Y-240364D01*
X411093Y-239164D01*
X410793Y-238097D01*
X410393Y-237297D01*
X409793Y-236631D01*
X408993Y-236364D01*
G01X415193Y-244631D02*
X418793Y-236364D01*
G01X422793Y-242764D02*
X423393Y-243697D01*
X424193Y-244231D01*
X425093Y-244364D01*
X425893Y-244231D01*
X426693Y-243564D01*
X427193Y-242764D01*
X427293Y-241964D01*
X427093Y-241031D01*
X426393Y-240364D01*
X425693Y-240097D01*
X424793D01*
G01X425693D02*
X426293Y-239697D01*
X426793Y-239031D01*
X426993Y-238231D01*
X426793Y-237431D01*
X426293Y-236764D01*
X425393Y-236364D01*
X424493Y-236497D01*
X423593Y-237031D01*
G01X432993Y-244364D02*
Y-236364D01*
X431793Y-237964D01*
G01Y-244364D02*
X434193D01*
G01X358793Y-219364D02*
Y-211364D01*
X360793D01*
X361593Y-211764D01*
X362193Y-212297D01*
X362693Y-213097D01*
X363093Y-214031D01*
X363193Y-215364D01*
X363093Y-216697D01*
X362693Y-217631D01*
X362193Y-218431D01*
X361593Y-218964D01*
X360793Y-219364D01*
X358793D01*
G01X366493D02*
X368993Y-211364D01*
X371493Y-219364D01*
G01X370593Y-216564D02*
X367393D01*
G01X376993Y-211364D02*
Y-219364D01*
G01X374693Y-211364D02*
X379293D01*
G01X383093Y-216031D02*
X383793Y-215097D01*
X384393Y-214564D01*
X385193Y-214297D01*
X385893Y-214564D01*
X386393Y-215097D01*
X386793Y-215897D01*
X386893Y-216831D01*
X386793Y-217631D01*
X386393Y-218431D01*
X385793Y-219097D01*
X385093Y-219364D01*
X384293Y-219097D01*
X383593Y-218298D01*
X383193Y-217097D01*
X383093Y-215764D01*
X383293Y-214031D01*
X383593Y-213097D01*
X384093Y-212164D01*
X384793Y-211497D01*
X385493Y-211364D01*
X386193Y-211631D01*
X386693Y-212297D01*
G01X390393Y-219364D02*
Y-211364D01*
X392993Y-218031D01*
X395593Y-211364D01*
Y-219364D01*
G01X400993Y-211364D02*
Y-219364D01*
G01X398693Y-211364D02*
X403293D01*
G01X406893Y-219364D02*
Y-211364D01*
G01X411093D02*
Y-219364D01*
G01Y-215364D02*
X406893D01*
G01X414793Y-217764D02*
X415393Y-218697D01*
X416193Y-219231D01*
X417093Y-219364D01*
X417893Y-219231D01*
X418693Y-218564D01*
X419193Y-217764D01*
X419293Y-216964D01*
X419093Y-216031D01*
X418393Y-215364D01*
X417693Y-215097D01*
X416793D01*
G01X417693D02*
X418293Y-214697D01*
X418793Y-214031D01*
X418993Y-213231D01*
X418793Y-212431D01*
X418293Y-211764D01*
X417393Y-211364D01*
X416493Y-211497D01*
X415593Y-212031D01*
G01X422493Y-219364D02*
X424993Y-211364D01*
X427493Y-219364D01*
G01X426593Y-216564D02*
X423393D01*
G01X430793Y-219364D02*
Y-211364D01*
X432793D01*
X433593Y-211764D01*
X434193Y-212297D01*
X434693Y-213097D01*
X435093Y-214031D01*
X435193Y-215364D01*
X435093Y-216697D01*
X434693Y-217631D01*
X434193Y-218431D01*
X433593Y-218964D01*
X432793Y-219364D01*
X430793D01*
G01X440993Y-211364D02*
X440193Y-211631D01*
X439593Y-212297D01*
X439193Y-213097D01*
X438893Y-214164D01*
X438793Y-215364D01*
X438893Y-216564D01*
X439193Y-217631D01*
X439593Y-218431D01*
X440193Y-219097D01*
X440993Y-219364D01*
X441793Y-219097D01*
X442393Y-218431D01*
X442793Y-217631D01*
X443093Y-216564D01*
X443193Y-215364D01*
X443093Y-214164D01*
X442793Y-213097D01*
X442393Y-212297D01*
X441793Y-211631D01*
X440993Y-211364D01*
G01X357553Y9226D02*
Y12326D01*
X358512D01*
X358818Y12171D01*
X359010Y11964D01*
X359087Y11551D01*
X359010Y11138D01*
X358780Y10879D01*
X358512Y10724D01*
X357553D01*
G01X358512D02*
X359087Y9226D01*
G01X361420D02*
Y12326D01*
X360960Y11706D01*
G01Y9226D02*
X361880D01*
G01X364443D02*
X364520Y9898D01*
X364635Y10466D01*
X364788Y10983D01*
X364980Y11551D01*
X365287Y12326D01*
X363753D01*
G01X366968Y9588D02*
X367237Y9329D01*
X367543Y9226D01*
X367850Y9329D01*
X368118Y9639D01*
X368310Y10104D01*
X368387Y10569D01*
Y11138D01*
X368310Y11603D01*
X368118Y12016D01*
X367888Y12223D01*
X367620Y12326D01*
X367313Y12223D01*
X367083Y12016D01*
X366930Y11706D01*
X366853Y11293D01*
X366930Y10931D01*
X367122Y10569D01*
X367352Y10363D01*
X367620Y10311D01*
X367927Y10414D01*
X368157Y10673D01*
X368387Y11138D01*
G01X367700Y14121D02*
X361500D01*
G01D02*
Y17321D01*
G01D02*
X367700D01*
G01D02*
Y14121D01*
G01X363633Y26152D02*
X360833D01*
G01X371485D02*
X368683D01*
G01X357340Y59122D02*
Y65322D01*
X360540D01*
Y59122D01*
X357340D01*
G01X368453Y59298D02*
Y65498D01*
X371653D01*
Y59298D01*
X368453D01*
G01X356474Y55194D02*
X353374D01*
Y56153D01*
X353529Y56459D01*
X353736Y56651D01*
X354149Y56728D01*
X354562Y56651D01*
X354821Y56421D01*
X354976Y56153D01*
Y55194D01*
G01Y56153D02*
X356474Y56728D01*
G01Y59061D02*
X353374D01*
X353994Y58601D01*
G01X356474D02*
Y59521D01*
G01X356112Y61509D02*
X356371Y61778D01*
X356474Y62084D01*
X356371Y62391D01*
X356061Y62659D01*
X355596Y62851D01*
X355131Y62928D01*
X354562D01*
X354097Y62851D01*
X353684Y62659D01*
X353477Y62429D01*
X353374Y62161D01*
X353477Y61854D01*
X353684Y61624D01*
X353994Y61471D01*
X354407Y61394D01*
X354769Y61471D01*
X355131Y61663D01*
X355337Y61893D01*
X355389Y62161D01*
X355286Y62468D01*
X355027Y62698D01*
X354562Y62928D01*
G01X356474Y65721D02*
X353374D01*
X355596Y64303D01*
Y66219D01*
G01X362253Y54158D02*
X362445Y53848D01*
X362675Y53641D01*
X362943Y53538D01*
X363250Y53641D01*
X363480Y53848D01*
X363710Y54158D01*
X363787Y54571D01*
Y56638D01*
G01X366120Y53538D02*
Y56638D01*
X365660Y56018D01*
G01Y53538D02*
X366580D01*
G01X360883Y50956D02*
X363633D01*
G01X368683D02*
X371533D01*
G01X357253Y70905D02*
Y67705D01*
G01X361373Y66271D02*
X358273D01*
Y67230D01*
X358428Y67536D01*
X358635Y67728D01*
X359048Y67805D01*
X359461Y67728D01*
X359720Y67498D01*
X359875Y67230D01*
Y66271D01*
G01Y67230D02*
X361373Y67805D01*
G01Y70138D02*
X358273D01*
X358893Y69678D01*
G01X361373D02*
Y70598D01*
G01Y73238D02*
X361321Y73506D01*
X361166Y73813D01*
X360908Y74005D01*
X360546Y74081D01*
X360185Y74005D01*
X359875Y73775D01*
X359720Y73430D01*
Y73046D01*
X359616Y72816D01*
X359358Y72625D01*
X358996Y72548D01*
X358635Y72663D01*
X358376Y72931D01*
X358273Y73238D01*
X358376Y73545D01*
X358635Y73813D01*
X358996Y73928D01*
X359358Y73851D01*
X359616Y73660D01*
X359720Y73430D01*
Y73046D01*
X359875Y72701D01*
X360185Y72471D01*
X360546Y72395D01*
X360908Y72471D01*
X361166Y72663D01*
X361321Y72970D01*
X361373Y73238D01*
G01X361011Y75686D02*
X361270Y75955D01*
X361373Y76261D01*
X361270Y76568D01*
X360960Y76836D01*
X360495Y77028D01*
X360030Y77105D01*
X359461D01*
X358996Y77028D01*
X358583Y76836D01*
X358376Y76606D01*
X358273Y76338D01*
X358376Y76031D01*
X358583Y75801D01*
X358893Y75648D01*
X359306Y75571D01*
X359668Y75648D01*
X360030Y75840D01*
X360236Y76070D01*
X360288Y76338D01*
X360185Y76645D01*
X359926Y76875D01*
X359461Y77105D01*
G01X366756Y61799D02*
X363656D01*
Y62758D01*
X363811Y63064D01*
X364018Y63256D01*
X364431Y63333D01*
X364844Y63256D01*
X365103Y63026D01*
X365258Y62758D01*
Y61799D01*
G01Y62758D02*
X366756Y63333D01*
G01Y65666D02*
X363656D01*
X364276Y65206D01*
G01X366756D02*
Y66126D01*
G01X366394Y68114D02*
X366653Y68383D01*
X366756Y68689D01*
X366653Y68996D01*
X366343Y69264D01*
X365878Y69456D01*
X365413Y69533D01*
X364844D01*
X364379Y69456D01*
X363966Y69264D01*
X363759Y69034D01*
X363656Y68766D01*
X363759Y68459D01*
X363966Y68229D01*
X364276Y68076D01*
X364689Y67999D01*
X365051Y68076D01*
X365413Y68268D01*
X365619Y68498D01*
X365671Y68766D01*
X365568Y69073D01*
X365309Y69303D01*
X364844Y69533D01*
G01X364173Y71138D02*
X363863Y71368D01*
X363708Y71636D01*
X363656Y71943D01*
X363759Y72326D01*
X364018Y72594D01*
X364328Y72671D01*
X364638Y72633D01*
X364896Y72479D01*
X365413Y71713D01*
X365774Y71368D01*
X366291Y71138D01*
X366756Y71061D01*
Y72671D01*
G01X358427Y164646D02*
X355327D01*
Y165605D01*
X355482Y165911D01*
X355689Y166103D01*
X356102Y166180D01*
X356515Y166103D01*
X356774Y165873D01*
X356929Y165605D01*
Y164646D01*
G01Y165605D02*
X358427Y166180D01*
G01X357962Y167670D02*
X358220Y167900D01*
X358375Y168168D01*
X358427Y168513D01*
X358324Y168858D01*
X358117Y169126D01*
X357755Y169318D01*
X357342Y169356D01*
X356929Y169280D01*
X356670Y169088D01*
X356464Y168820D01*
X356412Y168551D01*
X356464Y168283D01*
X356670Y167938D01*
X355327Y168053D01*
Y169088D01*
G01X358427Y171536D02*
X357755Y171613D01*
X357187Y171728D01*
X356670Y171881D01*
X356102Y172073D01*
X355327Y172380D01*
Y170846D01*
G01X362318Y164646D02*
X359218D01*
Y165605D01*
X359373Y165911D01*
X359580Y166103D01*
X359993Y166180D01*
X360406Y166103D01*
X360665Y165873D01*
X360820Y165605D01*
Y164646D01*
G01Y165605D02*
X362318Y166180D01*
G01Y168513D02*
X359218D01*
X359838Y168053D01*
G01X362318D02*
Y168973D01*
G01X359218Y171613D02*
X359321Y171306D01*
X359580Y171076D01*
X359890Y170923D01*
X360303Y170808D01*
X360768Y170770D01*
X361233Y170808D01*
X361646Y170923D01*
X361956Y171076D01*
X362215Y171306D01*
X362318Y171613D01*
X362215Y171920D01*
X361956Y172150D01*
X361646Y172303D01*
X361233Y172418D01*
X360768Y172456D01*
X360303Y172418D01*
X359890Y172303D01*
X359580Y172150D01*
X359321Y171920D01*
X359218Y171613D01*
G01X362318Y175173D02*
X359218D01*
X361440Y173755D01*
Y175671D01*
G01X366318Y164646D02*
X363218D01*
Y165605D01*
X363373Y165911D01*
X363580Y166103D01*
X363993Y166180D01*
X364406Y166103D01*
X364665Y165873D01*
X364820Y165605D01*
Y164646D01*
G01Y165605D02*
X366318Y166180D01*
G01X365853Y167670D02*
X366111Y167900D01*
X366266Y168168D01*
X366318Y168513D01*
X366215Y168858D01*
X366008Y169126D01*
X365646Y169318D01*
X365233Y169356D01*
X364820Y169280D01*
X364561Y169088D01*
X364355Y168820D01*
X364303Y168551D01*
X364355Y168283D01*
X364561Y167938D01*
X363218Y168053D01*
Y169088D01*
G01X366318Y171613D02*
X366266Y171881D01*
X366111Y172188D01*
X365853Y172380D01*
X365491Y172456D01*
X365130Y172380D01*
X364820Y172150D01*
X364665Y171805D01*
Y171421D01*
X364561Y171191D01*
X364303Y171000D01*
X363941Y170923D01*
X363580Y171038D01*
X363321Y171306D01*
X363218Y171613D01*
X363321Y171920D01*
X363580Y172188D01*
X363941Y172303D01*
X364303Y172226D01*
X364561Y172035D01*
X364665Y171805D01*
Y171421D01*
X364820Y171076D01*
X365130Y170846D01*
X365491Y170770D01*
X365853Y170846D01*
X366111Y171038D01*
X366266Y171345D01*
X366318Y171613D01*
G01X370090Y164646D02*
X366990D01*
Y165605D01*
X367145Y165911D01*
X367352Y166103D01*
X367765Y166180D01*
X368178Y166103D01*
X368437Y165873D01*
X368592Y165605D01*
Y164646D01*
G01Y165605D02*
X370090Y166180D01*
G01X368798Y167785D02*
X368437Y168053D01*
X368230Y168283D01*
X368127Y168590D01*
X368230Y168858D01*
X368437Y169050D01*
X368747Y169203D01*
X369108Y169241D01*
X369418Y169203D01*
X369728Y169050D01*
X369987Y168820D01*
X370090Y168551D01*
X369987Y168245D01*
X369677Y167976D01*
X369212Y167823D01*
X368695Y167785D01*
X368023Y167861D01*
X367662Y167976D01*
X367300Y168168D01*
X367042Y168436D01*
X366990Y168705D01*
X367093Y168973D01*
X367352Y169165D01*
G01X370090Y171613D02*
X370038Y171881D01*
X369883Y172188D01*
X369625Y172380D01*
X369263Y172456D01*
X368902Y172380D01*
X368592Y172150D01*
X368437Y171805D01*
Y171421D01*
X368333Y171191D01*
X368075Y171000D01*
X367713Y170923D01*
X367352Y171038D01*
X367093Y171306D01*
X366990Y171613D01*
X367093Y171920D01*
X367352Y172188D01*
X367713Y172303D01*
X368075Y172226D01*
X368333Y172035D01*
X368437Y171805D01*
Y171421D01*
X368592Y171076D01*
X368902Y170846D01*
X369263Y170770D01*
X369625Y170846D01*
X369883Y171038D01*
X370038Y171345D01*
X370090Y171613D01*
G01X358832Y179598D02*
X358602Y179753D01*
X358334Y179856D01*
X358027D01*
X357682Y179701D01*
X357414Y179443D01*
X357222Y179133D01*
X357069Y178616D01*
X357031Y178151D01*
X357107Y177686D01*
X357222Y177376D01*
X357452Y177066D01*
X357721Y176859D01*
X357989Y176756D01*
X358257D01*
X358526Y176859D01*
X358756Y177014D01*
X358947Y177221D01*
G01X361089Y176756D02*
X361357Y176808D01*
X361664Y176963D01*
X361856Y177221D01*
X361932Y177583D01*
X361856Y177944D01*
X361626Y178254D01*
X361281Y178409D01*
X360897D01*
X360667Y178513D01*
X360476Y178771D01*
X360399Y179133D01*
X360514Y179494D01*
X360782Y179753D01*
X361089Y179856D01*
X361396Y179753D01*
X361664Y179494D01*
X361779Y179133D01*
X361702Y178771D01*
X361511Y178513D01*
X361281Y178409D01*
X360897D01*
X360552Y178254D01*
X360322Y177944D01*
X360246Y177583D01*
X360322Y177221D01*
X360514Y176963D01*
X360821Y176808D01*
X361089Y176756D01*
G01X363461Y179339D02*
X363691Y179649D01*
X363959Y179804D01*
X364266Y179856D01*
X364649Y179753D01*
X364917Y179494D01*
X364994Y179184D01*
X364956Y178874D01*
X364802Y178616D01*
X364036Y178099D01*
X363691Y177738D01*
X363461Y177221D01*
X363384Y176756D01*
X364994D01*
G01X366446Y177221D02*
X366676Y176963D01*
X366944Y176808D01*
X367289Y176756D01*
X367634Y176859D01*
X367902Y177066D01*
X368094Y177428D01*
X368132Y177841D01*
X368056Y178254D01*
X367864Y178513D01*
X367596Y178719D01*
X367327Y178771D01*
X367059Y178719D01*
X366714Y178513D01*
X366829Y179856D01*
X367864D01*
G01X360712Y236091D02*
Y239191D01*
G01X362322D02*
Y236091D01*
G01Y237641D02*
X360712D01*
G01X365077Y236091D02*
Y239191D01*
X363659Y236969D01*
X365575D01*
G01X358473Y300369D02*
X358243Y300524D01*
X357975Y300627D01*
X357668D01*
X357323Y300472D01*
X357055Y300214D01*
X356863Y299904D01*
X356710Y299387D01*
X356672Y298922D01*
X356748Y298457D01*
X356863Y298147D01*
X357093Y297837D01*
X357362Y297630D01*
X357630Y297527D01*
X357898D01*
X358167Y297630D01*
X358397Y297785D01*
X358588Y297992D01*
G01X360002Y298819D02*
X360270Y299180D01*
X360500Y299387D01*
X360807Y299490D01*
X361075Y299387D01*
X361267Y299180D01*
X361420Y298870D01*
X361458Y298509D01*
X361420Y298199D01*
X361267Y297889D01*
X361037Y297630D01*
X360768Y297527D01*
X360462Y297630D01*
X360193Y297940D01*
X360040Y298405D01*
X360002Y298922D01*
X360078Y299594D01*
X360193Y299955D01*
X360385Y300317D01*
X360653Y300575D01*
X360922Y300627D01*
X361190Y300524D01*
X361382Y300265D01*
G01X363830Y297527D02*
Y300627D01*
X363370Y300007D01*
G01Y297527D02*
X364290D01*
G01X358663Y305469D02*
X358433Y305624D01*
X358165Y305727D01*
X357858D01*
X357513Y305572D01*
X357245Y305314D01*
X357053Y305004D01*
X356900Y304487D01*
X356862Y304022D01*
X356938Y303557D01*
X357053Y303247D01*
X357283Y302937D01*
X357552Y302730D01*
X357820Y302627D01*
X358088D01*
X358357Y302730D01*
X358587Y302885D01*
X358778Y303092D01*
G01X360192Y303919D02*
X360460Y304280D01*
X360690Y304487D01*
X360997Y304590D01*
X361265Y304487D01*
X361457Y304280D01*
X361610Y303970D01*
X361648Y303609D01*
X361610Y303299D01*
X361457Y302989D01*
X361227Y302730D01*
X360958Y302627D01*
X360652Y302730D01*
X360383Y303040D01*
X360230Y303505D01*
X360192Y304022D01*
X360268Y304694D01*
X360383Y305055D01*
X360575Y305417D01*
X360843Y305675D01*
X361112Y305727D01*
X361380Y305624D01*
X361572Y305365D01*
G01X364020Y305727D02*
X363713Y305624D01*
X363483Y305365D01*
X363330Y305055D01*
X363215Y304642D01*
X363177Y304177D01*
X363215Y303712D01*
X363330Y303299D01*
X363483Y302989D01*
X363713Y302730D01*
X364020Y302627D01*
X364327Y302730D01*
X364557Y302989D01*
X364710Y303299D01*
X364825Y303712D01*
X364863Y304177D01*
X364825Y304642D01*
X364710Y305055D01*
X364557Y305365D01*
X364327Y305624D01*
X364020Y305727D01*
G01X355383Y314307D02*
Y311207D01*
X356917D01*
G01X358522Y312499D02*
X358790Y312860D01*
X359020Y313067D01*
X359327Y313170D01*
X359595Y313067D01*
X359787Y312860D01*
X359940Y312550D01*
X359978Y312189D01*
X359940Y311879D01*
X359787Y311569D01*
X359557Y311310D01*
X359288Y311207D01*
X358982Y311310D01*
X358713Y311620D01*
X358560Y312085D01*
X358522Y312602D01*
X358598Y313274D01*
X358713Y313635D01*
X358905Y313997D01*
X359173Y314255D01*
X359442Y314307D01*
X359710Y314204D01*
X359902Y313945D01*
G01X355893Y309577D02*
Y306477D01*
X357427D01*
G01X360220D02*
Y309577D01*
X358802Y307355D01*
X360718D01*
G01X355670Y334576D02*
Y327776D01*
G01X362519Y324755D02*
X359419D01*
Y325714D01*
X359574Y326020D01*
X359781Y326212D01*
X360194Y326289D01*
X360607Y326212D01*
X360866Y325982D01*
X361021Y325714D01*
Y324755D01*
G01Y325714D02*
X362519Y326289D01*
G01Y328622D02*
X359419D01*
X360039Y328162D01*
G01X362519D02*
Y329082D01*
G01X359936Y330994D02*
X359626Y331224D01*
X359471Y331492D01*
X359419Y331799D01*
X359522Y332182D01*
X359781Y332450D01*
X360091Y332527D01*
X360401Y332489D01*
X360659Y332335D01*
X361176Y331569D01*
X361537Y331224D01*
X362054Y330994D01*
X362519Y330917D01*
Y332527D01*
G01Y334822D02*
X359419D01*
X360039Y334362D01*
G01X362519D02*
Y335282D01*
G01X362054Y337079D02*
X362312Y337309D01*
X362467Y337577D01*
X362519Y337922D01*
X362416Y338267D01*
X362209Y338535D01*
X361847Y338727D01*
X361434Y338765D01*
X361021Y338689D01*
X360762Y338497D01*
X360556Y338229D01*
X360504Y337960D01*
X360556Y337692D01*
X360762Y337347D01*
X359419Y337462D01*
Y338497D01*
G01X366626Y331148D02*
Y324948D01*
G01D02*
X363426D01*
G01D02*
Y331148D01*
G01X367634Y324449D02*
Y336923D01*
G01X379714Y324449D02*
X367634D01*
G01X364418Y344235D02*
Y347335D01*
G01X366028D02*
Y344235D01*
G01Y345785D02*
X364418D01*
G01X367595Y346818D02*
X367825Y347128D01*
X368093Y347283D01*
X368400Y347335D01*
X368783Y347232D01*
X369051Y346973D01*
X369128Y346663D01*
X369090Y346353D01*
X368936Y346095D01*
X368170Y345578D01*
X367825Y345217D01*
X367595Y344700D01*
X367518Y344235D01*
X369128D01*
G01X363426Y331148D02*
X366626D01*
G01X366924Y338061D02*
X366764Y338186D01*
X366577Y338269D01*
X366364D01*
X366124Y338144D01*
X365937Y337936D01*
X365804Y337686D01*
X365697Y337269D01*
X365670Y336894D01*
X365724Y336519D01*
X365804Y336269D01*
X365964Y336019D01*
X366150Y335852D01*
X366337Y335769D01*
X366524D01*
X366710Y335852D01*
X366870Y335977D01*
X367004Y336144D01*
G01X367634Y336923D02*
X379714D01*
G01X368997Y364480D02*
Y367580D01*
X369956D01*
X370262Y367425D01*
X370454Y367218D01*
X370531Y366805D01*
X370454Y366392D01*
X370224Y366133D01*
X369956Y365978D01*
X368997D01*
G01X369956D02*
X370531Y364480D01*
G01X372864D02*
Y367580D01*
X372404Y366960D01*
G01Y364480D02*
X373324D01*
G01X375887D02*
X375964Y365152D01*
X376079Y365720D01*
X376232Y366237D01*
X376424Y366805D01*
X376731Y367580D01*
X375197D01*
G01X379064Y364480D02*
X379332Y364532D01*
X379639Y364687D01*
X379831Y364945D01*
X379907Y365307D01*
X379831Y365668D01*
X379601Y365978D01*
X379256Y366133D01*
X378872D01*
X378642Y366237D01*
X378451Y366495D01*
X378374Y366857D01*
X378489Y367218D01*
X378757Y367477D01*
X379064Y367580D01*
X379371Y367477D01*
X379639Y367218D01*
X379754Y366857D01*
X379677Y366495D01*
X379486Y366237D01*
X379256Y366133D01*
X378872D01*
X378527Y365978D01*
X378297Y365668D01*
X378221Y365307D01*
X378297Y364945D01*
X378489Y364687D01*
X378796Y364532D01*
X379064Y364480D01*
G01X367218Y372108D02*
X373418D01*
G01Y368908D02*
X367218D01*
G01D02*
Y372108D01*
G01X365170Y405872D02*
Y385400D01*
G01X355707Y426160D02*
Y422960D01*
G01X364442Y431821D02*
Y425138D01*
X364421D01*
X362228Y427331D01*
X362249Y427352D01*
X367077D01*
X364842Y425117D01*
X364505D01*
G01X359578Y456077D02*
X359808Y456387D01*
X360076Y456542D01*
X360383Y456594D01*
X360766Y456491D01*
X361034Y456232D01*
X361111Y455922D01*
X361073Y455612D01*
X360919Y455354D01*
X360153Y454837D01*
X359808Y454476D01*
X359578Y453959D01*
X359501Y453494D01*
X361111D01*
G01X363866D02*
Y456594D01*
X362448Y454372D01*
X364364D01*
G01X359810Y444819D02*
X356610D01*
G01X359810Y451019D02*
Y444819D01*
G01X356610Y451019D02*
X359810D01*
G01X356610Y444819D02*
Y451019D01*
G01X366092Y459242D02*
X366322Y459552D01*
X366590Y459707D01*
X366897Y459759D01*
X367280Y459656D01*
X367548Y459397D01*
X367625Y459087D01*
X367587Y458777D01*
X367433Y458519D01*
X366667Y458002D01*
X366322Y457641D01*
X366092Y457124D01*
X366015Y456659D01*
X367625D01*
G01X369077Y457124D02*
X369307Y456866D01*
X369575Y456711D01*
X369920Y456659D01*
X370265Y456762D01*
X370533Y456969D01*
X370725Y457331D01*
X370763Y457744D01*
X370687Y458157D01*
X370495Y458416D01*
X370227Y458622D01*
X369958Y458674D01*
X369690Y458622D01*
X369345Y458416D01*
X369460Y459759D01*
X370495D01*
G01X360415Y462451D02*
Y489451D01*
G01X367315Y465124D02*
X370115D01*
G01X369843Y486447D02*
X370205Y486677D01*
X370411Y486983D01*
X370463Y487328D01*
X370411Y487635D01*
X370153Y487942D01*
X369843Y488133D01*
X369533Y488172D01*
X369171Y488095D01*
X368913Y487827D01*
X368810Y487558D01*
Y487213D01*
G01Y487558D02*
X368655Y487788D01*
X368396Y487980D01*
X368086Y488057D01*
X367776Y487980D01*
X367518Y487788D01*
X367363Y487443D01*
X367415Y487098D01*
X367621Y486753D01*
G01X369171Y489662D02*
X368810Y489930D01*
X368603Y490160D01*
X368500Y490467D01*
X368603Y490735D01*
X368810Y490927D01*
X369120Y491080D01*
X369481Y491118D01*
X369791Y491080D01*
X370101Y490927D01*
X370360Y490697D01*
X370463Y490428D01*
X370360Y490122D01*
X370050Y489853D01*
X369585Y489700D01*
X369068Y489662D01*
X368396Y489738D01*
X368035Y489853D01*
X367673Y490045D01*
X367415Y490313D01*
X367363Y490582D01*
X367466Y490850D01*
X367725Y491042D01*
G01X367315Y474967D02*
X371815D01*
G01X367415Y484809D02*
X370215D01*
G01X363983Y491107D02*
X364345Y491337D01*
X364551Y491643D01*
X364603Y491988D01*
X364551Y492295D01*
X364293Y492602D01*
X363983Y492793D01*
X363673Y492832D01*
X363311Y492755D01*
X363053Y492487D01*
X362950Y492218D01*
Y491873D01*
G01Y492218D02*
X362795Y492448D01*
X362536Y492640D01*
X362226Y492717D01*
X361916Y492640D01*
X361658Y492448D01*
X361503Y492103D01*
X361555Y491758D01*
X361761Y491413D01*
G01X364603Y494973D02*
X363931Y495050D01*
X363363Y495165D01*
X362846Y495318D01*
X362278Y495510D01*
X361503Y495817D01*
Y494283D01*
G01X367302Y496245D02*
X367147Y496015D01*
X367044Y495747D01*
Y495440D01*
X367199Y495095D01*
X367457Y494827D01*
X367767Y494635D01*
X368284Y494482D01*
X368749Y494444D01*
X369214Y494520D01*
X369524Y494635D01*
X369834Y494865D01*
X370041Y495134D01*
X370144Y495402D01*
Y495670D01*
X370041Y495939D01*
X369886Y496169D01*
X369679Y496360D01*
G01X370144Y498502D02*
X370092Y498770D01*
X369937Y499077D01*
X369679Y499269D01*
X369317Y499345D01*
X368956Y499269D01*
X368646Y499039D01*
X368491Y498694D01*
Y498310D01*
X368387Y498080D01*
X368129Y497889D01*
X367767Y497812D01*
X367406Y497927D01*
X367147Y498195D01*
X367044Y498502D01*
X367147Y498809D01*
X367406Y499077D01*
X367767Y499192D01*
X368129Y499115D01*
X368387Y498924D01*
X368491Y498694D01*
Y498310D01*
X368646Y497965D01*
X368956Y497735D01*
X369317Y497659D01*
X369679Y497735D01*
X369937Y497927D01*
X370092Y498234D01*
X370144Y498502D01*
G01Y501602D02*
X367044D01*
X367664Y501142D01*
G01X370144D02*
Y502062D01*
G01Y504702D02*
X367044D01*
X367664Y504242D01*
G01X370144D02*
Y505162D01*
G01X357994Y497385D02*
X354894D01*
Y498344D01*
X355049Y498650D01*
X355256Y498842D01*
X355669Y498919D01*
X356082Y498842D01*
X356341Y498612D01*
X356496Y498344D01*
Y497385D01*
G01Y498344D02*
X357994Y498919D01*
G01Y501252D02*
X354894D01*
X355514Y500792D01*
G01X357994D02*
Y501712D01*
G01X355411Y503624D02*
X355101Y503854D01*
X354946Y504122D01*
X354894Y504429D01*
X354997Y504812D01*
X355256Y505080D01*
X355566Y505157D01*
X355876Y505119D01*
X356134Y504965D01*
X356651Y504199D01*
X357012Y503854D01*
X357529Y503624D01*
X357994Y503547D01*
Y505157D01*
G01X357529Y506609D02*
X357787Y506839D01*
X357942Y507107D01*
X357994Y507452D01*
X357891Y507797D01*
X357684Y508065D01*
X357322Y508257D01*
X356909Y508295D01*
X356496Y508219D01*
X356237Y508027D01*
X356031Y507759D01*
X355979Y507490D01*
X356031Y507222D01*
X356237Y506877D01*
X354894Y506992D01*
Y508027D01*
G01X356702Y509824D02*
X356341Y510092D01*
X356134Y510322D01*
X356031Y510629D01*
X356134Y510897D01*
X356341Y511089D01*
X356651Y511242D01*
X357012Y511280D01*
X357322Y511242D01*
X357632Y511089D01*
X357891Y510859D01*
X357994Y510590D01*
X357891Y510284D01*
X357581Y510015D01*
X357116Y509862D01*
X356599Y509824D01*
X355927Y509900D01*
X355566Y510015D01*
X355204Y510207D01*
X354946Y510475D01*
X354894Y510744D01*
X354997Y511012D01*
X355256Y511204D01*
G01X362144Y497087D02*
X359044D01*
Y498046D01*
X359199Y498352D01*
X359406Y498544D01*
X359819Y498621D01*
X360232Y498544D01*
X360491Y498314D01*
X360646Y498046D01*
Y497087D01*
G01Y498046D02*
X362144Y498621D01*
G01Y500954D02*
X359044D01*
X359664Y500494D01*
G01X362144D02*
Y501414D01*
G01X359561Y503326D02*
X359251Y503556D01*
X359096Y503824D01*
X359044Y504131D01*
X359147Y504514D01*
X359406Y504782D01*
X359716Y504859D01*
X360026Y504821D01*
X360284Y504667D01*
X360801Y503901D01*
X361162Y503556D01*
X361679Y503326D01*
X362144Y503249D01*
Y504859D01*
G01X361679Y506311D02*
X361937Y506541D01*
X362092Y506809D01*
X362144Y507154D01*
X362041Y507499D01*
X361834Y507767D01*
X361472Y507959D01*
X361059Y507997D01*
X360646Y507921D01*
X360387Y507729D01*
X360181Y507461D01*
X360129Y507192D01*
X360181Y506924D01*
X360387Y506579D01*
X359044Y506694D01*
Y507729D01*
G01X361782Y509602D02*
X362041Y509871D01*
X362144Y510177D01*
X362041Y510484D01*
X361731Y510752D01*
X361266Y510944D01*
X360801Y511021D01*
X360232D01*
X359767Y510944D01*
X359354Y510752D01*
X359147Y510522D01*
X359044Y510254D01*
X359147Y509947D01*
X359354Y509717D01*
X359664Y509564D01*
X360077Y509487D01*
X360439Y509564D01*
X360801Y509756D01*
X361007Y509986D01*
X361059Y510254D01*
X360956Y510561D01*
X360697Y510791D01*
X360232Y511021D01*
G01X367343Y513998D02*
X370543D01*
G01X370443Y510898D02*
X367443D01*
G01X367343Y507798D02*
Y513998D01*
G01X370543Y507798D02*
X367343D01*
G01X356382Y517461D02*
Y519261D01*
G01X358715Y512209D02*
Y511213D01*
G01X361810Y514861D02*
G02I-1628J0D01*
G01X362382Y517461D02*
Y519261D01*
G01X357982Y517461D02*
Y519261D01*
G01X362382Y517461D02*
X357982D01*
G01X365994Y507166D02*
X362894D01*
Y508125D01*
X363049Y508431D01*
X363256Y508623D01*
X363669Y508700D01*
X364082Y508623D01*
X364341Y508393D01*
X364496Y508125D01*
Y507166D01*
G01Y508125D02*
X365994Y508700D01*
G01Y511033D02*
X362894D01*
X363514Y510573D01*
G01X365994D02*
Y511493D01*
G01Y514133D02*
X362894D01*
X363514Y513673D01*
G01X365994D02*
Y514593D01*
G01X362894Y517233D02*
X362997Y516926D01*
X363256Y516696D01*
X363566Y516543D01*
X363979Y516428D01*
X364444Y516390D01*
X364909Y516428D01*
X365322Y516543D01*
X365632Y516696D01*
X365891Y516926D01*
X365994Y517233D01*
X365891Y517540D01*
X365632Y517770D01*
X365322Y517923D01*
X364909Y518038D01*
X364444Y518076D01*
X363979Y518038D01*
X363566Y517923D01*
X363256Y517770D01*
X362997Y517540D01*
X362894Y517233D01*
G01X365994Y520793D02*
X362894D01*
X365116Y519375D01*
Y521291D01*
G01X366638Y514853D02*
Y521053D01*
G01X369838Y514853D02*
X366638D01*
G01X360273Y530291D02*
X360400Y531374D01*
X360590Y532291D01*
X360843Y533124D01*
X361160Y534041D01*
X361667Y535291D01*
X359133D01*
G01X356382Y529661D02*
Y519261D01*
G01X357982Y518061D02*
X362382D01*
G01Y518661D02*
X357982D01*
G01Y529661D02*
X362382D01*
G01X357982Y519261D02*
Y529661D01*
G01X362382Y519261D02*
X357982D01*
G01X362382Y529661D02*
Y519261D01*
G01X366638Y521053D02*
X369838D01*
G01X362994Y529070D02*
X364786D01*
X365161Y529177D01*
X365411Y529390D01*
X365494Y529657D01*
X365411Y529924D01*
X365161Y530137D01*
X364786Y530244D01*
X362994D01*
G01X365494Y531857D02*
X362994D01*
X363494Y531537D01*
G01X365494D02*
Y532177D01*
G01Y534057D02*
X362994D01*
X363494Y533737D01*
G01X365494D02*
Y534377D01*
G01X365202Y535804D02*
X365411Y535990D01*
X365494Y536204D01*
X365411Y536417D01*
X365161Y536604D01*
X364786Y536737D01*
X364411Y536790D01*
X363952D01*
X363577Y536737D01*
X363244Y536604D01*
X363077Y536444D01*
X362994Y536257D01*
X363077Y536044D01*
X363244Y535884D01*
X363494Y535777D01*
X363827Y535724D01*
X364119Y535777D01*
X364411Y535910D01*
X364577Y536070D01*
X364619Y536257D01*
X364536Y536470D01*
X364327Y536630D01*
X363952Y536790D01*
G01X365362Y524459D02*
X365630Y524820D01*
X365860Y525027D01*
X366167Y525130D01*
X366435Y525027D01*
X366627Y524820D01*
X366780Y524510D01*
X366818Y524149D01*
X366780Y523839D01*
X366627Y523529D01*
X366397Y523270D01*
X366128Y523167D01*
X365822Y523270D01*
X365553Y523580D01*
X365400Y524045D01*
X365362Y524562D01*
X365438Y525234D01*
X365553Y525595D01*
X365745Y525957D01*
X366013Y526215D01*
X366282Y526267D01*
X366550Y526164D01*
X366742Y525905D01*
G01X363654Y548727D02*
X363499Y548497D01*
X363396Y548229D01*
Y547922D01*
X363551Y547577D01*
X363809Y547309D01*
X364119Y547117D01*
X364636Y546964D01*
X365101Y546926D01*
X365566Y547002D01*
X365876Y547117D01*
X366186Y547347D01*
X366393Y547616D01*
X366496Y547884D01*
Y548152D01*
X366393Y548421D01*
X366238Y548651D01*
X366031Y548842D01*
G01X366496Y550984D02*
X366444Y551252D01*
X366289Y551559D01*
X366031Y551751D01*
X365669Y551827D01*
X365308Y551751D01*
X364998Y551521D01*
X364843Y551176D01*
Y550792D01*
X364739Y550562D01*
X364481Y550371D01*
X364119Y550294D01*
X363758Y550409D01*
X363499Y550677D01*
X363396Y550984D01*
X363499Y551291D01*
X363758Y551559D01*
X364119Y551674D01*
X364481Y551597D01*
X364739Y551406D01*
X364843Y551176D01*
Y550792D01*
X364998Y550447D01*
X365308Y550217D01*
X365669Y550141D01*
X366031Y550217D01*
X366289Y550409D01*
X366444Y550716D01*
X366496Y550984D01*
G01Y554084D02*
X363396D01*
X364016Y553624D01*
G01X366496D02*
Y554544D01*
G01X365204Y556456D02*
X364843Y556724D01*
X364636Y556954D01*
X364533Y557261D01*
X364636Y557529D01*
X364843Y557721D01*
X365153Y557874D01*
X365514Y557912D01*
X365824Y557874D01*
X366134Y557721D01*
X366393Y557491D01*
X366496Y557222D01*
X366393Y556916D01*
X366083Y556647D01*
X365618Y556494D01*
X365101Y556456D01*
X364429Y556532D01*
X364068Y556647D01*
X363706Y556839D01*
X363448Y557107D01*
X363396Y557376D01*
X363499Y557644D01*
X363758Y557836D01*
G01X366933Y541661D02*
X363933D01*
G01X367033Y538561D02*
X363833D01*
G01X367033Y544761D02*
Y538561D01*
G01X363833Y544761D02*
X367033D01*
G01X363833Y538561D02*
Y544761D01*
G01X358583Y538722D02*
X355483D01*
Y539488D01*
X355638Y539795D01*
X355845Y540025D01*
X356155Y540217D01*
X356516Y540370D01*
X357033Y540408D01*
X357550Y540370D01*
X357911Y540217D01*
X358221Y540025D01*
X358428Y539795D01*
X358583Y539488D01*
Y538722D01*
G01X357963Y541822D02*
X358325Y542052D01*
X358531Y542358D01*
X358583Y542703D01*
X358531Y543010D01*
X358273Y543317D01*
X357963Y543508D01*
X357653Y543547D01*
X357291Y543470D01*
X357033Y543202D01*
X356930Y542933D01*
Y542588D01*
G01Y542933D02*
X356775Y543163D01*
X356516Y543355D01*
X356206Y543432D01*
X355896Y543355D01*
X355638Y543163D01*
X355483Y542818D01*
X355535Y542473D01*
X355741Y542128D01*
G01X358583Y545765D02*
X358531Y546033D01*
X358376Y546340D01*
X358118Y546532D01*
X357756Y546608D01*
X357395Y546532D01*
X357085Y546302D01*
X356930Y545957D01*
Y545573D01*
X356826Y545343D01*
X356568Y545152D01*
X356206Y545075D01*
X355845Y545190D01*
X355586Y545458D01*
X355483Y545765D01*
X355586Y546072D01*
X355845Y546340D01*
X356206Y546455D01*
X356568Y546378D01*
X356826Y546187D01*
X356930Y545957D01*
Y545573D01*
X357085Y545228D01*
X357395Y544998D01*
X357756Y544922D01*
X358118Y544998D01*
X358376Y545190D01*
X358531Y545497D01*
X358583Y545765D01*
G01X362496Y547117D02*
X359396D01*
Y548076D01*
X359551Y548382D01*
X359758Y548574D01*
X360171Y548651D01*
X360584Y548574D01*
X360843Y548344D01*
X360998Y548076D01*
Y547117D01*
G01Y548076D02*
X362496Y548651D01*
G01Y550984D02*
X359396D01*
X360016Y550524D01*
G01X362496D02*
Y551444D01*
G01X359396Y554084D02*
X359499Y553777D01*
X359758Y553547D01*
X360068Y553394D01*
X360481Y553279D01*
X360946Y553241D01*
X361411Y553279D01*
X361824Y553394D01*
X362134Y553547D01*
X362393Y553777D01*
X362496Y554084D01*
X362393Y554391D01*
X362134Y554621D01*
X361824Y554774D01*
X361411Y554889D01*
X360946Y554927D01*
X360481Y554889D01*
X360068Y554774D01*
X359758Y554621D01*
X359499Y554391D01*
X359396Y554084D01*
G01X362496Y557184D02*
X362444Y557452D01*
X362289Y557759D01*
X362031Y557951D01*
X361669Y558027D01*
X361308Y557951D01*
X360998Y557721D01*
X360843Y557376D01*
Y556992D01*
X360739Y556762D01*
X360481Y556571D01*
X360119Y556494D01*
X359758Y556609D01*
X359499Y556877D01*
X359396Y557184D01*
X359499Y557491D01*
X359758Y557759D01*
X360119Y557874D01*
X360481Y557797D01*
X360739Y557606D01*
X360843Y557376D01*
Y556992D01*
X360998Y556647D01*
X361308Y556417D01*
X361669Y556341D01*
X362031Y556417D01*
X362289Y556609D01*
X362444Y556916D01*
X362496Y557184D01*
G01Y560744D02*
X359396D01*
X361618Y559326D01*
Y561242D01*
G01X363033Y538561D02*
X359833D01*
G01X363033Y544761D02*
Y538561D01*
G01X359833Y544761D02*
X363033D01*
G01X359833Y538561D02*
Y544761D01*
G01X367959Y545067D02*
X374159D01*
G01X367959Y541867D02*
Y545067D01*
G01X374159Y541867D02*
X367959D01*
G01X367501Y558071D02*
Y561171D01*
X368460D01*
X368766Y561016D01*
X368958Y560809D01*
X369035Y560396D01*
X368958Y559983D01*
X368728Y559724D01*
X368460Y559569D01*
X367501D01*
G01X368460D02*
X369035Y558071D01*
G01X371368D02*
Y561171D01*
X370908Y560551D01*
G01Y558071D02*
X371828D01*
G01X374468Y561171D02*
X374161Y561068D01*
X373931Y560809D01*
X373778Y560499D01*
X373663Y560086D01*
X373625Y559621D01*
X373663Y559156D01*
X373778Y558743D01*
X373931Y558433D01*
X374161Y558174D01*
X374468Y558071D01*
X374775Y558174D01*
X375005Y558433D01*
X375158Y558743D01*
X375273Y559156D01*
X375311Y559621D01*
X375273Y560086D01*
X375158Y560499D01*
X375005Y560809D01*
X374775Y561068D01*
X374468Y561171D01*
G01X377568Y558071D02*
X377836Y558123D01*
X378143Y558278D01*
X378335Y558536D01*
X378411Y558898D01*
X378335Y559259D01*
X378105Y559569D01*
X377760Y559724D01*
X377376D01*
X377146Y559828D01*
X376955Y560086D01*
X376878Y560448D01*
X376993Y560809D01*
X377261Y561068D01*
X377568Y561171D01*
X377875Y561068D01*
X378143Y560809D01*
X378258Y560448D01*
X378181Y560086D01*
X377990Y559828D01*
X377760Y559724D01*
X377376D01*
X377031Y559569D01*
X376801Y559259D01*
X376725Y558898D01*
X376801Y558536D01*
X376993Y558278D01*
X377300Y558123D01*
X377568Y558071D01*
G01X379940Y559363D02*
X380208Y559724D01*
X380438Y559931D01*
X380745Y560034D01*
X381013Y559931D01*
X381205Y559724D01*
X381358Y559414D01*
X381396Y559053D01*
X381358Y558743D01*
X381205Y558433D01*
X380975Y558174D01*
X380706Y558071D01*
X380400Y558174D01*
X380131Y558484D01*
X379978Y558949D01*
X379940Y559466D01*
X380016Y560138D01*
X380131Y560499D01*
X380323Y560861D01*
X380591Y561119D01*
X380860Y561171D01*
X381128Y561068D01*
X381320Y560809D01*
G01X367501Y562313D02*
Y565413D01*
X368460D01*
X368766Y565258D01*
X368958Y565051D01*
X369035Y564638D01*
X368958Y564225D01*
X368728Y563966D01*
X368460Y563811D01*
X367501D01*
G01X368460D02*
X369035Y562313D01*
G01X371368D02*
Y565413D01*
X370908Y564793D01*
G01Y562313D02*
X371828D01*
G01X374468Y565413D02*
X374161Y565310D01*
X373931Y565051D01*
X373778Y564741D01*
X373663Y564328D01*
X373625Y563863D01*
X373663Y563398D01*
X373778Y562985D01*
X373931Y562675D01*
X374161Y562416D01*
X374468Y562313D01*
X374775Y562416D01*
X375005Y562675D01*
X375158Y562985D01*
X375273Y563398D01*
X375311Y563863D01*
X375273Y564328D01*
X375158Y564741D01*
X375005Y565051D01*
X374775Y565310D01*
X374468Y565413D01*
G01X377568Y562313D02*
X377836Y562365D01*
X378143Y562520D01*
X378335Y562778D01*
X378411Y563140D01*
X378335Y563501D01*
X378105Y563811D01*
X377760Y563966D01*
X377376D01*
X377146Y564070D01*
X376955Y564328D01*
X376878Y564690D01*
X376993Y565051D01*
X377261Y565310D01*
X377568Y565413D01*
X377875Y565310D01*
X378143Y565051D01*
X378258Y564690D01*
X378181Y564328D01*
X377990Y564070D01*
X377760Y563966D01*
X377376D01*
X377031Y563811D01*
X376801Y563501D01*
X376725Y563140D01*
X376801Y562778D01*
X376993Y562520D01*
X377300Y562365D01*
X377568Y562313D01*
G01X379825Y562778D02*
X380055Y562520D01*
X380323Y562365D01*
X380668Y562313D01*
X381013Y562416D01*
X381281Y562623D01*
X381473Y562985D01*
X381511Y563398D01*
X381435Y563811D01*
X381243Y564070D01*
X380975Y564276D01*
X380706Y564328D01*
X380438Y564276D01*
X380093Y564070D01*
X380208Y565413D01*
X381243D01*
G01X369111Y569561D02*
X368881Y569716D01*
X368613Y569819D01*
X368306D01*
X367961Y569664D01*
X367693Y569406D01*
X367501Y569096D01*
X367348Y568579D01*
X367310Y568114D01*
X367386Y567649D01*
X367501Y567339D01*
X367731Y567029D01*
X368000Y566822D01*
X368268Y566719D01*
X368536D01*
X368805Y566822D01*
X369035Y566977D01*
X369226Y567184D01*
G01X371368Y566719D02*
X371636Y566771D01*
X371943Y566926D01*
X372135Y567184D01*
X372211Y567546D01*
X372135Y567907D01*
X371905Y568217D01*
X371560Y568372D01*
X371176D01*
X370946Y568476D01*
X370755Y568734D01*
X370678Y569096D01*
X370793Y569457D01*
X371061Y569716D01*
X371368Y569819D01*
X371675Y569716D01*
X371943Y569457D01*
X372058Y569096D01*
X371981Y568734D01*
X371790Y568476D01*
X371560Y568372D01*
X371176D01*
X370831Y568217D01*
X370601Y567907D01*
X370525Y567546D01*
X370601Y567184D01*
X370793Y566926D01*
X371100Y566771D01*
X371368Y566719D01*
G01X374468D02*
Y569819D01*
X374008Y569199D01*
G01Y566719D02*
X374928D01*
G01X376725Y567184D02*
X376955Y566926D01*
X377223Y566771D01*
X377568Y566719D01*
X377913Y566822D01*
X378181Y567029D01*
X378373Y567391D01*
X378411Y567804D01*
X378335Y568217D01*
X378143Y568476D01*
X377875Y568682D01*
X377606Y568734D01*
X377338Y568682D01*
X376993Y568476D01*
X377108Y569819D01*
X378143D01*
G01X364678Y593894D02*
Y596994D01*
X365598D01*
X365905Y596839D01*
X366135Y596477D01*
X366212Y596064D01*
X366135Y595651D01*
X365943Y595341D01*
X365598Y595186D01*
X364678D01*
G01X367778Y596994D02*
Y593894D01*
X369312D01*
G01X372105D02*
Y596994D01*
X370687Y594772D01*
X372603D01*
G01X354872Y616413D02*
Y609613D01*
G01X356257Y598156D02*
Y624534D01*
G01X389057Y598156D02*
X356257D01*
G01X354872Y608413D02*
Y601613D01*
G01Y624413D02*
Y617613D01*
G01X356257Y624534D02*
X389057D01*
G01X369077Y626138D02*
X365877D01*
G01D02*
Y632338D01*
G01X363798Y641132D02*
Y626132D01*
G01X365231Y638607D02*
X369831D01*
G01Y633507D02*
X365231D01*
G01Y643707D02*
X369831D01*
G01X365231Y633507D02*
Y643707D01*
G01X358342Y645766D02*
Y642566D01*
G01X365877Y632338D02*
X369077D01*
G01X363274Y643439D02*
X363807D01*
Y642689D01*
X363647Y642439D01*
X363461Y642272D01*
X363194Y642189D01*
X362927Y642272D01*
X362741Y642439D01*
X362581Y642689D01*
X362474Y642981D01*
X362421Y643314D01*
Y643606D01*
X362474Y643856D01*
X362581Y644147D01*
X362741Y644397D01*
X362901Y644564D01*
X363114Y644689D01*
X363301D01*
X363514Y644606D01*
X363674Y644439D01*
G01X355877Y648633D02*
Y653633D01*
X357143D01*
X357650Y653383D01*
X358030Y653050D01*
X358347Y652550D01*
X358600Y651966D01*
X358663Y651133D01*
X358600Y650300D01*
X358347Y649716D01*
X358030Y649216D01*
X357650Y648883D01*
X357143Y648633D01*
X355877D01*
G01X353510Y647570D02*
Y714380D01*
G01X368819Y656521D02*
Y659721D01*
G01X375019Y656521D02*
X368819D01*
G01Y659721D02*
X375019D01*
G01X368834Y652557D02*
Y655757D01*
G01X375034Y652557D02*
X368834D01*
G01Y655757D02*
X375034D01*
G01X357530Y660630D02*
Y657630D01*
G01X360630Y660730D02*
Y657530D01*
G01X354430D02*
Y660730D01*
G01X360630Y657530D02*
X354430D01*
G01X368758Y648556D02*
Y651756D01*
G01X374958Y648556D02*
X368758D01*
G01Y651756D02*
X374958D01*
G01X368758Y644556D02*
Y647756D01*
G01X374958Y644556D02*
X368758D01*
G01Y647756D02*
X374958D01*
G01X354430Y660730D02*
X360630D01*
G01X360628Y676730D02*
Y673530D01*
G01X354428D02*
Y676730D01*
G01X360628Y673530D02*
X354428D01*
G01X360630Y664728D02*
Y661528D01*
G01X354430D02*
Y664728D01*
G01X360630Y661528D02*
X354430D01*
G01Y664728D02*
X360630D01*
G01X368758Y664556D02*
Y667756D01*
G01X374958Y664556D02*
X368758D01*
G01Y667756D02*
X374958D01*
G01X368758Y668556D02*
Y671756D01*
G01X374958Y668556D02*
X368758D01*
G01Y671756D02*
X374958D01*
G01X368758Y672614D02*
Y675814D01*
G01X374958Y672614D02*
X368758D01*
G01Y676622D02*
Y679822D01*
G01X374958Y676622D02*
X368758D01*
G01Y679822D02*
X374958D01*
G01X357510Y692124D02*
Y689124D01*
G01X360610Y692224D02*
Y689024D01*
G01X354410D02*
Y692224D01*
G01X360610Y689024D02*
X354410D01*
G01X360628Y680733D02*
Y677533D01*
G01X354428Y680733D02*
X360628D01*
G01X354428Y677533D02*
Y680733D01*
G01X360628Y677533D02*
X354428D01*
G01Y676730D02*
X360628D01*
G01X368758Y684648D02*
Y687848D01*
G01X374958Y684648D02*
X368758D01*
G01Y687848D02*
X374958D01*
G01X368758Y688648D02*
Y691848D01*
G01X374958Y688648D02*
X368758D01*
G01Y680648D02*
Y683848D01*
G01X374958Y680648D02*
X368758D01*
G01Y683848D02*
X374958D01*
G01X368758Y675814D02*
X374958D01*
G01X354410Y692224D02*
X360610D01*
G01X360630Y708728D02*
Y705528D01*
G01X354430D02*
Y708728D01*
G01X360630Y705528D02*
X354430D01*
G01X360630Y704728D02*
Y701528D01*
G01X354430Y704728D02*
X360630D01*
G01X354430Y701528D02*
Y704728D01*
G01X360630Y701528D02*
X354430D01*
G01X360630Y700728D02*
Y697528D01*
G01X354430Y700728D02*
X360630D01*
G01X354430Y697528D02*
Y700728D01*
G01X360630Y697528D02*
X354430D01*
G01X360637Y696728D02*
Y693528D01*
G01X354437D02*
Y696728D01*
G01X360637Y693528D02*
X354437D01*
G01Y696728D02*
X360637D01*
G01X368758Y700648D02*
Y703848D01*
G01X374958Y700648D02*
X368758D01*
G01Y703848D02*
X374958D01*
G01X368758Y704648D02*
Y707848D01*
G01X374958Y704648D02*
X368758D01*
G01Y696648D02*
Y699848D01*
G01X374958Y696648D02*
X368758D01*
G01Y699848D02*
X374958D01*
G01X368758Y692648D02*
Y695848D01*
G01X374958Y692648D02*
X368758D01*
G01Y695848D02*
X374958D01*
G01X368758Y691848D02*
X374958D01*
G01X353510Y714380D02*
X381250D01*
Y719187D01*
X410410D01*
Y665940D01*
G01X361771Y725137D02*
Y721937D01*
G01X355571D02*
Y725137D01*
G01X358671Y725037D02*
Y722037D01*
G01X361771Y721937D02*
X355571D01*
G01X354430Y708728D02*
X360630D01*
G01Y712728D02*
Y709528D01*
G01X354430Y712728D02*
X360630D01*
G01X354430Y709528D02*
Y712728D01*
G01X360630Y709528D02*
X354430D01*
G01X367903Y722022D02*
Y725222D01*
G01X374103Y722022D02*
X367903D01*
G01X368758Y707848D02*
X374958D01*
G01X361771Y741137D02*
Y737937D01*
G01X355571D02*
Y741137D01*
G01X358671Y741037D02*
Y738037D01*
G01X361771Y737937D02*
X355571D01*
G01X367811Y729859D02*
Y733059D01*
G01X374011Y729859D02*
X367811D01*
G01Y733059D02*
X374011D01*
G01X355571Y733937D02*
Y737137D01*
G01X361771Y733937D02*
X355571D01*
G01X361771Y737137D02*
Y733937D01*
G01X355571Y737137D02*
X361771D01*
G01X358671Y734037D02*
Y737037D01*
G01X361771Y729137D02*
Y725937D01*
G01X355571Y729137D02*
X361771D01*
G01Y725937D02*
X355571D01*
G01D02*
Y729137D01*
G01X358671Y729037D02*
Y726037D01*
G01X367811Y725859D02*
Y729059D01*
G01X374011Y725859D02*
X367811D01*
G01Y729059D02*
X374011D01*
G01X355571Y725137D02*
X361771D01*
G01X374011Y737859D02*
X367811D01*
G01D02*
Y741059D01*
G01X353540Y732256D02*
Y726056D01*
G01X367903Y725222D02*
X374103D01*
G01X367811Y733859D02*
Y737059D01*
G01X374011Y733859D02*
X367811D01*
G01Y737059D02*
X374011D01*
G01X355571Y741137D02*
X361771D01*
G01X368247Y757235D02*
X368017Y757390D01*
X367749Y757493D01*
X367442D01*
X367097Y757338D01*
X366829Y757080D01*
X366637Y756770D01*
X366484Y756253D01*
X366446Y755788D01*
X366522Y755323D01*
X366637Y755013D01*
X366867Y754703D01*
X367136Y754496D01*
X367404Y754393D01*
X367672D01*
X367941Y754496D01*
X368171Y754651D01*
X368362Y754858D01*
G01X369776Y755685D02*
X370044Y756046D01*
X370274Y756253D01*
X370581Y756356D01*
X370849Y756253D01*
X371041Y756046D01*
X371194Y755736D01*
X371232Y755375D01*
X371194Y755065D01*
X371041Y754755D01*
X370811Y754496D01*
X370542Y754393D01*
X370236Y754496D01*
X369967Y754806D01*
X369814Y755271D01*
X369776Y755788D01*
X369852Y756460D01*
X369967Y756821D01*
X370159Y757183D01*
X370427Y757441D01*
X370696Y757493D01*
X370964Y757390D01*
X371156Y757131D01*
G01X372952Y754755D02*
X373221Y754496D01*
X373527Y754393D01*
X373834Y754496D01*
X374102Y754806D01*
X374294Y755271D01*
X374371Y755736D01*
Y756305D01*
X374294Y756770D01*
X374102Y757183D01*
X373872Y757390D01*
X373604Y757493D01*
X373297Y757390D01*
X373067Y757183D01*
X372914Y756873D01*
X372837Y756460D01*
X372914Y756098D01*
X373106Y755736D01*
X373336Y755530D01*
X373604Y755478D01*
X373911Y755581D01*
X374141Y755840D01*
X374371Y756305D01*
G01X376704Y757493D02*
X376397Y757390D01*
X376167Y757131D01*
X376014Y756821D01*
X375899Y756408D01*
X375861Y755943D01*
X375899Y755478D01*
X376014Y755065D01*
X376167Y754755D01*
X376397Y754496D01*
X376704Y754393D01*
X377011Y754496D01*
X377241Y754755D01*
X377394Y755065D01*
X377509Y755478D01*
X377547Y755943D01*
X377509Y756408D01*
X377394Y756821D01*
X377241Y757131D01*
X377011Y757390D01*
X376704Y757493D01*
G01X367811Y741059D02*
X374011D01*
G01X361771Y745137D02*
Y741937D01*
G01X355571Y745137D02*
X361771D01*
G01X355571Y741937D02*
Y745137D01*
G01X358671Y745037D02*
Y742037D01*
G01X361771Y741937D02*
X355571D01*
G01X374011Y741859D02*
X367811D01*
G01Y745059D02*
X374011D01*
G01X367811Y741859D02*
Y745059D01*
G01X366637Y750505D02*
Y753605D01*
X367596D01*
X367902Y753450D01*
X368094Y753243D01*
X368171Y752830D01*
X368094Y752417D01*
X367864Y752158D01*
X367596Y752003D01*
X366637D01*
G01X367596D02*
X368171Y750505D01*
G01X369852Y750867D02*
X370121Y750608D01*
X370427Y750505D01*
X370734Y750608D01*
X371002Y750918D01*
X371194Y751383D01*
X371271Y751848D01*
Y752417D01*
X371194Y752882D01*
X371002Y753295D01*
X370772Y753502D01*
X370504Y753605D01*
X370197Y753502D01*
X369967Y753295D01*
X369814Y752985D01*
X369737Y752572D01*
X369814Y752210D01*
X370006Y751848D01*
X370236Y751642D01*
X370504Y751590D01*
X370811Y751693D01*
X371041Y751952D01*
X371271Y752417D01*
G01X373604Y753605D02*
X373297Y753502D01*
X373067Y753243D01*
X372914Y752933D01*
X372799Y752520D01*
X372761Y752055D01*
X372799Y751590D01*
X372914Y751177D01*
X373067Y750867D01*
X373297Y750608D01*
X373604Y750505D01*
X373911Y750608D01*
X374141Y750867D01*
X374294Y751177D01*
X374409Y751590D01*
X374447Y752055D01*
X374409Y752520D01*
X374294Y752933D01*
X374141Y753243D01*
X373911Y753502D01*
X373604Y753605D01*
G01X375976Y753088D02*
X376206Y753398D01*
X376474Y753553D01*
X376781Y753605D01*
X377164Y753502D01*
X377432Y753243D01*
X377509Y752933D01*
X377471Y752623D01*
X377317Y752365D01*
X376551Y751848D01*
X376206Y751487D01*
X375976Y750970D01*
X375899Y750505D01*
X377509D01*
G01X368247Y761365D02*
X368017Y761520D01*
X367749Y761623D01*
X367442D01*
X367097Y761468D01*
X366829Y761210D01*
X366637Y760900D01*
X366484Y760383D01*
X366446Y759918D01*
X366522Y759453D01*
X366637Y759143D01*
X366867Y758833D01*
X367136Y758626D01*
X367404Y758523D01*
X367672D01*
X367941Y758626D01*
X368171Y758781D01*
X368362Y758988D01*
G01X369776Y759815D02*
X370044Y760176D01*
X370274Y760383D01*
X370581Y760486D01*
X370849Y760383D01*
X371041Y760176D01*
X371194Y759866D01*
X371232Y759505D01*
X371194Y759195D01*
X371041Y758885D01*
X370811Y758626D01*
X370542Y758523D01*
X370236Y758626D01*
X369967Y758936D01*
X369814Y759401D01*
X369776Y759918D01*
X369852Y760590D01*
X369967Y760951D01*
X370159Y761313D01*
X370427Y761571D01*
X370696Y761623D01*
X370964Y761520D01*
X371156Y761261D01*
G01X373527Y758523D02*
X373604Y759195D01*
X373719Y759763D01*
X373872Y760280D01*
X374064Y760848D01*
X374371Y761623D01*
X372837D01*
G01X376704Y758523D02*
X376972Y758575D01*
X377279Y758730D01*
X377471Y758988D01*
X377547Y759350D01*
X377471Y759711D01*
X377241Y760021D01*
X376896Y760176D01*
X376512D01*
X376282Y760280D01*
X376091Y760538D01*
X376014Y760900D01*
X376129Y761261D01*
X376397Y761520D01*
X376704Y761623D01*
X377011Y761520D01*
X377279Y761261D01*
X377394Y760900D01*
X377317Y760538D01*
X377126Y760280D01*
X376896Y760176D01*
X376512D01*
X376167Y760021D01*
X375937Y759711D01*
X375861Y759350D01*
X375937Y758988D01*
X376129Y758730D01*
X376436Y758575D01*
X376704Y758523D01*
G01X368247Y769902D02*
X368017Y770057D01*
X367749Y770160D01*
X367442D01*
X367097Y770005D01*
X366829Y769747D01*
X366637Y769437D01*
X366484Y768920D01*
X366446Y768455D01*
X366522Y767990D01*
X366637Y767680D01*
X366867Y767370D01*
X367136Y767163D01*
X367404Y767060D01*
X367672D01*
X367941Y767163D01*
X368171Y767318D01*
X368362Y767525D01*
G01X370427Y767060D02*
X370504Y767732D01*
X370619Y768300D01*
X370772Y768817D01*
X370964Y769385D01*
X371271Y770160D01*
X369737D01*
G01X373604D02*
X373297Y770057D01*
X373067Y769798D01*
X372914Y769488D01*
X372799Y769075D01*
X372761Y768610D01*
X372799Y768145D01*
X372914Y767732D01*
X373067Y767422D01*
X373297Y767163D01*
X373604Y767060D01*
X373911Y767163D01*
X374141Y767422D01*
X374294Y767732D01*
X374409Y768145D01*
X374447Y768610D01*
X374409Y769075D01*
X374294Y769488D01*
X374141Y769798D01*
X373911Y770057D01*
X373604Y770160D01*
G01X375861Y767525D02*
X376091Y767267D01*
X376359Y767112D01*
X376704Y767060D01*
X377049Y767163D01*
X377317Y767370D01*
X377509Y767732D01*
X377547Y768145D01*
X377471Y768558D01*
X377279Y768817D01*
X377011Y769023D01*
X376742Y769075D01*
X376474Y769023D01*
X376129Y768817D01*
X376244Y770160D01*
X377279D01*
G01X366637Y762555D02*
Y765655D01*
X367596D01*
X367902Y765500D01*
X368094Y765293D01*
X368171Y764880D01*
X368094Y764467D01*
X367864Y764208D01*
X367596Y764053D01*
X366637D01*
G01X367596D02*
X368171Y762555D01*
G01X369852Y762917D02*
X370121Y762658D01*
X370427Y762555D01*
X370734Y762658D01*
X371002Y762968D01*
X371194Y763433D01*
X371271Y763898D01*
Y764467D01*
X371194Y764932D01*
X371002Y765345D01*
X370772Y765552D01*
X370504Y765655D01*
X370197Y765552D01*
X369967Y765345D01*
X369814Y765035D01*
X369737Y764622D01*
X369814Y764260D01*
X370006Y763898D01*
X370236Y763692D01*
X370504Y763640D01*
X370811Y763743D01*
X371041Y764002D01*
X371271Y764467D01*
G01X373604Y765655D02*
X373297Y765552D01*
X373067Y765293D01*
X372914Y764983D01*
X372799Y764570D01*
X372761Y764105D01*
X372799Y763640D01*
X372914Y763227D01*
X373067Y762917D01*
X373297Y762658D01*
X373604Y762555D01*
X373911Y762658D01*
X374141Y762917D01*
X374294Y763227D01*
X374409Y763640D01*
X374447Y764105D01*
X374409Y764570D01*
X374294Y764983D01*
X374141Y765293D01*
X373911Y765552D01*
X373604Y765655D01*
G01X375861Y763020D02*
X376091Y762762D01*
X376359Y762607D01*
X376704Y762555D01*
X377049Y762658D01*
X377317Y762865D01*
X377509Y763227D01*
X377547Y763640D01*
X377471Y764053D01*
X377279Y764312D01*
X377011Y764518D01*
X376742Y764570D01*
X376474Y764518D01*
X376129Y764312D01*
X376244Y765655D01*
X377279D01*
G01X366637Y771463D02*
Y774563D01*
X367596D01*
X367902Y774408D01*
X368094Y774201D01*
X368171Y773788D01*
X368094Y773375D01*
X367864Y773116D01*
X367596Y772961D01*
X366637D01*
G01X367596D02*
X368171Y771463D01*
G01X369852Y771825D02*
X370121Y771566D01*
X370427Y771463D01*
X370734Y771566D01*
X371002Y771876D01*
X371194Y772341D01*
X371271Y772806D01*
Y773375D01*
X371194Y773840D01*
X371002Y774253D01*
X370772Y774460D01*
X370504Y774563D01*
X370197Y774460D01*
X369967Y774253D01*
X369814Y773943D01*
X369737Y773530D01*
X369814Y773168D01*
X370006Y772806D01*
X370236Y772600D01*
X370504Y772548D01*
X370811Y772651D01*
X371041Y772910D01*
X371271Y773375D01*
G01X372761Y772083D02*
X372991Y771721D01*
X373297Y771515D01*
X373642Y771463D01*
X373949Y771515D01*
X374256Y771773D01*
X374447Y772083D01*
X374486Y772393D01*
X374409Y772755D01*
X374141Y773013D01*
X373872Y773116D01*
X373527D01*
G01X373872D02*
X374102Y773271D01*
X374294Y773530D01*
X374371Y773840D01*
X374294Y774150D01*
X374102Y774408D01*
X373757Y774563D01*
X373412Y774511D01*
X373067Y774305D01*
G01X376052Y771825D02*
X376321Y771566D01*
X376627Y771463D01*
X376934Y771566D01*
X377202Y771876D01*
X377394Y772341D01*
X377471Y772806D01*
Y773375D01*
X377394Y773840D01*
X377202Y774253D01*
X376972Y774460D01*
X376704Y774563D01*
X376397Y774460D01*
X376167Y774253D01*
X376014Y773943D01*
X375937Y773530D01*
X376014Y773168D01*
X376206Y772806D01*
X376436Y772600D01*
X376704Y772548D01*
X377011Y772651D01*
X377241Y772910D01*
X377471Y773375D01*
G01X380993Y-186364D02*
Y-194364D01*
G01X378693Y-186364D02*
X383293D01*
G01X387093Y-191031D02*
X387793Y-190097D01*
X388393Y-189564D01*
X389193Y-189297D01*
X389893Y-189564D01*
X390393Y-190097D01*
X390793Y-190897D01*
X390893Y-191831D01*
X390793Y-192631D01*
X390393Y-193431D01*
X389793Y-194097D01*
X389093Y-194364D01*
X388293Y-194097D01*
X387593Y-193298D01*
X387193Y-192097D01*
X387093Y-190764D01*
X387293Y-189031D01*
X387593Y-188097D01*
X388093Y-187164D01*
X388793Y-186497D01*
X389493Y-186364D01*
X390193Y-186631D01*
X390693Y-187297D01*
G01X394393Y-194364D02*
Y-186364D01*
X396993Y-193031D01*
X399593Y-186364D01*
Y-194364D01*
G01X401993Y-197031D02*
X407993D01*
G01X415193Y-187031D02*
X414593Y-186631D01*
X413893Y-186364D01*
X413093D01*
X412193Y-186764D01*
X411493Y-187431D01*
X410993Y-188231D01*
X410593Y-189564D01*
X410493Y-190764D01*
X410693Y-191964D01*
X410993Y-192764D01*
X411593Y-193564D01*
X412293Y-194097D01*
X412993Y-194364D01*
X413693D01*
X414393Y-194097D01*
X414993Y-193697D01*
X415493Y-193164D01*
G01X418393Y-194364D02*
Y-186364D01*
X420993Y-193031D01*
X423593Y-186364D01*
Y-194364D01*
G01X425993Y-197031D02*
X431993D01*
G01X434793Y-194364D02*
Y-186364D01*
X436793D01*
X437593Y-186764D01*
X438193Y-187297D01*
X438693Y-188097D01*
X439093Y-189031D01*
X439193Y-190364D01*
X439093Y-191697D01*
X438693Y-192631D01*
X438193Y-193431D01*
X437593Y-193964D01*
X436793Y-194364D01*
X434793D01*
G01X373447Y13781D02*
X373217Y13936D01*
X372949Y14039D01*
X372642D01*
X372297Y13884D01*
X372029Y13626D01*
X371837Y13316D01*
X371684Y12799D01*
X371646Y12334D01*
X371722Y11869D01*
X371837Y11559D01*
X372067Y11249D01*
X372336Y11042D01*
X372604Y10939D01*
X372872D01*
X373141Y11042D01*
X373371Y11197D01*
X373562Y11404D01*
G01X375704Y10939D02*
Y14039D01*
X375244Y13419D01*
G01Y10939D02*
X376164D01*
G01X377961Y11559D02*
X378191Y11197D01*
X378497Y10991D01*
X378842Y10939D01*
X379149Y10991D01*
X379456Y11249D01*
X379647Y11559D01*
X379686Y11869D01*
X379609Y12231D01*
X379341Y12489D01*
X379072Y12592D01*
X378727D01*
G01X379072D02*
X379302Y12747D01*
X379494Y13006D01*
X379571Y13316D01*
X379494Y13626D01*
X379302Y13884D01*
X378957Y14039D01*
X378612Y13987D01*
X378267Y13781D01*
G01X381061Y11404D02*
X381291Y11146D01*
X381559Y10991D01*
X381904Y10939D01*
X382249Y11042D01*
X382517Y11249D01*
X382709Y11611D01*
X382747Y12024D01*
X382671Y12437D01*
X382479Y12696D01*
X382211Y12902D01*
X381942Y12954D01*
X381674Y12902D01*
X381329Y12696D01*
X381444Y14039D01*
X382479D01*
G01X372508Y19389D02*
X378708D01*
G01X375608Y16289D02*
Y19289D01*
G01X378708Y16189D02*
X372508D01*
G01D02*
Y19389D01*
G01X378708D02*
Y16189D01*
G01X384199Y19119D02*
X390399D01*
G01Y15919D02*
X384199D01*
G01D02*
Y19119D01*
G01X379383Y26152D02*
X376581D01*
G01X387233D02*
X384433D01*
G01X377451Y59466D02*
Y65666D01*
X380651D01*
Y59466D01*
X377451D01*
G01X369309Y47412D02*
Y50954D01*
G01X371533Y47412D02*
X369309D01*
G01X376581Y50956D02*
X379383D01*
G01X378757Y47412D02*
X376533D01*
G01X384433Y50956D02*
X387233D01*
G01X378757Y50854D02*
Y47412D01*
G01X384602Y65856D02*
X381502D01*
Y66815D01*
X381657Y67121D01*
X381864Y67313D01*
X382277Y67390D01*
X382690Y67313D01*
X382949Y67083D01*
X383104Y66815D01*
Y65856D01*
G01Y66815D02*
X384602Y67390D01*
G01Y69723D02*
X381502D01*
X382122Y69263D01*
G01X384602D02*
Y70183D01*
G01X384240Y72171D02*
X384499Y72440D01*
X384602Y72746D01*
X384499Y73053D01*
X384189Y73321D01*
X383724Y73513D01*
X383259Y73590D01*
X382690D01*
X382225Y73513D01*
X381812Y73321D01*
X381605Y73091D01*
X381502Y72823D01*
X381605Y72516D01*
X381812Y72286D01*
X382122Y72133D01*
X382535Y72056D01*
X382897Y72133D01*
X383259Y72325D01*
X383465Y72555D01*
X383517Y72823D01*
X383414Y73130D01*
X383155Y73360D01*
X382690Y73590D01*
G01X381502Y75923D02*
X381605Y75616D01*
X381864Y75386D01*
X382174Y75233D01*
X382587Y75118D01*
X383052Y75080D01*
X383517Y75118D01*
X383930Y75233D01*
X384240Y75386D01*
X384499Y75616D01*
X384602Y75923D01*
X384499Y76230D01*
X384240Y76460D01*
X383930Y76613D01*
X383517Y76728D01*
X383052Y76766D01*
X382587Y76728D01*
X382174Y76613D01*
X381864Y76460D01*
X381605Y76230D01*
X381502Y75923D01*
G01X376954Y65483D02*
X373854D01*
Y66442D01*
X374009Y66748D01*
X374216Y66940D01*
X374629Y67017D01*
X375042Y66940D01*
X375301Y66710D01*
X375456Y66442D01*
Y65483D01*
G01Y66442D02*
X376954Y67017D01*
G01Y69350D02*
X373854D01*
X374474Y68890D01*
G01X376954D02*
Y69810D01*
G01X376592Y71798D02*
X376851Y72067D01*
X376954Y72373D01*
X376851Y72680D01*
X376541Y72948D01*
X376076Y73140D01*
X375611Y73217D01*
X375042D01*
X374577Y73140D01*
X374164Y72948D01*
X373957Y72718D01*
X373854Y72450D01*
X373957Y72143D01*
X374164Y71913D01*
X374474Y71760D01*
X374887Y71683D01*
X375249Y71760D01*
X375611Y71952D01*
X375817Y72182D01*
X375869Y72450D01*
X375766Y72757D01*
X375507Y72987D01*
X375042Y73217D01*
G01X376954Y75550D02*
X373854D01*
X374474Y75090D01*
G01X376954D02*
Y76010D01*
G01X381060Y151230D02*
Y163720D01*
G01X406580Y151230D02*
X381060D01*
G01X385353Y152346D02*
X382253D01*
Y153305D01*
X382408Y153611D01*
X382615Y153803D01*
X383028Y153880D01*
X383441Y153803D01*
X383700Y153573D01*
X383855Y153305D01*
Y152346D01*
G01Y153305D02*
X385353Y153880D01*
G01Y156213D02*
X382253D01*
X382873Y155753D01*
G01X385353D02*
Y156673D01*
G01X384888Y158470D02*
X385146Y158700D01*
X385301Y158968D01*
X385353Y159313D01*
X385250Y159658D01*
X385043Y159926D01*
X384681Y160118D01*
X384268Y160156D01*
X383855Y160080D01*
X383596Y159888D01*
X383390Y159620D01*
X383338Y159351D01*
X383390Y159083D01*
X383596Y158738D01*
X382253Y158853D01*
Y159888D01*
G01X385353Y162413D02*
X382253D01*
X382873Y161953D01*
G01X385353D02*
Y162873D01*
G01X374090Y164646D02*
X370990D01*
Y165605D01*
X371145Y165911D01*
X371352Y166103D01*
X371765Y166180D01*
X372178Y166103D01*
X372437Y165873D01*
X372592Y165605D01*
Y164646D01*
G01Y165605D02*
X374090Y166180D01*
G01X372798Y167785D02*
X372437Y168053D01*
X372230Y168283D01*
X372127Y168590D01*
X372230Y168858D01*
X372437Y169050D01*
X372747Y169203D01*
X373108Y169241D01*
X373418Y169203D01*
X373728Y169050D01*
X373987Y168820D01*
X374090Y168551D01*
X373987Y168245D01*
X373677Y167976D01*
X373212Y167823D01*
X372695Y167785D01*
X372023Y167861D01*
X371662Y167976D01*
X371300Y168168D01*
X371042Y168436D01*
X370990Y168705D01*
X371093Y168973D01*
X371352Y169165D01*
G01X373625Y170770D02*
X373883Y171000D01*
X374038Y171268D01*
X374090Y171613D01*
X373987Y171958D01*
X373780Y172226D01*
X373418Y172418D01*
X373005Y172456D01*
X372592Y172380D01*
X372333Y172188D01*
X372127Y171920D01*
X372075Y171651D01*
X372127Y171383D01*
X372333Y171038D01*
X370990Y171153D01*
Y172188D01*
G01X385723Y164646D02*
X382623D01*
Y165605D01*
X382778Y165911D01*
X382985Y166103D01*
X383398Y166180D01*
X383811Y166103D01*
X384070Y165873D01*
X384225Y165605D01*
Y164646D01*
G01Y165605D02*
X385723Y166180D01*
G01X384431Y167785D02*
X384070Y168053D01*
X383863Y168283D01*
X383760Y168590D01*
X383863Y168858D01*
X384070Y169050D01*
X384380Y169203D01*
X384741Y169241D01*
X385051Y169203D01*
X385361Y169050D01*
X385620Y168820D01*
X385723Y168551D01*
X385620Y168245D01*
X385310Y167976D01*
X384845Y167823D01*
X384328Y167785D01*
X383656Y167861D01*
X383295Y167976D01*
X382933Y168168D01*
X382675Y168436D01*
X382623Y168705D01*
X382726Y168973D01*
X382985Y169165D01*
G01X385361Y170961D02*
X385620Y171230D01*
X385723Y171536D01*
X385620Y171843D01*
X385310Y172111D01*
X384845Y172303D01*
X384380Y172380D01*
X383811D01*
X383346Y172303D01*
X382933Y172111D01*
X382726Y171881D01*
X382623Y171613D01*
X382726Y171306D01*
X382933Y171076D01*
X383243Y170923D01*
X383656Y170846D01*
X384018Y170923D01*
X384380Y171115D01*
X384586Y171345D01*
X384638Y171613D01*
X384535Y171920D01*
X384276Y172150D01*
X383811Y172380D01*
G01X377818Y164646D02*
X374718D01*
Y165605D01*
X374873Y165911D01*
X375080Y166103D01*
X375493Y166180D01*
X375906Y166103D01*
X376165Y165873D01*
X376320Y165605D01*
Y164646D01*
G01Y165605D02*
X377818Y166180D01*
G01Y168436D02*
X377146Y168513D01*
X376578Y168628D01*
X376061Y168781D01*
X375493Y168973D01*
X374718Y169280D01*
Y167746D01*
G01X377198Y170770D02*
X377560Y171000D01*
X377766Y171306D01*
X377818Y171651D01*
X377766Y171958D01*
X377508Y172265D01*
X377198Y172456D01*
X376888Y172495D01*
X376526Y172418D01*
X376268Y172150D01*
X376165Y171881D01*
Y171536D01*
G01Y171881D02*
X376010Y172111D01*
X375751Y172303D01*
X375441Y172380D01*
X375131Y172303D01*
X374873Y172111D01*
X374718Y171766D01*
X374770Y171421D01*
X374976Y171076D01*
G01X381818Y164646D02*
X378718D01*
Y165605D01*
X378873Y165911D01*
X379080Y166103D01*
X379493Y166180D01*
X379906Y166103D01*
X380165Y165873D01*
X380320Y165605D01*
Y164646D01*
G01Y165605D02*
X381818Y166180D01*
G01Y168436D02*
X381146Y168513D01*
X380578Y168628D01*
X380061Y168781D01*
X379493Y168973D01*
X378718Y169280D01*
Y167746D01*
G01X379235Y170885D02*
X378925Y171115D01*
X378770Y171383D01*
X378718Y171690D01*
X378821Y172073D01*
X379080Y172341D01*
X379390Y172418D01*
X379700Y172380D01*
X379958Y172226D01*
X380475Y171460D01*
X380836Y171115D01*
X381353Y170885D01*
X381818Y170808D01*
Y172418D01*
G01X369693Y176706D02*
Y179806D01*
X370652D01*
X370958Y179651D01*
X371150Y179444D01*
X371227Y179031D01*
X371150Y178618D01*
X370920Y178359D01*
X370652Y178204D01*
X369693D01*
G01X370652D02*
X371227Y176706D01*
G01X373560D02*
Y179806D01*
X373100Y179186D01*
G01Y176706D02*
X374020D01*
G01X376660Y179806D02*
X376353Y179703D01*
X376123Y179444D01*
X375970Y179134D01*
X375855Y178721D01*
X375817Y178256D01*
X375855Y177791D01*
X375970Y177378D01*
X376123Y177068D01*
X376353Y176809D01*
X376660Y176706D01*
X376967Y176809D01*
X377197Y177068D01*
X377350Y177378D01*
X377465Y177791D01*
X377503Y178256D01*
X377465Y178721D01*
X377350Y179134D01*
X377197Y179444D01*
X376967Y179703D01*
X376660Y179806D01*
G01X379108Y177068D02*
X379377Y176809D01*
X379683Y176706D01*
X379990Y176809D01*
X380258Y177119D01*
X380450Y177584D01*
X380527Y178049D01*
Y178618D01*
X380450Y179083D01*
X380258Y179496D01*
X380028Y179703D01*
X379760Y179806D01*
X379453Y179703D01*
X379223Y179496D01*
X379070Y179186D01*
X378993Y178773D01*
X379070Y178411D01*
X379262Y178049D01*
X379492Y177843D01*
X379760Y177791D01*
X380067Y177894D01*
X380297Y178153D01*
X380527Y178618D01*
G01X382860Y179806D02*
X382553Y179703D01*
X382323Y179444D01*
X382170Y179134D01*
X382055Y178721D01*
X382017Y178256D01*
X382055Y177791D01*
X382170Y177378D01*
X382323Y177068D01*
X382553Y176809D01*
X382860Y176706D01*
X383167Y176809D01*
X383397Y177068D01*
X383550Y177378D01*
X383665Y177791D01*
X383703Y178256D01*
X383665Y178721D01*
X383550Y179134D01*
X383397Y179444D01*
X383167Y179703D01*
X382860Y179806D01*
G01X372663Y322080D02*
X372770Y322205D01*
X372850Y322414D01*
X372903Y322705D01*
X372850Y322955D01*
X372743Y323122D01*
X372557Y323247D01*
X371837D01*
Y320747D01*
X372717D01*
X372903Y320914D01*
X373010Y321164D01*
X373063Y321455D01*
X373010Y321747D01*
X372850Y321997D01*
X372663Y322080D01*
X371837D01*
G01X378796Y320713D02*
X377730D01*
Y323213D01*
X378796D01*
G01X378370Y322005D02*
X377730D01*
G01X371757Y315365D02*
X371450Y315417D01*
X371182Y315623D01*
X370952Y315933D01*
X370799Y316295D01*
X370722Y316708D01*
Y317122D01*
X370799Y317535D01*
X370952Y317897D01*
X371182Y318207D01*
X371450Y318413D01*
X371757Y318465D01*
X372064Y318413D01*
X372332Y318207D01*
X372562Y317897D01*
X372715Y317535D01*
X372792Y317122D01*
Y316708D01*
X372715Y316295D01*
X372562Y315933D01*
X372332Y315623D01*
X372064Y315417D01*
X371757Y315365D01*
G01X372064Y316192D02*
X372524Y315365D01*
G01X375317D02*
Y318465D01*
X373899Y316243D01*
X375815D01*
G01X377229Y317948D02*
X377459Y318258D01*
X377727Y318413D01*
X378034Y318465D01*
X378417Y318362D01*
X378685Y318103D01*
X378762Y317793D01*
X378724Y317483D01*
X378570Y317225D01*
X377804Y316708D01*
X377459Y316347D01*
X377229Y315830D01*
X377152Y315365D01*
X378762D01*
G01X379714Y336923D02*
Y324449D01*
G01X444882Y377165D02*
G02I-31496J0D01*
G01X373339Y387715D02*
Y374526D01*
G01X373418Y372108D02*
Y368908D01*
G01X375691Y377980D02*
Y380480D01*
X374704Y378688D01*
X376038D01*
G01X387906Y387715D02*
X373339D01*
G01Y403463D02*
X387906D01*
G01X373339Y416652D02*
Y403463D01*
G01X376515Y410634D02*
Y408412D01*
X376668Y407947D01*
X376975Y407637D01*
X377358Y407534D01*
X377741Y407637D01*
X378048Y407947D01*
X378201Y408412D01*
Y410634D01*
G01X380918Y407534D02*
Y410634D01*
X379500Y408412D01*
X381416D01*
G01X370127Y418476D02*
X370357Y418218D01*
X370625Y418063D01*
X370970Y418011D01*
X371315Y418114D01*
X371583Y418321D01*
X371775Y418683D01*
X371813Y419096D01*
X371737Y419509D01*
X371545Y419768D01*
X371277Y419974D01*
X371008Y420026D01*
X370740Y419974D01*
X370395Y419768D01*
X370510Y421111D01*
X371545D01*
G01X376335Y415554D02*
Y413332D01*
X376488Y412867D01*
X376795Y412557D01*
X377178Y412454D01*
X377561Y412557D01*
X377868Y412867D01*
X378021Y413332D01*
Y415554D01*
G01X379435Y412919D02*
X379665Y412661D01*
X379933Y412506D01*
X380278Y412454D01*
X380623Y412557D01*
X380891Y412764D01*
X381083Y413126D01*
X381121Y413539D01*
X381045Y413952D01*
X380853Y414211D01*
X380585Y414417D01*
X380316Y414469D01*
X380048Y414417D01*
X379703Y414211D01*
X379818Y415554D01*
X380853D01*
G01X383893Y451317D02*
Y454417D01*
X384813D01*
X385120Y454262D01*
X385350Y453900D01*
X385427Y453487D01*
X385350Y453074D01*
X385158Y452764D01*
X384813Y452609D01*
X383893D01*
G01X388603Y454159D02*
X388373Y454314D01*
X388105Y454417D01*
X387798D01*
X387453Y454262D01*
X387185Y454004D01*
X386993Y453694D01*
X386840Y453177D01*
X386802Y452712D01*
X386878Y452247D01*
X386993Y451937D01*
X387223Y451627D01*
X387492Y451420D01*
X387760Y451317D01*
X388028D01*
X388297Y451420D01*
X388527Y451575D01*
X388718Y451782D01*
G01X390860Y451317D02*
Y454417D01*
X390400Y453797D01*
G01Y451317D02*
X391320D01*
G01X393960D02*
Y454417D01*
X393500Y453797D01*
G01Y451317D02*
X394420D01*
G01X396983D02*
X397060Y451989D01*
X397175Y452557D01*
X397328Y453074D01*
X397520Y453642D01*
X397827Y454417D01*
X396293D01*
G01X383893Y456227D02*
Y459327D01*
X384813D01*
X385120Y459172D01*
X385350Y458810D01*
X385427Y458397D01*
X385350Y457984D01*
X385158Y457674D01*
X384813Y457519D01*
X383893D01*
G01X388603Y459069D02*
X388373Y459224D01*
X388105Y459327D01*
X387798D01*
X387453Y459172D01*
X387185Y458914D01*
X386993Y458604D01*
X386840Y458087D01*
X386802Y457622D01*
X386878Y457157D01*
X386993Y456847D01*
X387223Y456537D01*
X387492Y456330D01*
X387760Y456227D01*
X388028D01*
X388297Y456330D01*
X388527Y456485D01*
X388718Y456692D01*
G01X390860Y456227D02*
Y459327D01*
X390400Y458707D01*
G01Y456227D02*
X391320D01*
G01X393232Y458810D02*
X393462Y459120D01*
X393730Y459275D01*
X394037Y459327D01*
X394420Y459224D01*
X394688Y458965D01*
X394765Y458655D01*
X394727Y458345D01*
X394573Y458087D01*
X393807Y457570D01*
X393462Y457209D01*
X393232Y456692D01*
X393155Y456227D01*
X394765D01*
G01X396332Y457519D02*
X396600Y457880D01*
X396830Y458087D01*
X397137Y458190D01*
X397405Y458087D01*
X397597Y457880D01*
X397750Y457570D01*
X397788Y457209D01*
X397750Y456899D01*
X397597Y456589D01*
X397367Y456330D01*
X397098Y456227D01*
X396792Y456330D01*
X396523Y456640D01*
X396370Y457105D01*
X396332Y457622D01*
X396408Y458294D01*
X396523Y458655D01*
X396715Y459017D01*
X396983Y459275D01*
X397252Y459327D01*
X397520Y459224D01*
X397712Y458965D01*
G01X371647Y460875D02*
Y463975D01*
X372606D01*
X372912Y463820D01*
X373104Y463613D01*
X373181Y463200D01*
X373104Y462787D01*
X372874Y462528D01*
X372606Y462373D01*
X371647D01*
G01X372606D02*
X373181Y460875D01*
G01X375514D02*
Y463975D01*
X375054Y463355D01*
G01Y460875D02*
X375974D01*
G01X377886Y463458D02*
X378116Y463768D01*
X378384Y463923D01*
X378691Y463975D01*
X379074Y463872D01*
X379342Y463613D01*
X379419Y463303D01*
X379381Y462993D01*
X379227Y462735D01*
X378461Y462218D01*
X378116Y461857D01*
X377886Y461340D01*
X377809Y460875D01*
X379419D01*
G01X380871Y461340D02*
X381101Y461082D01*
X381369Y460927D01*
X381714Y460875D01*
X382059Y460978D01*
X382327Y461185D01*
X382519Y461547D01*
X382557Y461960D01*
X382481Y462373D01*
X382289Y462632D01*
X382021Y462838D01*
X381752Y462890D01*
X381484Y462838D01*
X381139Y462632D01*
X381254Y463975D01*
X382289D01*
G01X384814Y460875D02*
X385082Y460927D01*
X385389Y461082D01*
X385581Y461340D01*
X385657Y461702D01*
X385581Y462063D01*
X385351Y462373D01*
X385006Y462528D01*
X384622D01*
X384392Y462632D01*
X384201Y462890D01*
X384124Y463252D01*
X384239Y463613D01*
X384507Y463872D01*
X384814Y463975D01*
X385121Y463872D01*
X385389Y463613D01*
X385504Y463252D01*
X385427Y462890D01*
X385236Y462632D01*
X385006Y462528D01*
X384622D01*
X384277Y462373D01*
X384047Y462063D01*
X383971Y461702D01*
X384047Y461340D01*
X384239Y461082D01*
X384546Y460927D01*
X384814Y460875D01*
G01X379586Y468675D02*
Y465475D01*
G01X373386Y468675D02*
X379586D01*
G01X373386Y465475D02*
Y468675D01*
G01X379586Y465475D02*
X373386D01*
G01X379193Y478669D02*
X378963Y478824D01*
X378695Y478927D01*
X378388D01*
X378043Y478772D01*
X377775Y478514D01*
X377583Y478204D01*
X377430Y477687D01*
X377392Y477222D01*
X377468Y476757D01*
X377583Y476447D01*
X377813Y476137D01*
X378082Y475930D01*
X378350Y475827D01*
X378618D01*
X378887Y475930D01*
X379117Y476085D01*
X379308Y476292D01*
G01X381450Y475827D02*
Y478927D01*
X380990Y478307D01*
G01Y475827D02*
X381910D01*
G01X384550D02*
Y478927D01*
X384090Y478307D01*
G01Y475827D02*
X385010D01*
G01X386922Y478410D02*
X387152Y478720D01*
X387420Y478875D01*
X387727Y478927D01*
X388110Y478824D01*
X388378Y478565D01*
X388455Y478255D01*
X388417Y477945D01*
X388263Y477687D01*
X387497Y477170D01*
X387152Y476809D01*
X386922Y476292D01*
X386845Y475827D01*
X388455D01*
G01X390022Y478410D02*
X390252Y478720D01*
X390520Y478875D01*
X390827Y478927D01*
X391210Y478824D01*
X391478Y478565D01*
X391555Y478255D01*
X391517Y477945D01*
X391363Y477687D01*
X390597Y477170D01*
X390252Y476809D01*
X390022Y476292D01*
X389945Y475827D01*
X391555D01*
G01X375807Y471849D02*
X372607D01*
G01X375807Y478049D02*
Y471849D01*
G01X372607Y478049D02*
X375807D01*
G01X372607Y471849D02*
Y478049D01*
G01X375707Y474949D02*
X372707D01*
G01X378662Y488256D02*
X378432Y488411D01*
X378164Y488514D01*
X377857D01*
X377512Y488359D01*
X377244Y488101D01*
X377052Y487791D01*
X376899Y487274D01*
X376861Y486809D01*
X376937Y486344D01*
X377052Y486034D01*
X377282Y485724D01*
X377551Y485517D01*
X377819Y485414D01*
X378087D01*
X378356Y485517D01*
X378586Y485672D01*
X378777Y485879D01*
G01X380919Y485414D02*
Y488514D01*
X380459Y487894D01*
G01Y485414D02*
X381379D01*
G01X384019D02*
Y488514D01*
X383559Y487894D01*
G01Y485414D02*
X384479D01*
G01X387119D02*
Y488514D01*
X386659Y487894D01*
G01Y485414D02*
X387579D01*
G01X389567Y485776D02*
X389836Y485517D01*
X390142Y485414D01*
X390449Y485517D01*
X390717Y485827D01*
X390909Y486292D01*
X390986Y486757D01*
Y487326D01*
X390909Y487791D01*
X390717Y488204D01*
X390487Y488411D01*
X390219Y488514D01*
X389912Y488411D01*
X389682Y488204D01*
X389529Y487894D01*
X389452Y487481D01*
X389529Y487119D01*
X389721Y486757D01*
X389951Y486551D01*
X390219Y486499D01*
X390526Y486602D01*
X390756Y486861D01*
X390986Y487326D01*
G01X372603Y483349D02*
Y489549D01*
G01X375803Y483349D02*
X372603D01*
G01X375803Y489549D02*
Y483349D01*
G01X372703Y486449D02*
X375703D01*
G01X376610Y490630D02*
Y503520D01*
G01X406000Y490630D02*
X376610D01*
G01X371692Y496487D02*
X371567Y496327D01*
X371484Y496140D01*
Y495927D01*
X371609Y495687D01*
X371817Y495500D01*
X372067Y495367D01*
X372484Y495260D01*
X372859Y495233D01*
X373234Y495287D01*
X373484Y495367D01*
X373734Y495527D01*
X373901Y495713D01*
X373984Y495900D01*
Y496087D01*
X373901Y496273D01*
X373776Y496433D01*
X373609Y496567D01*
G01X373984Y498100D02*
X373942Y498287D01*
X373817Y498500D01*
X373609Y498633D01*
X373317Y498687D01*
X373026Y498633D01*
X372776Y498473D01*
X372651Y498233D01*
Y497967D01*
X372567Y497807D01*
X372359Y497673D01*
X372067Y497620D01*
X371776Y497700D01*
X371567Y497887D01*
X371484Y498100D01*
X371567Y498313D01*
X371776Y498500D01*
X372067Y498580D01*
X372359Y498527D01*
X372567Y498393D01*
X372651Y498233D01*
Y497967D01*
X372776Y497727D01*
X373026Y497567D01*
X373317Y497513D01*
X373609Y497567D01*
X373817Y497700D01*
X373942Y497913D01*
X373984Y498100D01*
G01Y500300D02*
X371484D01*
X371984Y499980D01*
G01X373984D02*
Y500620D01*
G01X371484Y502500D02*
X371567Y502287D01*
X371776Y502127D01*
X372026Y502020D01*
X372359Y501940D01*
X372734Y501913D01*
X373109Y501940D01*
X373442Y502020D01*
X373692Y502127D01*
X373901Y502287D01*
X373984Y502500D01*
X373901Y502713D01*
X373692Y502873D01*
X373442Y502980D01*
X373109Y503060D01*
X372734Y503087D01*
X372359Y503060D01*
X372026Y502980D01*
X371776Y502873D01*
X371567Y502713D01*
X371484Y502500D01*
G01X372603Y489549D02*
X375803D01*
G01X384815Y491717D02*
X381715D01*
Y492637D01*
X381870Y492944D01*
X382232Y493174D01*
X382645Y493251D01*
X383058Y493174D01*
X383368Y492982D01*
X383523Y492637D01*
Y491717D01*
G01X384815Y494817D02*
X381715D01*
Y495776D01*
X381870Y496082D01*
X382077Y496274D01*
X382490Y496351D01*
X382903Y496274D01*
X383162Y496044D01*
X383317Y495776D01*
Y494817D01*
G01Y495776D02*
X384815Y496351D01*
G01Y498607D02*
X384143Y498684D01*
X383575Y498799D01*
X383058Y498952D01*
X382490Y499144D01*
X381715Y499451D01*
Y497917D01*
G01X384453Y501132D02*
X384712Y501401D01*
X384815Y501707D01*
X384712Y502014D01*
X384402Y502282D01*
X383937Y502474D01*
X383472Y502551D01*
X382903D01*
X382438Y502474D01*
X382025Y502282D01*
X381818Y502052D01*
X381715Y501784D01*
X381818Y501477D01*
X382025Y501247D01*
X382335Y501094D01*
X382748Y501017D01*
X383110Y501094D01*
X383472Y501286D01*
X383678Y501516D01*
X383730Y501784D01*
X383627Y502091D01*
X383368Y502321D01*
X382903Y502551D01*
G01X380778Y491717D02*
X377678D01*
Y492637D01*
X377833Y492944D01*
X378195Y493174D01*
X378608Y493251D01*
X379021Y493174D01*
X379331Y492982D01*
X379486Y492637D01*
Y491717D01*
G01X380158Y494817D02*
X380468Y495009D01*
X380675Y495239D01*
X380778Y495507D01*
X380675Y495814D01*
X380468Y496044D01*
X380158Y496274D01*
X379745Y496351D01*
X377678D01*
G01X380778Y498684D02*
X377678D01*
X378298Y498224D01*
G01X380778D02*
Y499144D01*
G01X379486Y501056D02*
X379125Y501324D01*
X378918Y501554D01*
X378815Y501861D01*
X378918Y502129D01*
X379125Y502321D01*
X379435Y502474D01*
X379796Y502512D01*
X380106Y502474D01*
X380416Y502321D01*
X380675Y502091D01*
X380778Y501822D01*
X380675Y501516D01*
X380365Y501247D01*
X379900Y501094D01*
X379383Y501056D01*
X378711Y501132D01*
X378350Y501247D01*
X377988Y501439D01*
X377730Y501707D01*
X377678Y501976D01*
X377781Y502244D01*
X378040Y502436D01*
G01X376610Y503520D02*
X403770D01*
G01X371386Y504517D02*
Y519517D01*
G01X378186Y504517D02*
X371386D01*
G01X378186Y519517D02*
Y504517D01*
G01X378086Y512017D02*
X371486D01*
G01X382286Y516372D02*
X379286D01*
G01X379186Y513272D02*
Y519472D01*
G01X382386D02*
Y513272D01*
G01D02*
X379186D01*
G01X370543Y513998D02*
Y507798D01*
G01X369838Y521053D02*
Y514853D01*
G01X371386Y519517D02*
X378186D01*
G01X379186Y519472D02*
X382386D01*
G01X380558Y520428D02*
Y522928D01*
X380238Y522428D01*
G01Y520428D02*
X380878D01*
G01X382758Y522928D02*
X382545Y522845D01*
X382385Y522636D01*
X382278Y522386D01*
X382198Y522053D01*
X382171Y521678D01*
X382198Y521303D01*
X382278Y520970D01*
X382385Y520720D01*
X382545Y520511D01*
X382758Y520428D01*
X382971Y520511D01*
X383131Y520720D01*
X383238Y520970D01*
X383318Y521303D01*
X383345Y521678D01*
X383318Y522053D01*
X383238Y522386D01*
X383131Y522636D01*
X382971Y522845D01*
X382758Y522928D01*
G01X369345Y524265D02*
Y536273D01*
G01X381353Y524265D02*
Y536273D01*
G01X369345Y524265D02*
X370149D01*
G01X369345Y526369D02*
Y524265D01*
G01X381353D02*
Y526569D01*
G01X380549Y524265D02*
X381353D01*
G01Y533669D02*
Y536273D01*
G01X369345D02*
Y533769D01*
G01X384062Y544935D02*
X390662D01*
G01X383962Y537435D02*
Y552435D01*
G01X390762Y537435D02*
X383962D01*
G01X374159Y545067D02*
Y541867D01*
G01X377561Y549179D02*
Y545979D01*
G01X371361D02*
Y549179D01*
G01X377561Y545979D02*
X371361D01*
G01Y549179D02*
X377561D01*
G01X381248Y549245D02*
X381558Y549437D01*
X381765Y549667D01*
X381868Y549935D01*
X381765Y550242D01*
X381558Y550472D01*
X381248Y550702D01*
X380835Y550779D01*
X378768D01*
G01X379285Y552384D02*
X378975Y552614D01*
X378820Y552882D01*
X378768Y553189D01*
X378871Y553572D01*
X379130Y553840D01*
X379440Y553917D01*
X379750Y553879D01*
X380008Y553725D01*
X380525Y552959D01*
X380886Y552614D01*
X381403Y552384D01*
X381868Y552307D01*
Y553917D01*
G01Y556212D02*
X378768D01*
X379388Y555752D01*
G01X381868D02*
Y556672D01*
G01X381067Y537821D02*
Y540921D01*
X380607Y540301D01*
G01Y537821D02*
X381527D01*
G01X369303Y538279D02*
X369463Y538071D01*
X369650Y537946D01*
X369890Y537904D01*
X370130Y537987D01*
X370317Y538154D01*
X370450Y538446D01*
X370477Y538779D01*
X370423Y539112D01*
X370290Y539321D01*
X370103Y539487D01*
X369917Y539529D01*
X369730Y539487D01*
X369490Y539321D01*
X369570Y540404D01*
X370290D01*
G01X370149Y536273D02*
X369345D01*
G01X381353D02*
X380549D01*
G01X383620Y554960D02*
X395990D01*
G01X383620Y576030D02*
Y554960D01*
G01X383962Y552435D02*
X390762D01*
G01X374461Y553079D02*
Y550079D01*
G01X377561Y553179D02*
Y549979D01*
G01X371361Y553179D02*
X377561D01*
G01X371361Y549979D02*
Y553179D01*
G01X377561Y549979D02*
X371361D01*
G01X384735Y563762D02*
Y566862D01*
X385694D01*
X386000Y566707D01*
X386192Y566500D01*
X386269Y566087D01*
X386192Y565674D01*
X385962Y565415D01*
X385694Y565260D01*
X384735D01*
G01X385694D02*
X386269Y563762D01*
G01X388602D02*
Y566862D01*
X388142Y566242D01*
G01Y563762D02*
X389062D01*
G01X390859Y564382D02*
X391089Y564020D01*
X391395Y563814D01*
X391740Y563762D01*
X392047Y563814D01*
X392354Y564072D01*
X392545Y564382D01*
X392584Y564692D01*
X392507Y565054D01*
X392239Y565312D01*
X391970Y565415D01*
X391625D01*
G01X391970D02*
X392200Y565570D01*
X392392Y565829D01*
X392469Y566139D01*
X392392Y566449D01*
X392200Y566707D01*
X391855Y566862D01*
X391510Y566810D01*
X391165Y566604D01*
G01X394725Y563762D02*
X394802Y564434D01*
X394917Y565002D01*
X395070Y565519D01*
X395262Y566087D01*
X395569Y566862D01*
X394035D01*
G01X384724Y559738D02*
Y562838D01*
X385644D01*
X385951Y562683D01*
X386181Y562321D01*
X386258Y561908D01*
X386181Y561495D01*
X385989Y561185D01*
X385644Y561030D01*
X384724D01*
G01X387824Y559738D02*
Y562838D01*
X388783D01*
X389089Y562683D01*
X389281Y562476D01*
X389358Y562063D01*
X389281Y561650D01*
X389051Y561391D01*
X388783Y561236D01*
X387824D01*
G01X388783D02*
X389358Y559738D01*
G01X392151D02*
Y562838D01*
X390733Y560616D01*
X392649D01*
G01X394063Y561030D02*
X394331Y561391D01*
X394561Y561598D01*
X394868Y561701D01*
X395136Y561598D01*
X395328Y561391D01*
X395481Y561081D01*
X395519Y560720D01*
X395481Y560410D01*
X395328Y560100D01*
X395098Y559841D01*
X394829Y559738D01*
X394523Y559841D01*
X394254Y560151D01*
X394101Y560616D01*
X394063Y561133D01*
X394139Y561805D01*
X394254Y562166D01*
X394446Y562528D01*
X394714Y562786D01*
X394983Y562838D01*
X395251Y562735D01*
X395443Y562476D01*
G01X384724Y555814D02*
Y558914D01*
X385644D01*
X385951Y558759D01*
X386181Y558397D01*
X386258Y557984D01*
X386181Y557571D01*
X385989Y557261D01*
X385644Y557106D01*
X384724D01*
G01X387824Y555814D02*
Y558914D01*
X388783D01*
X389089Y558759D01*
X389281Y558552D01*
X389358Y558139D01*
X389281Y557726D01*
X389051Y557467D01*
X388783Y557312D01*
X387824D01*
G01X388783D02*
X389358Y555814D01*
G01X392151D02*
Y558914D01*
X390733Y556692D01*
X392649D01*
G01X395251Y555814D02*
Y558914D01*
X393833Y556692D01*
X395749D01*
G01X397490Y576030D02*
X383620D01*
G01X384724Y567884D02*
Y570984D01*
X385644D01*
X385951Y570829D01*
X386181Y570467D01*
X386258Y570054D01*
X386181Y569641D01*
X385989Y569331D01*
X385644Y569176D01*
X384724D01*
G01X387824Y567884D02*
Y570984D01*
X388783D01*
X389089Y570829D01*
X389281Y570622D01*
X389358Y570209D01*
X389281Y569796D01*
X389051Y569537D01*
X388783Y569382D01*
X387824D01*
G01X388783D02*
X389358Y567884D01*
G01X390848Y568349D02*
X391078Y568091D01*
X391346Y567936D01*
X391691Y567884D01*
X392036Y567987D01*
X392304Y568194D01*
X392496Y568556D01*
X392534Y568969D01*
X392458Y569382D01*
X392266Y569641D01*
X391998Y569847D01*
X391729Y569899D01*
X391461Y569847D01*
X391116Y569641D01*
X391231Y570984D01*
X392266D01*
G01X394063Y570467D02*
X394293Y570777D01*
X394561Y570932D01*
X394868Y570984D01*
X395251Y570881D01*
X395519Y570622D01*
X395596Y570312D01*
X395558Y570002D01*
X395404Y569744D01*
X394638Y569227D01*
X394293Y568866D01*
X394063Y568349D01*
X393986Y567884D01*
X395596D01*
G01X384724Y571884D02*
Y574984D01*
X385644D01*
X385951Y574829D01*
X386181Y574467D01*
X386258Y574054D01*
X386181Y573641D01*
X385989Y573331D01*
X385644Y573176D01*
X384724D01*
G01X387824Y571884D02*
Y574984D01*
X388783D01*
X389089Y574829D01*
X389281Y574622D01*
X389358Y574209D01*
X389281Y573796D01*
X389051Y573537D01*
X388783Y573382D01*
X387824D01*
G01X388783D02*
X389358Y571884D01*
G01X390848Y572349D02*
X391078Y572091D01*
X391346Y571936D01*
X391691Y571884D01*
X392036Y571987D01*
X392304Y572194D01*
X392496Y572556D01*
X392534Y572969D01*
X392458Y573382D01*
X392266Y573641D01*
X391998Y573847D01*
X391729Y573899D01*
X391461Y573847D01*
X391116Y573641D01*
X391231Y574984D01*
X392266D01*
G01X395251Y571884D02*
Y574984D01*
X393833Y572762D01*
X395749D01*
G01X371800Y625960D02*
Y625360D01*
G01X390930Y625960D02*
X371800D01*
G01X369077Y632338D02*
Y626138D01*
G01X370067Y627935D02*
X370600D01*
Y627185D01*
X370440Y626935D01*
X370254Y626768D01*
X369987Y626685D01*
X369720Y626768D01*
X369534Y626935D01*
X369374Y627185D01*
X369267Y627477D01*
X369214Y627810D01*
Y628102D01*
X369267Y628352D01*
X369374Y628643D01*
X369534Y628893D01*
X369694Y629060D01*
X369907Y629185D01*
X370094D01*
X370307Y629102D01*
X370467Y628935D01*
G01X370718Y626898D02*
Y641898D01*
G01X383718Y626898D02*
X370718D01*
G01X383718Y641898D02*
Y626898D01*
G01X369831Y643707D02*
Y633507D01*
G01X384595Y631740D02*
X384808Y631532D01*
X385048Y631407D01*
X385262D01*
X385475Y631532D01*
X385635Y631740D01*
X385715Y632032D01*
X385662Y632324D01*
X385528Y632574D01*
X385288Y632740D01*
X384968Y632824D01*
X384782Y632990D01*
X384702Y633282D01*
X384755Y633574D01*
X384888Y633782D01*
X385075Y633907D01*
X385262D01*
X385448Y633824D01*
X385608Y633615D01*
G01X378645Y643251D02*
Y645751D01*
X379179D01*
X379392Y645626D01*
X379552Y645459D01*
X379685Y645209D01*
X379792Y644918D01*
X379819Y644501D01*
X379792Y644084D01*
X379685Y643793D01*
X379552Y643543D01*
X379392Y643376D01*
X379179Y643251D01*
X378645D01*
G01X370718Y641898D02*
X383718D01*
G01X371919Y656621D02*
Y659621D01*
G01X375019Y659721D02*
Y656521D01*
G01X371934Y652657D02*
Y655657D01*
G01X375034Y655757D02*
Y652557D01*
G01X374958Y651756D02*
Y648556D01*
G01Y647756D02*
Y644556D01*
G01Y667756D02*
Y664556D01*
G01Y671756D02*
Y668556D01*
G01Y675814D02*
Y672614D01*
G01X371858Y676722D02*
Y679722D01*
G01X374958Y679822D02*
Y676622D01*
G01Y687848D02*
Y684648D01*
G01Y691848D02*
Y688648D01*
G01Y683848D02*
Y680648D01*
G01Y703848D02*
Y700648D01*
G01Y707848D02*
Y704648D01*
G01Y699848D02*
Y696648D01*
G01Y695848D02*
Y692648D01*
G01X382975Y713842D02*
Y717042D01*
G01X389175Y713842D02*
X382975D01*
G01Y717042D02*
X389175D01*
G01X374103Y725222D02*
Y722022D01*
G01X374011Y733059D02*
Y729859D01*
G01X370911Y729959D02*
Y732959D01*
G01X374011Y729059D02*
Y725859D01*
G01X370911Y725959D02*
Y728959D01*
G01X374011Y741059D02*
Y737859D01*
G01X370911Y740959D02*
Y737959D01*
G01X374011Y737059D02*
Y733859D01*
G01Y745059D02*
Y741859D01*
G01X372089Y778176D02*
X372281Y777866D01*
X372511Y777659D01*
X372779Y777556D01*
X373086Y777659D01*
X373316Y777866D01*
X373546Y778176D01*
X373623Y778589D01*
Y780656D01*
G01X375113Y778176D02*
X375343Y777814D01*
X375649Y777608D01*
X375994Y777556D01*
X376301Y777608D01*
X376608Y777866D01*
X376799Y778176D01*
X376838Y778486D01*
X376761Y778848D01*
X376493Y779106D01*
X376224Y779209D01*
X375879D01*
G01X376224D02*
X376454Y779364D01*
X376646Y779623D01*
X376723Y779933D01*
X376646Y780243D01*
X376454Y780501D01*
X376109Y780656D01*
X375764Y780604D01*
X375419Y780398D01*
G01X378213Y778021D02*
X378443Y777763D01*
X378711Y777608D01*
X379056Y777556D01*
X379401Y777659D01*
X379669Y777866D01*
X379861Y778228D01*
X379899Y778641D01*
X379823Y779054D01*
X379631Y779313D01*
X379363Y779519D01*
X379094Y779571D01*
X378826Y779519D01*
X378481Y779313D01*
X378596Y780656D01*
X379631D01*
G01X376503Y785264D02*
X376610Y785389D01*
X376690Y785598D01*
X376743Y785889D01*
X376690Y786139D01*
X376583Y786306D01*
X376397Y786431D01*
X375677D01*
Y783931D01*
X376557D01*
X376743Y784098D01*
X376850Y784348D01*
X376903Y784639D01*
X376850Y784931D01*
X376690Y785181D01*
X376503Y785264D01*
X375677D01*
G01X378490Y783931D02*
Y786431D01*
X378170Y785931D01*
G01Y783931D02*
X378810D01*
G01X380571Y819152D02*
Y788581D01*
G01X378071Y821652D02*
X380571Y819152D01*
G01X387073Y14330D02*
X386843Y14485D01*
X386575Y14588D01*
X386268D01*
X385923Y14433D01*
X385655Y14175D01*
X385463Y13865D01*
X385310Y13348D01*
X385272Y12883D01*
X385348Y12418D01*
X385463Y12108D01*
X385693Y11798D01*
X385962Y11591D01*
X386230Y11488D01*
X386498D01*
X386767Y11591D01*
X386997Y11746D01*
X387188Y11953D01*
G01X388487Y12108D02*
X388717Y11746D01*
X389023Y11540D01*
X389368Y11488D01*
X389675Y11540D01*
X389982Y11798D01*
X390173Y12108D01*
X390212Y12418D01*
X390135Y12780D01*
X389867Y13038D01*
X389598Y13141D01*
X389253D01*
G01X389598D02*
X389828Y13296D01*
X390020Y13555D01*
X390097Y13865D01*
X390020Y14175D01*
X389828Y14433D01*
X389483Y14588D01*
X389138Y14536D01*
X388793Y14330D01*
G01X391587Y12108D02*
X391817Y11746D01*
X392123Y11540D01*
X392468Y11488D01*
X392775Y11540D01*
X393082Y11798D01*
X393273Y12108D01*
X393312Y12418D01*
X393235Y12780D01*
X392967Y13038D01*
X392698Y13141D01*
X392353D01*
G01X392698D02*
X392928Y13296D01*
X393120Y13555D01*
X393197Y13865D01*
X393120Y14175D01*
X392928Y14433D01*
X392583Y14588D01*
X392238Y14536D01*
X391893Y14330D01*
G01X395990Y11488D02*
Y14588D01*
X394572Y12366D01*
X396488D01*
G01X398774Y14621D02*
X398544Y14776D01*
X398276Y14879D01*
X397969D01*
X397624Y14724D01*
X397356Y14466D01*
X397164Y14156D01*
X397011Y13639D01*
X396973Y13174D01*
X397049Y12709D01*
X397164Y12399D01*
X397394Y12089D01*
X397663Y11882D01*
X397931Y11779D01*
X398199D01*
X398468Y11882D01*
X398698Y12037D01*
X398889Y12244D01*
G01X401031Y11779D02*
Y14879D01*
X400571Y14259D01*
G01Y11779D02*
X401491D01*
G01X403288Y12399D02*
X403518Y12037D01*
X403824Y11831D01*
X404169Y11779D01*
X404476Y11831D01*
X404783Y12089D01*
X404974Y12399D01*
X405013Y12709D01*
X404936Y13071D01*
X404668Y13329D01*
X404399Y13432D01*
X404054D01*
G01X404399D02*
X404629Y13587D01*
X404821Y13846D01*
X404898Y14156D01*
X404821Y14466D01*
X404629Y14724D01*
X404284Y14879D01*
X403939Y14827D01*
X403594Y14621D01*
G01X407691Y11779D02*
Y14879D01*
X406273Y12657D01*
X408189D01*
G01X390399Y19119D02*
Y15919D01*
G01X387299Y16019D02*
Y19019D01*
G01X391264Y19119D02*
X397464D01*
G01Y15919D02*
X391264D01*
G01D02*
Y19119D01*
G01X394364Y16019D02*
Y19019D01*
G01X397464Y19119D02*
Y15919D01*
G01X395133Y26152D02*
X392348D01*
G01X406809D02*
X400233D01*
G01X385399Y59661D02*
Y65861D01*
X388599D01*
Y59661D01*
X385399D01*
G01X392894Y56253D02*
X389794D01*
Y57212D01*
X389949Y57518D01*
X390156Y57710D01*
X390569Y57787D01*
X390982Y57710D01*
X391241Y57480D01*
X391396Y57212D01*
Y56253D01*
G01Y57212D02*
X392894Y57787D01*
G01Y60120D02*
X389794D01*
X390414Y59660D01*
G01X392894D02*
Y60580D01*
G01X392532Y62568D02*
X392791Y62837D01*
X392894Y63143D01*
X392791Y63450D01*
X392481Y63718D01*
X392016Y63910D01*
X391551Y63987D01*
X390982D01*
X390517Y63910D01*
X390104Y63718D01*
X389897Y63488D01*
X389794Y63220D01*
X389897Y62913D01*
X390104Y62683D01*
X390414Y62530D01*
X390827Y62453D01*
X391189Y62530D01*
X391551Y62722D01*
X391757Y62952D01*
X391809Y63220D01*
X391706Y63527D01*
X391447Y63757D01*
X390982Y63987D01*
G01X392274Y65477D02*
X392636Y65707D01*
X392842Y66013D01*
X392894Y66358D01*
X392842Y66665D01*
X392584Y66972D01*
X392274Y67163D01*
X391964Y67202D01*
X391602Y67125D01*
X391344Y66857D01*
X391241Y66588D01*
Y66243D01*
G01Y66588D02*
X391086Y66818D01*
X390827Y67010D01*
X390517Y67087D01*
X390207Y67010D01*
X389949Y66818D01*
X389794Y66473D01*
X389846Y66128D01*
X390052Y65783D01*
G01X393480Y59835D02*
Y66035D01*
X396680D01*
Y59835D01*
X393480D01*
G01X392348Y50956D02*
X395133D01*
G01X400233D02*
X406809D01*
G01X399064Y71210D02*
X405264D01*
G01Y68010D02*
X399064D01*
G01D02*
Y71210D01*
G01X392373Y73553D02*
Y76653D01*
X393332D01*
X393638Y76498D01*
X393830Y76291D01*
X393907Y75878D01*
X393830Y75465D01*
X393600Y75206D01*
X393332Y75051D01*
X392373D01*
G01X393332D02*
X393907Y73553D01*
G01X395512Y76136D02*
X395742Y76446D01*
X396010Y76601D01*
X396317Y76653D01*
X396700Y76550D01*
X396968Y76291D01*
X397045Y75981D01*
X397007Y75671D01*
X396853Y75413D01*
X396087Y74896D01*
X395742Y74535D01*
X395512Y74018D01*
X395435Y73553D01*
X397045D01*
G01X399340Y76653D02*
X399033Y76550D01*
X398803Y76291D01*
X398650Y75981D01*
X398535Y75568D01*
X398497Y75103D01*
X398535Y74638D01*
X398650Y74225D01*
X398803Y73915D01*
X399033Y73656D01*
X399340Y73553D01*
X399647Y73656D01*
X399877Y73915D01*
X400030Y74225D01*
X400145Y74638D01*
X400183Y75103D01*
X400145Y75568D01*
X400030Y75981D01*
X399877Y76291D01*
X399647Y76550D01*
X399340Y76653D01*
G01X401597Y74018D02*
X401827Y73760D01*
X402095Y73605D01*
X402440Y73553D01*
X402785Y73656D01*
X403053Y73863D01*
X403245Y74225D01*
X403283Y74638D01*
X403207Y75051D01*
X403015Y75310D01*
X402747Y75516D01*
X402478Y75568D01*
X402210Y75516D01*
X401865Y75310D01*
X401980Y76653D01*
X403015D01*
G01X388696Y68043D02*
Y71243D01*
G01X394896Y68043D02*
X388696D01*
G01Y71243D02*
X394896D01*
G01D02*
Y68043D01*
G01X397181Y124681D02*
X397341Y124931D01*
X397528Y125056D01*
X397741Y125098D01*
X398008Y125015D01*
X398195Y124806D01*
X398248Y124556D01*
X398221Y124306D01*
X398115Y124098D01*
X397581Y123681D01*
X397341Y123390D01*
X397181Y122973D01*
X397128Y122598D01*
X398248D01*
G01X399888Y125098D02*
X399675Y125015D01*
X399515Y124806D01*
X399408Y124556D01*
X399328Y124223D01*
X399301Y123848D01*
X399328Y123473D01*
X399408Y123140D01*
X399515Y122890D01*
X399675Y122681D01*
X399888Y122598D01*
X400101Y122681D01*
X400261Y122890D01*
X400368Y123140D01*
X400448Y123473D01*
X400475Y123848D01*
X400448Y124223D01*
X400368Y124556D01*
X400261Y124806D01*
X400101Y125015D01*
X399888Y125098D01*
G01X402408Y122598D02*
Y125098D01*
X401421Y123306D01*
X402755D01*
G01X401353Y152346D02*
X398253D01*
Y153305D01*
X398408Y153611D01*
X398615Y153803D01*
X399028Y153880D01*
X399441Y153803D01*
X399700Y153573D01*
X399855Y153305D01*
Y152346D01*
G01Y153305D02*
X401353Y153880D01*
G01Y156213D02*
X398253D01*
X398873Y155753D01*
G01X401353D02*
Y156673D01*
G01X400888Y158470D02*
X401146Y158700D01*
X401301Y158968D01*
X401353Y159313D01*
X401250Y159658D01*
X401043Y159926D01*
X400681Y160118D01*
X400268Y160156D01*
X399855Y160080D01*
X399596Y159888D01*
X399390Y159620D01*
X399338Y159351D01*
X399390Y159083D01*
X399596Y158738D01*
X398253Y158853D01*
Y159888D01*
G01X400733Y161570D02*
X401095Y161800D01*
X401301Y162106D01*
X401353Y162451D01*
X401301Y162758D01*
X401043Y163065D01*
X400733Y163256D01*
X400423Y163295D01*
X400061Y163218D01*
X399803Y162950D01*
X399700Y162681D01*
Y162336D01*
G01Y162681D02*
X399545Y162911D01*
X399286Y163103D01*
X398976Y163180D01*
X398666Y163103D01*
X398408Y162911D01*
X398253Y162566D01*
X398305Y162221D01*
X398511Y161876D01*
G01X393353Y152346D02*
X390253D01*
Y153305D01*
X390408Y153611D01*
X390615Y153803D01*
X391028Y153880D01*
X391441Y153803D01*
X391700Y153573D01*
X391855Y153305D01*
Y152346D01*
G01Y153305D02*
X393353Y153880D01*
G01Y156213D02*
X390253D01*
X390873Y155753D01*
G01X393353D02*
Y156673D01*
G01X392061Y158585D02*
X391700Y158853D01*
X391493Y159083D01*
X391390Y159390D01*
X391493Y159658D01*
X391700Y159850D01*
X392010Y160003D01*
X392371Y160041D01*
X392681Y160003D01*
X392991Y159850D01*
X393250Y159620D01*
X393353Y159351D01*
X393250Y159045D01*
X392940Y158776D01*
X392475Y158623D01*
X391958Y158585D01*
X391286Y158661D01*
X390925Y158776D01*
X390563Y158968D01*
X390305Y159236D01*
X390253Y159505D01*
X390356Y159773D01*
X390615Y159965D01*
G01X390253Y162413D02*
X390356Y162106D01*
X390615Y161876D01*
X390925Y161723D01*
X391338Y161608D01*
X391803Y161570D01*
X392268Y161608D01*
X392681Y161723D01*
X392991Y161876D01*
X393250Y162106D01*
X393353Y162413D01*
X393250Y162720D01*
X392991Y162950D01*
X392681Y163103D01*
X392268Y163218D01*
X391803Y163256D01*
X391338Y163218D01*
X390925Y163103D01*
X390615Y162950D01*
X390356Y162720D01*
X390253Y162413D01*
G01X389353Y152346D02*
X386253D01*
Y153305D01*
X386408Y153611D01*
X386615Y153803D01*
X387028Y153880D01*
X387441Y153803D01*
X387700Y153573D01*
X387855Y153305D01*
Y152346D01*
G01Y153305D02*
X389353Y153880D01*
G01Y156213D02*
X386253D01*
X386873Y155753D01*
G01X389353D02*
Y156673D01*
G01X388888Y158470D02*
X389146Y158700D01*
X389301Y158968D01*
X389353Y159313D01*
X389250Y159658D01*
X389043Y159926D01*
X388681Y160118D01*
X388268Y160156D01*
X387855Y160080D01*
X387596Y159888D01*
X387390Y159620D01*
X387338Y159351D01*
X387390Y159083D01*
X387596Y158738D01*
X386253Y158853D01*
Y159888D01*
G01X389353Y162873D02*
X386253D01*
X388475Y161455D01*
Y163371D01*
G01X397353Y152346D02*
X394253D01*
Y153305D01*
X394408Y153611D01*
X394615Y153803D01*
X395028Y153880D01*
X395441Y153803D01*
X395700Y153573D01*
X395855Y153305D01*
Y152346D01*
G01Y153305D02*
X397353Y153880D01*
G01Y156213D02*
X394253D01*
X394873Y155753D01*
G01X397353D02*
Y156673D01*
G01X396888Y158470D02*
X397146Y158700D01*
X397301Y158968D01*
X397353Y159313D01*
X397250Y159658D01*
X397043Y159926D01*
X396681Y160118D01*
X396268Y160156D01*
X395855Y160080D01*
X395596Y159888D01*
X395390Y159620D01*
X395338Y159351D01*
X395390Y159083D01*
X395596Y158738D01*
X394253Y158853D01*
Y159888D01*
G01X397353Y162336D02*
X396681Y162413D01*
X396113Y162528D01*
X395596Y162681D01*
X395028Y162873D01*
X394253Y163180D01*
Y161646D01*
G01X401596Y164646D02*
X398496D01*
Y165605D01*
X398651Y165911D01*
X398858Y166103D01*
X399271Y166180D01*
X399684Y166103D01*
X399943Y165873D01*
X400098Y165605D01*
Y164646D01*
G01Y165605D02*
X401596Y166180D01*
G01Y168513D02*
X398496D01*
X399116Y168053D01*
G01X401596D02*
Y168973D01*
G01X398496Y171613D02*
X398599Y171306D01*
X398858Y171076D01*
X399168Y170923D01*
X399581Y170808D01*
X400046Y170770D01*
X400511Y170808D01*
X400924Y170923D01*
X401234Y171076D01*
X401493Y171306D01*
X401596Y171613D01*
X401493Y171920D01*
X401234Y172150D01*
X400924Y172303D01*
X400511Y172418D01*
X400046Y172456D01*
X399581Y172418D01*
X399168Y172303D01*
X398858Y172150D01*
X398599Y171920D01*
X398496Y171613D01*
G01X401234Y174061D02*
X401493Y174330D01*
X401596Y174636D01*
X401493Y174943D01*
X401183Y175211D01*
X400718Y175403D01*
X400253Y175480D01*
X399684D01*
X399219Y175403D01*
X398806Y175211D01*
X398599Y174981D01*
X398496Y174713D01*
X398599Y174406D01*
X398806Y174176D01*
X399116Y174023D01*
X399529Y173946D01*
X399891Y174023D01*
X400253Y174215D01*
X400459Y174445D01*
X400511Y174713D01*
X400408Y175020D01*
X400149Y175250D01*
X399684Y175480D01*
G01X393699Y164646D02*
X390599D01*
Y165605D01*
X390754Y165911D01*
X390961Y166103D01*
X391374Y166180D01*
X391787Y166103D01*
X392046Y165873D01*
X392201Y165605D01*
Y164646D01*
G01Y165605D02*
X393699Y166180D01*
G01Y168436D02*
X393027Y168513D01*
X392459Y168628D01*
X391942Y168781D01*
X391374Y168973D01*
X390599Y169280D01*
Y167746D01*
G01X393699Y171613D02*
X390599D01*
X391219Y171153D01*
G01X393699D02*
Y172073D01*
G01X389673Y164646D02*
X386573D01*
Y165605D01*
X386728Y165911D01*
X386935Y166103D01*
X387348Y166180D01*
X387761Y166103D01*
X388020Y165873D01*
X388175Y165605D01*
Y164646D01*
G01Y165605D02*
X389673Y166180D01*
G01X388381Y167785D02*
X388020Y168053D01*
X387813Y168283D01*
X387710Y168590D01*
X387813Y168858D01*
X388020Y169050D01*
X388330Y169203D01*
X388691Y169241D01*
X389001Y169203D01*
X389311Y169050D01*
X389570Y168820D01*
X389673Y168551D01*
X389570Y168245D01*
X389260Y167976D01*
X388795Y167823D01*
X388278Y167785D01*
X387606Y167861D01*
X387245Y167976D01*
X386883Y168168D01*
X386625Y168436D01*
X386573Y168705D01*
X386676Y168973D01*
X386935Y169165D01*
G01X389673Y171536D02*
X389001Y171613D01*
X388433Y171728D01*
X387916Y171881D01*
X387348Y172073D01*
X386573Y172380D01*
Y170846D01*
G01X397596Y164646D02*
X394496D01*
Y165605D01*
X394651Y165911D01*
X394858Y166103D01*
X395271Y166180D01*
X395684Y166103D01*
X395943Y165873D01*
X396098Y165605D01*
Y164646D01*
G01Y165605D02*
X397596Y166180D01*
G01Y168513D02*
X394496D01*
X395116Y168053D01*
G01X397596D02*
Y168973D01*
G01Y171613D02*
X394496D01*
X395116Y171153D01*
G01X397596D02*
Y172073D01*
G01Y174713D02*
X394496D01*
X395116Y174253D01*
G01X397596D02*
Y175173D01*
G01X387906Y403463D02*
Y387715D01*
G01X390823Y414376D02*
Y417476D01*
X391743D01*
X392050Y417321D01*
X392280Y416959D01*
X392357Y416546D01*
X392280Y416133D01*
X392088Y415823D01*
X391743Y415668D01*
X390823D01*
G01X395533Y417218D02*
X395303Y417373D01*
X395035Y417476D01*
X394728D01*
X394383Y417321D01*
X394115Y417063D01*
X393923Y416753D01*
X393770Y416236D01*
X393732Y415771D01*
X393808Y415306D01*
X393923Y414996D01*
X394153Y414686D01*
X394422Y414479D01*
X394690Y414376D01*
X394958D01*
X395227Y414479D01*
X395457Y414634D01*
X395648Y414841D01*
G01X397790Y414376D02*
Y417476D01*
X397330Y416856D01*
G01Y414376D02*
X398250D01*
G01X400162Y416959D02*
X400392Y417269D01*
X400660Y417424D01*
X400967Y417476D01*
X401350Y417373D01*
X401618Y417114D01*
X401695Y416804D01*
X401657Y416494D01*
X401503Y416236D01*
X400737Y415719D01*
X400392Y415358D01*
X400162Y414841D01*
X400085Y414376D01*
X401695D01*
G01X403147Y414996D02*
X403377Y414634D01*
X403683Y414428D01*
X404028Y414376D01*
X404335Y414428D01*
X404642Y414686D01*
X404833Y414996D01*
X404872Y415306D01*
X404795Y415668D01*
X404527Y415926D01*
X404258Y416029D01*
X403913D01*
G01X404258D02*
X404488Y416184D01*
X404680Y416443D01*
X404757Y416753D01*
X404680Y417063D01*
X404488Y417321D01*
X404143Y417476D01*
X403798Y417424D01*
X403453Y417218D01*
G01X391203Y420686D02*
Y423786D01*
X392123D01*
X392430Y423631D01*
X392660Y423269D01*
X392737Y422856D01*
X392660Y422443D01*
X392468Y422133D01*
X392123Y421978D01*
X391203D01*
G01X395913Y423528D02*
X395683Y423683D01*
X395415Y423786D01*
X395108D01*
X394763Y423631D01*
X394495Y423373D01*
X394303Y423063D01*
X394150Y422546D01*
X394112Y422081D01*
X394188Y421616D01*
X394303Y421306D01*
X394533Y420996D01*
X394802Y420789D01*
X395070Y420686D01*
X395338D01*
X395607Y420789D01*
X395837Y420944D01*
X396028Y421151D01*
G01X398170Y420686D02*
Y423786D01*
X397710Y423166D01*
G01Y420686D02*
X398630D01*
G01X401270D02*
Y423786D01*
X400810Y423166D01*
G01Y420686D02*
X401730D01*
G01X403718Y421048D02*
X403987Y420789D01*
X404293Y420686D01*
X404600Y420789D01*
X404868Y421099D01*
X405060Y421564D01*
X405137Y422029D01*
Y422598D01*
X405060Y423063D01*
X404868Y423476D01*
X404638Y423683D01*
X404370Y423786D01*
X404063Y423683D01*
X403833Y423476D01*
X403680Y423166D01*
X403603Y422753D01*
X403680Y422391D01*
X403872Y422029D01*
X404102Y421823D01*
X404370Y421771D01*
X404677Y421874D01*
X404907Y422133D01*
X405137Y422598D01*
G01X391719Y435026D02*
Y438126D01*
X392639D01*
X392946Y437971D01*
X393176Y437609D01*
X393253Y437196D01*
X393176Y436783D01*
X392984Y436473D01*
X392639Y436318D01*
X391719D01*
G01X396429Y437868D02*
X396199Y438023D01*
X395931Y438126D01*
X395624D01*
X395279Y437971D01*
X395011Y437713D01*
X394819Y437403D01*
X394666Y436886D01*
X394628Y436421D01*
X394704Y435956D01*
X394819Y435646D01*
X395049Y435336D01*
X395318Y435129D01*
X395586Y435026D01*
X395854D01*
X396123Y435129D01*
X396353Y435284D01*
X396544Y435491D01*
G01X398686Y435026D02*
Y438126D01*
X398226Y437506D01*
G01Y435026D02*
X399146D01*
G01X401786Y438126D02*
X401479Y438023D01*
X401249Y437764D01*
X401096Y437454D01*
X400981Y437041D01*
X400943Y436576D01*
X400981Y436111D01*
X401096Y435698D01*
X401249Y435388D01*
X401479Y435129D01*
X401786Y435026D01*
X402093Y435129D01*
X402323Y435388D01*
X402476Y435698D01*
X402591Y436111D01*
X402629Y436576D01*
X402591Y437041D01*
X402476Y437454D01*
X402323Y437764D01*
X402093Y438023D01*
X401786Y438126D01*
G01X404809Y435026D02*
X404886Y435698D01*
X405001Y436266D01*
X405154Y436783D01*
X405346Y437351D01*
X405653Y438126D01*
X404119D01*
G01X391556Y428073D02*
Y431173D01*
X392476D01*
X392783Y431018D01*
X393013Y430656D01*
X393090Y430243D01*
X393013Y429830D01*
X392821Y429520D01*
X392476Y429365D01*
X391556D01*
G01X396266Y430915D02*
X396036Y431070D01*
X395768Y431173D01*
X395461D01*
X395116Y431018D01*
X394848Y430760D01*
X394656Y430450D01*
X394503Y429933D01*
X394465Y429468D01*
X394541Y429003D01*
X394656Y428693D01*
X394886Y428383D01*
X395155Y428176D01*
X395423Y428073D01*
X395691D01*
X395960Y428176D01*
X396190Y428331D01*
X396381Y428538D01*
G01X398523Y428073D02*
Y431173D01*
X398063Y430553D01*
G01Y428073D02*
X398983D01*
G01X401623Y431173D02*
X401316Y431070D01*
X401086Y430811D01*
X400933Y430501D01*
X400818Y430088D01*
X400780Y429623D01*
X400818Y429158D01*
X400933Y428745D01*
X401086Y428435D01*
X401316Y428176D01*
X401623Y428073D01*
X401930Y428176D01*
X402160Y428435D01*
X402313Y428745D01*
X402428Y429158D01*
X402466Y429623D01*
X402428Y430088D01*
X402313Y430501D01*
X402160Y430811D01*
X401930Y431070D01*
X401623Y431173D01*
G01X403995Y429365D02*
X404263Y429726D01*
X404493Y429933D01*
X404800Y430036D01*
X405068Y429933D01*
X405260Y429726D01*
X405413Y429416D01*
X405451Y429055D01*
X405413Y428745D01*
X405260Y428435D01*
X405030Y428176D01*
X404761Y428073D01*
X404455Y428176D01*
X404186Y428486D01*
X404033Y428951D01*
X403995Y429468D01*
X404071Y430140D01*
X404186Y430501D01*
X404378Y430863D01*
X404646Y431121D01*
X404915Y431173D01*
X405183Y431070D01*
X405375Y430811D01*
G01X391643Y440537D02*
Y443637D01*
X392563D01*
X392870Y443482D01*
X393100Y443120D01*
X393177Y442707D01*
X393100Y442294D01*
X392908Y441984D01*
X392563Y441829D01*
X391643D01*
G01X396353Y443379D02*
X396123Y443534D01*
X395855Y443637D01*
X395548D01*
X395203Y443482D01*
X394935Y443224D01*
X394743Y442914D01*
X394590Y442397D01*
X394552Y441932D01*
X394628Y441467D01*
X394743Y441157D01*
X394973Y440847D01*
X395242Y440640D01*
X395510Y440537D01*
X395778D01*
X396047Y440640D01*
X396277Y440795D01*
X396468Y441002D01*
G01X398610Y440537D02*
Y443637D01*
X398150Y443017D01*
G01Y440537D02*
X399070D01*
G01X400982Y443120D02*
X401212Y443430D01*
X401480Y443585D01*
X401787Y443637D01*
X402170Y443534D01*
X402438Y443275D01*
X402515Y442965D01*
X402477Y442655D01*
X402323Y442397D01*
X401557Y441880D01*
X401212Y441519D01*
X400982Y441002D01*
X400905Y440537D01*
X402515D01*
G01X404810Y443637D02*
X404503Y443534D01*
X404273Y443275D01*
X404120Y442965D01*
X404005Y442552D01*
X403967Y442087D01*
X404005Y441622D01*
X404120Y441209D01*
X404273Y440899D01*
X404503Y440640D01*
X404810Y440537D01*
X405117Y440640D01*
X405347Y440899D01*
X405500Y441209D01*
X405615Y441622D01*
X405653Y442087D01*
X405615Y442552D01*
X405500Y442965D01*
X405347Y443275D01*
X405117Y443534D01*
X404810Y443637D01*
G01X414311Y449430D02*
X399311D01*
G01D02*
Y456230D01*
G01X414311Y457174D02*
X399311D01*
G01D02*
Y463974D01*
G01D02*
X414311D01*
G01X399311Y456230D02*
X414311D01*
G01X394497Y465586D02*
Y468686D01*
X395417D01*
X395724Y468531D01*
X395954Y468169D01*
X396031Y467756D01*
X395954Y467343D01*
X395762Y467033D01*
X395417Y466878D01*
X394497D01*
G01X397597Y465586D02*
Y468686D01*
X398556D01*
X398862Y468531D01*
X399054Y468324D01*
X399131Y467911D01*
X399054Y467498D01*
X398824Y467239D01*
X398556Y467084D01*
X397597D01*
G01X398556D02*
X399131Y465586D01*
G01X400621Y466051D02*
X400851Y465793D01*
X401119Y465638D01*
X401464Y465586D01*
X401809Y465689D01*
X402077Y465896D01*
X402269Y466258D01*
X402307Y466671D01*
X402231Y467084D01*
X402039Y467343D01*
X401771Y467549D01*
X401502Y467601D01*
X401234Y467549D01*
X400889Y467343D01*
X401004Y468686D01*
X402039D01*
G01X403836Y466878D02*
X404104Y467239D01*
X404334Y467446D01*
X404641Y467549D01*
X404909Y467446D01*
X405101Y467239D01*
X405254Y466929D01*
X405292Y466568D01*
X405254Y466258D01*
X405101Y465948D01*
X404871Y465689D01*
X404602Y465586D01*
X404296Y465689D01*
X404027Y465999D01*
X403874Y466464D01*
X403836Y466981D01*
X403912Y467653D01*
X404027Y468014D01*
X404219Y468376D01*
X404487Y468634D01*
X404756Y468686D01*
X405024Y468583D01*
X405216Y468324D01*
G01X398256Y476349D02*
Y479449D01*
X399176D01*
X399483Y479294D01*
X399713Y478932D01*
X399790Y478519D01*
X399713Y478106D01*
X399521Y477796D01*
X399176Y477641D01*
X398256D01*
G01X401356Y476349D02*
Y479449D01*
X402315D01*
X402621Y479294D01*
X402813Y479087D01*
X402890Y478674D01*
X402813Y478261D01*
X402583Y478002D01*
X402315Y477847D01*
X401356D01*
G01X402315D02*
X402890Y476349D01*
G01X405146D02*
X405223Y477021D01*
X405338Y477589D01*
X405491Y478106D01*
X405683Y478674D01*
X405990Y479449D01*
X404456D01*
G01X407480Y476814D02*
X407710Y476556D01*
X407978Y476401D01*
X408323Y476349D01*
X408668Y476452D01*
X408936Y476659D01*
X409128Y477021D01*
X409166Y477434D01*
X409090Y477847D01*
X408898Y478106D01*
X408630Y478312D01*
X408361Y478364D01*
X408093Y478312D01*
X407748Y478106D01*
X407863Y479449D01*
X408898D01*
G01X394824Y492581D02*
Y495681D01*
X395744D01*
X396051Y495526D01*
X396281Y495164D01*
X396358Y494751D01*
X396281Y494338D01*
X396089Y494028D01*
X395744Y493873D01*
X394824D01*
G01X399534Y495423D02*
X399304Y495578D01*
X399036Y495681D01*
X398729D01*
X398384Y495526D01*
X398116Y495268D01*
X397924Y494958D01*
X397771Y494441D01*
X397733Y493976D01*
X397809Y493511D01*
X397924Y493201D01*
X398154Y492891D01*
X398423Y492684D01*
X398691Y492581D01*
X398959D01*
X399228Y492684D01*
X399458Y492839D01*
X399649Y493046D01*
G01X401139Y492943D02*
X401408Y492684D01*
X401714Y492581D01*
X402021Y492684D01*
X402289Y492994D01*
X402481Y493459D01*
X402558Y493924D01*
Y494493D01*
X402481Y494958D01*
X402289Y495371D01*
X402059Y495578D01*
X401791Y495681D01*
X401484Y495578D01*
X401254Y495371D01*
X401101Y495061D01*
X401024Y494648D01*
X401101Y494286D01*
X401293Y493924D01*
X401523Y493718D01*
X401791Y493666D01*
X402098Y493769D01*
X402328Y494028D01*
X402558Y494493D01*
G01X404163Y493873D02*
X404431Y494234D01*
X404661Y494441D01*
X404968Y494544D01*
X405236Y494441D01*
X405428Y494234D01*
X405581Y493924D01*
X405619Y493563D01*
X405581Y493253D01*
X405428Y492943D01*
X405198Y492684D01*
X404929Y492581D01*
X404623Y492684D01*
X404354Y492994D01*
X404201Y493459D01*
X404163Y493976D01*
X404239Y494648D01*
X404354Y495009D01*
X404546Y495371D01*
X404814Y495629D01*
X405083Y495681D01*
X405351Y495578D01*
X405543Y495319D01*
G01X393944Y491553D02*
X390844D01*
Y492473D01*
X390999Y492780D01*
X391361Y493010D01*
X391774Y493087D01*
X392187Y493010D01*
X392497Y492818D01*
X392652Y492473D01*
Y491553D01*
G01X391102Y496263D02*
X390947Y496033D01*
X390844Y495765D01*
Y495458D01*
X390999Y495113D01*
X391257Y494845D01*
X391567Y494653D01*
X392084Y494500D01*
X392549Y494462D01*
X393014Y494538D01*
X393324Y494653D01*
X393634Y494883D01*
X393841Y495152D01*
X393944Y495420D01*
Y495688D01*
X393841Y495957D01*
X393686Y496187D01*
X393479Y496378D01*
G01X393944Y498520D02*
X393892Y498788D01*
X393737Y499095D01*
X393479Y499287D01*
X393117Y499363D01*
X392756Y499287D01*
X392446Y499057D01*
X392291Y498712D01*
Y498328D01*
X392187Y498098D01*
X391929Y497907D01*
X391567Y497830D01*
X391206Y497945D01*
X390947Y498213D01*
X390844Y498520D01*
X390947Y498827D01*
X391206Y499095D01*
X391567Y499210D01*
X391929Y499133D01*
X392187Y498942D01*
X392291Y498712D01*
Y498328D01*
X392446Y497983D01*
X392756Y497753D01*
X393117Y497677D01*
X393479Y497753D01*
X393737Y497945D01*
X393892Y498252D01*
X393944Y498520D01*
G01Y501620D02*
X393892Y501888D01*
X393737Y502195D01*
X393479Y502387D01*
X393117Y502463D01*
X392756Y502387D01*
X392446Y502157D01*
X392291Y501812D01*
Y501428D01*
X392187Y501198D01*
X391929Y501007D01*
X391567Y500930D01*
X391206Y501045D01*
X390947Y501313D01*
X390844Y501620D01*
X390947Y501927D01*
X391206Y502195D01*
X391567Y502310D01*
X391929Y502233D01*
X392187Y502042D01*
X392291Y501812D01*
Y501428D01*
X392446Y501083D01*
X392756Y500853D01*
X393117Y500777D01*
X393479Y500853D01*
X393737Y501045D01*
X393892Y501352D01*
X393944Y501620D01*
G01X394748Y497751D02*
Y500851D01*
X395668D01*
X395975Y500696D01*
X396205Y500334D01*
X396282Y499921D01*
X396205Y499508D01*
X396013Y499198D01*
X395668Y499043D01*
X394748D01*
G01X397848Y497751D02*
Y500851D01*
X398807D01*
X399113Y500696D01*
X399305Y500489D01*
X399382Y500076D01*
X399305Y499663D01*
X399075Y499404D01*
X398807Y499249D01*
X397848D01*
G01X398807D02*
X399382Y497751D01*
G01X400872Y498216D02*
X401102Y497958D01*
X401370Y497803D01*
X401715Y497751D01*
X402060Y497854D01*
X402328Y498061D01*
X402520Y498423D01*
X402558Y498836D01*
X402482Y499249D01*
X402290Y499508D01*
X402022Y499714D01*
X401753Y499766D01*
X401485Y499714D01*
X401140Y499508D01*
X401255Y500851D01*
X402290D01*
G01X404815Y497751D02*
Y500851D01*
X404355Y500231D01*
G01Y497751D02*
X405275D01*
G01X388815Y491717D02*
X385715D01*
Y492637D01*
X385870Y492944D01*
X386232Y493174D01*
X386645Y493251D01*
X387058Y493174D01*
X387368Y492982D01*
X387523Y492637D01*
Y491717D01*
G01X388815Y494817D02*
X385715D01*
Y495776D01*
X385870Y496082D01*
X386077Y496274D01*
X386490Y496351D01*
X386903Y496274D01*
X387162Y496044D01*
X387317Y495776D01*
Y494817D01*
G01Y495776D02*
X388815Y496351D01*
G01Y499144D02*
X385715D01*
X387937Y497726D01*
Y499642D01*
G01X388815Y501784D02*
X388763Y502052D01*
X388608Y502359D01*
X388350Y502551D01*
X387988Y502627D01*
X387627Y502551D01*
X387317Y502321D01*
X387162Y501976D01*
Y501592D01*
X387058Y501362D01*
X386800Y501171D01*
X386438Y501094D01*
X386077Y501209D01*
X385818Y501477D01*
X385715Y501784D01*
X385818Y502091D01*
X386077Y502359D01*
X386438Y502474D01*
X386800Y502397D01*
X387058Y502206D01*
X387162Y501976D01*
Y501592D01*
X387317Y501247D01*
X387627Y501017D01*
X387988Y500941D01*
X388350Y501017D01*
X388608Y501209D01*
X388763Y501516D01*
X388815Y501784D01*
G01X385802Y518953D02*
X385647Y518723D01*
X385544Y518455D01*
Y518148D01*
X385699Y517803D01*
X385957Y517535D01*
X386267Y517343D01*
X386784Y517190D01*
X387249Y517152D01*
X387714Y517228D01*
X388024Y517343D01*
X388334Y517573D01*
X388541Y517842D01*
X388644Y518110D01*
Y518378D01*
X388541Y518647D01*
X388386Y518877D01*
X388179Y519068D01*
G01X388644Y521210D02*
X388592Y521478D01*
X388437Y521785D01*
X388179Y521977D01*
X387817Y522053D01*
X387456Y521977D01*
X387146Y521747D01*
X386991Y521402D01*
Y521018D01*
X386887Y520788D01*
X386629Y520597D01*
X386267Y520520D01*
X385906Y520635D01*
X385647Y520903D01*
X385544Y521210D01*
X385647Y521517D01*
X385906Y521785D01*
X386267Y521900D01*
X386629Y521823D01*
X386887Y521632D01*
X386991Y521402D01*
Y521018D01*
X387146Y520673D01*
X387456Y520443D01*
X387817Y520367D01*
X388179Y520443D01*
X388437Y520635D01*
X388592Y520942D01*
X388644Y521210D01*
G01X385544Y524310D02*
X385647Y524003D01*
X385906Y523773D01*
X386216Y523620D01*
X386629Y523505D01*
X387094Y523467D01*
X387559Y523505D01*
X387972Y523620D01*
X388282Y523773D01*
X388541Y524003D01*
X388644Y524310D01*
X388541Y524617D01*
X388282Y524847D01*
X387972Y525000D01*
X387559Y525115D01*
X387094Y525153D01*
X386629Y525115D01*
X386216Y525000D01*
X385906Y524847D01*
X385647Y524617D01*
X385544Y524310D01*
G01X388282Y526758D02*
X388541Y527027D01*
X388644Y527333D01*
X388541Y527640D01*
X388231Y527908D01*
X387766Y528100D01*
X387301Y528177D01*
X386732D01*
X386267Y528100D01*
X385854Y527908D01*
X385647Y527678D01*
X385544Y527410D01*
X385647Y527103D01*
X385854Y526873D01*
X386164Y526720D01*
X386577Y526643D01*
X386939Y526720D01*
X387301Y526912D01*
X387507Y527142D01*
X387559Y527410D01*
X387456Y527717D01*
X387197Y527947D01*
X386732Y528177D01*
G01X388475Y504677D02*
X385375D01*
Y505597D01*
X385530Y505904D01*
X385892Y506134D01*
X386305Y506211D01*
X386718Y506134D01*
X387028Y505942D01*
X387183Y505597D01*
Y504677D01*
G01X388475Y507777D02*
X385375D01*
Y508736D01*
X385530Y509042D01*
X385737Y509234D01*
X386150Y509311D01*
X386563Y509234D01*
X386822Y509004D01*
X386977Y508736D01*
Y507777D01*
G01Y508736D02*
X388475Y509311D01*
G01Y512104D02*
X385375D01*
X387597Y510686D01*
Y512602D01*
G01X388010Y513901D02*
X388268Y514131D01*
X388423Y514399D01*
X388475Y514744D01*
X388372Y515089D01*
X388165Y515357D01*
X387803Y515549D01*
X387390Y515587D01*
X386977Y515511D01*
X386718Y515319D01*
X386512Y515051D01*
X386460Y514782D01*
X386512Y514514D01*
X386718Y514169D01*
X385375Y514284D01*
Y515319D01*
G01X394056Y514772D02*
Y520972D01*
G01X397256Y514772D02*
X394056D01*
G01X397256Y520972D02*
Y514772D01*
G01X392649Y504677D02*
X389549D01*
Y505597D01*
X389704Y505904D01*
X390066Y506134D01*
X390479Y506211D01*
X390892Y506134D01*
X391202Y505942D01*
X391357Y505597D01*
Y504677D01*
G01X392649Y507777D02*
X389549D01*
Y508736D01*
X389704Y509042D01*
X389911Y509234D01*
X390324Y509311D01*
X390737Y509234D01*
X390996Y509004D01*
X391151Y508736D01*
Y507777D01*
G01Y508736D02*
X392649Y509311D01*
G01X392184Y510801D02*
X392442Y511031D01*
X392597Y511299D01*
X392649Y511644D01*
X392546Y511989D01*
X392339Y512257D01*
X391977Y512449D01*
X391564Y512487D01*
X391151Y512411D01*
X390892Y512219D01*
X390686Y511951D01*
X390634Y511682D01*
X390686Y511414D01*
X390892Y511069D01*
X389549Y511184D01*
Y512219D01*
G01Y514744D02*
X389652Y514437D01*
X389911Y514207D01*
X390221Y514054D01*
X390634Y513939D01*
X391099Y513901D01*
X391564Y513939D01*
X391977Y514054D01*
X392287Y514207D01*
X392546Y514437D01*
X392649Y514744D01*
X392546Y515051D01*
X392287Y515281D01*
X391977Y515434D01*
X391564Y515549D01*
X391099Y515587D01*
X390634Y515549D01*
X390221Y515434D01*
X389911Y515281D01*
X389652Y515051D01*
X389549Y514744D01*
G01X398237Y514772D02*
Y520972D01*
G01X401437Y514772D02*
X398237D01*
G01X395990Y521650D02*
X398600D01*
G01X395990Y554960D02*
Y521650D01*
G01X398600D02*
X405670D01*
G01X390252Y526343D02*
X390097Y526113D01*
X389994Y525845D01*
Y525538D01*
X390149Y525193D01*
X390407Y524925D01*
X390717Y524733D01*
X391234Y524580D01*
X391699Y524542D01*
X392164Y524618D01*
X392474Y524733D01*
X392784Y524963D01*
X392991Y525232D01*
X393094Y525500D01*
Y525768D01*
X392991Y526037D01*
X392836Y526267D01*
X392629Y526458D01*
G01X393094Y528600D02*
X393042Y528868D01*
X392887Y529175D01*
X392629Y529367D01*
X392267Y529443D01*
X391906Y529367D01*
X391596Y529137D01*
X391441Y528792D01*
Y528408D01*
X391337Y528178D01*
X391079Y527987D01*
X390717Y527910D01*
X390356Y528025D01*
X390097Y528293D01*
X389994Y528600D01*
X390097Y528907D01*
X390356Y529175D01*
X390717Y529290D01*
X391079Y529213D01*
X391337Y529022D01*
X391441Y528792D01*
Y528408D01*
X391596Y528063D01*
X391906Y527833D01*
X392267Y527757D01*
X392629Y527833D01*
X392887Y528025D01*
X393042Y528332D01*
X393094Y528600D01*
G01Y531700D02*
X389994D01*
X390614Y531240D01*
G01X393094D02*
Y532160D01*
G01Y535260D02*
X389994D01*
X392216Y533842D01*
Y535758D01*
G01X388721Y532838D02*
X385721D01*
G01X388821Y529738D02*
X385621D01*
G01X388821Y535938D02*
Y529738D01*
G01X385621D02*
Y535938D01*
G01X398629Y530416D02*
Y533616D01*
G01X404829Y530416D02*
X398629D01*
G01Y533616D02*
X404829D01*
G01X398539Y529615D02*
X404739D01*
G01X398539Y526415D02*
Y529615D01*
G01X404739Y526415D02*
X398539D01*
G01X398501Y525691D02*
X404701D01*
G01X398501Y522491D02*
Y525691D01*
G01X404701Y522491D02*
X398501D01*
G01X394056Y520972D02*
X397256D01*
G01X398237D02*
X401437D01*
G01X397490Y542980D02*
Y576030D01*
G01X405670Y542980D02*
X397490D01*
G01X392053Y543688D02*
X391898Y543458D01*
X391795Y543190D01*
Y542883D01*
X391950Y542538D01*
X392208Y542270D01*
X392518Y542078D01*
X393035Y541925D01*
X393500Y541887D01*
X393965Y541963D01*
X394275Y542078D01*
X394585Y542308D01*
X394792Y542577D01*
X394895Y542845D01*
Y543113D01*
X394792Y543382D01*
X394637Y543612D01*
X394430Y543803D01*
G01X394895Y545945D02*
X394843Y546213D01*
X394688Y546520D01*
X394430Y546712D01*
X394068Y546788D01*
X393707Y546712D01*
X393397Y546482D01*
X393242Y546137D01*
Y545753D01*
X393138Y545523D01*
X392880Y545332D01*
X392518Y545255D01*
X392157Y545370D01*
X391898Y545638D01*
X391795Y545945D01*
X391898Y546252D01*
X392157Y546520D01*
X392518Y546635D01*
X392880Y546558D01*
X393138Y546367D01*
X393242Y546137D01*
Y545753D01*
X393397Y545408D01*
X393707Y545178D01*
X394068Y545102D01*
X394430Y545178D01*
X394688Y545370D01*
X394843Y545677D01*
X394895Y545945D01*
G01Y549045D02*
X391795D01*
X392415Y548585D01*
G01X394895D02*
Y549505D01*
G01X392312Y551417D02*
X392002Y551647D01*
X391847Y551915D01*
X391795Y552222D01*
X391898Y552605D01*
X392157Y552873D01*
X392467Y552950D01*
X392777Y552912D01*
X393035Y552758D01*
X393552Y551992D01*
X393913Y551647D01*
X394430Y551417D01*
X394895Y551340D01*
Y552950D01*
G01X390762Y552435D02*
Y537435D01*
G01X385621Y535938D02*
X388821D01*
G01X398512Y534527D02*
Y537727D01*
G01X404712Y534527D02*
X398512D01*
G01Y537727D02*
X404712D01*
G01X398712Y538527D02*
Y541727D01*
G01X404912Y538527D02*
X398712D01*
G01Y541727D02*
X404912D01*
G01X398427Y561227D02*
Y563727D01*
X399067D01*
X399280Y563602D01*
X399440Y563310D01*
X399493Y562977D01*
X399440Y562644D01*
X399307Y562394D01*
X399067Y562269D01*
X398427D01*
G01X401747Y563519D02*
X401587Y563644D01*
X401400Y563727D01*
X401187D01*
X400947Y563602D01*
X400760Y563394D01*
X400627Y563144D01*
X400520Y562727D01*
X400493Y562352D01*
X400547Y561977D01*
X400627Y561727D01*
X400787Y561477D01*
X400973Y561310D01*
X401160Y561227D01*
X401347D01*
X401533Y561310D01*
X401693Y561435D01*
X401827Y561602D01*
G01X403360Y561227D02*
Y563727D01*
X403040Y563227D01*
G01Y561227D02*
X403680D01*
G01X405560D02*
Y563727D01*
X405240Y563227D01*
G01Y561227D02*
X405880D01*
G01X407173Y561602D02*
X407333Y561394D01*
X407520Y561269D01*
X407760Y561227D01*
X408000Y561310D01*
X408187Y561477D01*
X408320Y561769D01*
X408347Y562102D01*
X408293Y562435D01*
X408160Y562644D01*
X407973Y562810D01*
X407787Y562852D01*
X407600Y562810D01*
X407360Y562644D01*
X407440Y563727D01*
X408160D01*
G01X400330Y565312D02*
Y567812D01*
X400970D01*
X401183Y567687D01*
X401343Y567395D01*
X401396Y567062D01*
X401343Y566729D01*
X401210Y566479D01*
X400970Y566354D01*
X400330D01*
G01X402530Y565312D02*
Y567812D01*
X403196D01*
X403410Y567687D01*
X403543Y567520D01*
X403596Y567187D01*
X403543Y566854D01*
X403383Y566645D01*
X403196Y566520D01*
X402530D01*
G01X403196D02*
X403596Y565312D01*
G01X405210D02*
X405263Y565854D01*
X405343Y566312D01*
X405450Y566729D01*
X405583Y567187D01*
X405796Y567812D01*
X404730D01*
G01X407463Y565312D02*
X407650Y565354D01*
X407863Y565479D01*
X407996Y565687D01*
X408050Y565979D01*
X407996Y566270D01*
X407836Y566520D01*
X407596Y566645D01*
X407330D01*
X407170Y566729D01*
X407036Y566937D01*
X406983Y567229D01*
X407063Y567520D01*
X407250Y567729D01*
X407463Y567812D01*
X407676Y567729D01*
X407863Y567520D01*
X407943Y567229D01*
X407890Y566937D01*
X407756Y566729D01*
X407596Y566645D01*
X407330D01*
X407090Y566520D01*
X406930Y566270D01*
X406876Y565979D01*
X406930Y565687D01*
X407063Y565479D01*
X407276Y565354D01*
X407463Y565312D01*
G01X400330Y570052D02*
Y572552D01*
X400970D01*
X401183Y572427D01*
X401343Y572135D01*
X401396Y571802D01*
X401343Y571469D01*
X401210Y571219D01*
X400970Y571094D01*
X400330D01*
G01X403650Y572344D02*
X403490Y572469D01*
X403303Y572552D01*
X403090D01*
X402850Y572427D01*
X402663Y572219D01*
X402530Y571969D01*
X402423Y571552D01*
X402396Y571177D01*
X402450Y570802D01*
X402530Y570552D01*
X402690Y570302D01*
X402876Y570135D01*
X403063Y570052D01*
X403250D01*
X403436Y570135D01*
X403596Y570260D01*
X403730Y570427D01*
G01X404810Y570344D02*
X404996Y570135D01*
X405210Y570052D01*
X405423Y570135D01*
X405610Y570385D01*
X405743Y570760D01*
X405796Y571135D01*
Y571594D01*
X405743Y571969D01*
X405610Y572302D01*
X405450Y572469D01*
X405263Y572552D01*
X405050Y572469D01*
X404890Y572302D01*
X404783Y572052D01*
X404730Y571719D01*
X404783Y571427D01*
X404916Y571135D01*
X405076Y570969D01*
X405263Y570927D01*
X405476Y571010D01*
X405636Y571219D01*
X405796Y571594D01*
G01X407410Y570052D02*
X407463Y570594D01*
X407543Y571052D01*
X407650Y571469D01*
X407783Y571927D01*
X407996Y572552D01*
X406930D01*
G01X386011Y579696D02*
Y582796D01*
X386931D01*
X387238Y582641D01*
X387468Y582279D01*
X387545Y581866D01*
X387468Y581453D01*
X387276Y581143D01*
X386931Y580988D01*
X386011D01*
G01X390721Y582538D02*
X390491Y582693D01*
X390223Y582796D01*
X389916D01*
X389571Y582641D01*
X389303Y582383D01*
X389111Y582073D01*
X388958Y581556D01*
X388920Y581091D01*
X388996Y580626D01*
X389111Y580316D01*
X389341Y580006D01*
X389610Y579799D01*
X389878Y579696D01*
X390146D01*
X390415Y579799D01*
X390645Y579954D01*
X390836Y580161D01*
G01X392135Y580316D02*
X392365Y579954D01*
X392671Y579748D01*
X393016Y579696D01*
X393323Y579748D01*
X393630Y580006D01*
X393821Y580316D01*
X393860Y580626D01*
X393783Y580988D01*
X393515Y581246D01*
X393246Y581349D01*
X392901D01*
G01X393246D02*
X393476Y581504D01*
X393668Y581763D01*
X393745Y582073D01*
X393668Y582383D01*
X393476Y582641D01*
X393131Y582796D01*
X392786Y582744D01*
X392441Y582538D01*
G01X395350Y582279D02*
X395580Y582589D01*
X395848Y582744D01*
X396155Y582796D01*
X396538Y582693D01*
X396806Y582434D01*
X396883Y582124D01*
X396845Y581814D01*
X396691Y581556D01*
X395925Y581039D01*
X395580Y580678D01*
X395350Y580161D01*
X395273Y579696D01*
X396883D01*
G01X400330Y574325D02*
Y576825D01*
X400970D01*
X401183Y576700D01*
X401343Y576408D01*
X401396Y576075D01*
X401343Y575742D01*
X401210Y575492D01*
X400970Y575367D01*
X400330D01*
G01X402530Y574825D02*
X402663Y574575D01*
X402823Y574408D01*
X403010Y574325D01*
X403223Y574408D01*
X403383Y574575D01*
X403543Y574825D01*
X403596Y575158D01*
Y576825D01*
G01X405263Y574325D02*
Y576825D01*
X404943Y576325D01*
G01Y574325D02*
X405583D01*
G01X407410D02*
X407463Y574867D01*
X407543Y575325D01*
X407650Y575742D01*
X407783Y576200D01*
X407996Y576825D01*
X406930D01*
G01X386041Y583883D02*
Y586983D01*
X386961D01*
X387268Y586828D01*
X387498Y586466D01*
X387575Y586053D01*
X387498Y585640D01*
X387306Y585330D01*
X386961Y585175D01*
X386041D01*
G01X390751Y586725D02*
X390521Y586880D01*
X390253Y586983D01*
X389946D01*
X389601Y586828D01*
X389333Y586570D01*
X389141Y586260D01*
X388988Y585743D01*
X388950Y585278D01*
X389026Y584813D01*
X389141Y584503D01*
X389371Y584193D01*
X389640Y583986D01*
X389908Y583883D01*
X390176D01*
X390445Y583986D01*
X390675Y584141D01*
X390866Y584348D01*
G01X392165Y584503D02*
X392395Y584141D01*
X392701Y583935D01*
X393046Y583883D01*
X393353Y583935D01*
X393660Y584193D01*
X393851Y584503D01*
X393890Y584813D01*
X393813Y585175D01*
X393545Y585433D01*
X393276Y585536D01*
X392931D01*
G01X393276D02*
X393506Y585691D01*
X393698Y585950D01*
X393775Y586260D01*
X393698Y586570D01*
X393506Y586828D01*
X393161Y586983D01*
X392816Y586931D01*
X392471Y586725D01*
G01X395265Y584503D02*
X395495Y584141D01*
X395801Y583935D01*
X396146Y583883D01*
X396453Y583935D01*
X396760Y584193D01*
X396951Y584503D01*
X396990Y584813D01*
X396913Y585175D01*
X396645Y585433D01*
X396376Y585536D01*
X396031D01*
G01X396376D02*
X396606Y585691D01*
X396798Y585950D01*
X396875Y586260D01*
X396798Y586570D01*
X396606Y586828D01*
X396261Y586983D01*
X395916Y586931D01*
X395571Y586725D01*
G01X395868Y596442D02*
Y599442D01*
G01X392768Y596342D02*
Y599542D01*
G01X398968Y596342D02*
X392768D01*
G01X398968Y599542D02*
Y596342D01*
G01X393457Y595543D02*
Y588143D01*
G01X384757D02*
Y595543D01*
G01X402157Y588143D02*
X384757D01*
G01Y595543D02*
X402157D01*
G01X389057Y624534D02*
Y598156D01*
G01X393285Y600798D02*
Y603298D01*
X392965Y602798D01*
G01Y600798D02*
X393605D01*
G01X394978Y602881D02*
X395138Y603131D01*
X395325Y603256D01*
X395538Y603298D01*
X395805Y603215D01*
X395992Y603006D01*
X396045Y602756D01*
X396018Y602506D01*
X395912Y602298D01*
X395378Y601881D01*
X395138Y601590D01*
X394978Y601173D01*
X394925Y600798D01*
X396045D01*
G01X396719Y603149D02*
X398820D01*
G01X396719Y605150D02*
Y603149D01*
G01X394827Y610335D02*
X392827D01*
G01X392958Y611731D02*
X389858D01*
Y612651D01*
X390013Y612958D01*
X390375Y613188D01*
X390788Y613265D01*
X391201Y613188D01*
X391511Y612996D01*
X391666Y612651D01*
Y611731D01*
G01X390116Y616441D02*
X389961Y616211D01*
X389858Y615943D01*
Y615636D01*
X390013Y615291D01*
X390271Y615023D01*
X390581Y614831D01*
X391098Y614678D01*
X391563Y614640D01*
X392028Y614716D01*
X392338Y614831D01*
X392648Y615061D01*
X392855Y615330D01*
X392958Y615598D01*
Y615866D01*
X392855Y616135D01*
X392700Y616365D01*
X392493Y616556D01*
G01X392338Y617855D02*
X392700Y618085D01*
X392906Y618391D01*
X392958Y618736D01*
X392906Y619043D01*
X392648Y619350D01*
X392338Y619541D01*
X392028Y619580D01*
X391666Y619503D01*
X391408Y619235D01*
X391305Y618966D01*
Y618621D01*
G01Y618966D02*
X391150Y619196D01*
X390891Y619388D01*
X390581Y619465D01*
X390271Y619388D01*
X390013Y619196D01*
X389858Y618851D01*
X389910Y618506D01*
X390116Y618161D01*
G01X391666Y621070D02*
X391305Y621338D01*
X391098Y621568D01*
X390995Y621875D01*
X391098Y622143D01*
X391305Y622335D01*
X391615Y622488D01*
X391976Y622526D01*
X392286Y622488D01*
X392596Y622335D01*
X392855Y622105D01*
X392958Y621836D01*
X392855Y621530D01*
X392545Y621261D01*
X392080Y621108D01*
X391563Y621070D01*
X390891Y621146D01*
X390530Y621261D01*
X390168Y621453D01*
X389910Y621721D01*
X389858Y621990D01*
X389961Y622258D01*
X390220Y622450D01*
G01X389959Y610650D02*
X393159D01*
G01X389959Y604450D02*
Y610650D01*
G01X393159Y604450D02*
X389959D01*
G01X393159Y610650D02*
Y604450D01*
G01X390059Y607550D02*
X393059D01*
G01X392768Y599542D02*
X398968D01*
G01X390930Y624500D02*
Y625960D01*
G01X391790Y624500D02*
X390930D01*
G01X399900Y621770D02*
X394090D01*
G01X399900Y627490D02*
Y621770D01*
G01X421950Y627490D02*
X399900D01*
G01X394826Y613767D02*
X395012Y613558D01*
X395226Y613475D01*
X395439Y613558D01*
X395626Y613808D01*
X395759Y614183D01*
X395812Y614558D01*
Y615017D01*
X395759Y615392D01*
X395626Y615725D01*
X395466Y615892D01*
X395279Y615975D01*
X395066Y615892D01*
X394906Y615725D01*
X394799Y615475D01*
X394746Y615142D01*
X394799Y614850D01*
X394932Y614558D01*
X395092Y614392D01*
X395279Y614350D01*
X395492Y614433D01*
X395652Y614642D01*
X395812Y615017D01*
G01X396719Y615551D02*
Y613850D01*
G01X398820Y615551D02*
X396719D01*
G01X396174Y622609D02*
Y625609D01*
G01X393074Y622509D02*
Y625709D01*
G01X399274Y622509D02*
X393074D01*
G01X399274Y625709D02*
Y622509D01*
G01X393074Y625709D02*
X399274D01*
G01X399268Y629833D02*
Y626633D01*
G01X393068D02*
Y629833D01*
G01X399268Y626633D02*
X393068D01*
G01X388064Y641792D02*
Y635592D01*
G01D02*
X384864D01*
G01D02*
Y641792D01*
G01D02*
X388064D01*
G01X392082Y635592D02*
X388882D01*
G01D02*
Y641792D01*
G01D02*
X392082D01*
G01D02*
Y635592D01*
G01X393068Y629833D02*
X399268D01*
G01X392618Y641021D02*
Y643521D01*
X392298Y643021D01*
G01Y641021D02*
X392938D01*
G01X391449Y633548D02*
X391609Y633798D01*
X391796Y633923D01*
X392009Y633965D01*
X392276Y633882D01*
X392463Y633673D01*
X392516Y633423D01*
X392489Y633173D01*
X392383Y632965D01*
X391849Y632548D01*
X391609Y632257D01*
X391449Y631840D01*
X391396Y631465D01*
X392516D01*
G01X393305Y642781D02*
X405023D01*
G01X393305Y630969D02*
Y642781D01*
G01X405023Y630969D02*
X393305D01*
G01X389558Y644189D02*
Y663789D01*
G01X401558Y644189D02*
X389558D01*
G01X392558Y661489D02*
G02I-1000J0D01*
G01X397758Y663789D02*
X401558D01*
G01X395558Y661589D02*
X397758Y663789D01*
G01X393358D02*
X395558Y661589D01*
G01X389558Y663789D02*
X393358D01*
G01X389558Y666892D02*
Y686492D01*
G01X401558Y666892D02*
X389558D01*
G01X392558Y684192D02*
G02I-1000J0D01*
G01X397758Y686492D02*
X401558D01*
G01X395558Y684292D02*
X397758Y686492D01*
G01X393358D02*
X395558Y684292D01*
G01X389558Y686492D02*
X393358D01*
G01X389918Y688756D02*
Y708556D01*
G01X401118Y688756D02*
X389918D01*
G01X393018Y706156D02*
G02I-1000J0D01*
G01X395518Y706756D02*
X397318Y708556D01*
G01X393718D02*
X395518Y706756D01*
G01X390297Y718170D02*
X400897D01*
G01X390297Y709508D02*
Y718170D01*
G01X400897Y709508D02*
X390297D01*
G01X397318Y708556D02*
X401118D01*
G01X389918D02*
X393718D01*
G01X389175Y717042D02*
Y713842D01*
G01X415397Y11152D02*
Y51314D01*
X423084D01*
Y10290D01*
X415397D01*
Y11152D01*
G01X400684Y24066D02*
X400844Y24316D01*
X401031Y24441D01*
X401244Y24483D01*
X401511Y24400D01*
X401698Y24191D01*
X401751Y23941D01*
X401724Y23691D01*
X401618Y23483D01*
X401084Y23066D01*
X400844Y22775D01*
X400684Y22358D01*
X400631Y21983D01*
X401751D01*
G01X406809Y50956D02*
Y26152D01*
G01X414995Y35386D02*
X408312D01*
Y35407D01*
X410505Y37600D01*
X410526Y37579D01*
Y32751D01*
X408291Y34986D01*
Y35323D01*
G01X412937Y54763D02*
Y59763D01*
X414203D01*
X414710Y59513D01*
X415090Y59180D01*
X415407Y58680D01*
X415660Y58096D01*
X415723Y57263D01*
X415660Y56430D01*
X415407Y55846D01*
X415090Y55346D01*
X414710Y55013D01*
X414203Y54763D01*
X412937D01*
G01X418670Y59763D02*
X420190D01*
G01X419430D02*
Y54763D01*
G01X418670D02*
X420190D01*
G01X422883D02*
Y59763D01*
X424530Y55596D01*
X426177Y59763D01*
Y54763D01*
G01X427983D02*
Y59763D01*
X429630Y55596D01*
X431277Y59763D01*
Y54763D01*
G01X438500Y55430D02*
X439007Y55013D01*
X439577Y54763D01*
X440083D01*
X440590Y55013D01*
X440970Y55430D01*
X441160Y56013D01*
X441033Y56596D01*
X440717Y57096D01*
X440147Y57430D01*
X439387Y57596D01*
X438943Y57930D01*
X438753Y58513D01*
X438880Y59096D01*
X439197Y59513D01*
X439640Y59763D01*
X440083D01*
X440527Y59596D01*
X440907Y59180D01*
G01X443663Y59763D02*
Y54763D01*
X446197D01*
G01X450030D02*
X449523Y54846D01*
X449080Y55180D01*
X448700Y55680D01*
X448447Y56263D01*
X448320Y56930D01*
Y57596D01*
X448447Y58263D01*
X448700Y58846D01*
X449080Y59346D01*
X449523Y59680D01*
X450030Y59763D01*
X450537Y59680D01*
X450980Y59346D01*
X451360Y58846D01*
X451613Y58263D01*
X451740Y57596D01*
Y56930D01*
X451613Y56263D01*
X451360Y55680D01*
X450980Y55180D01*
X450537Y54846D01*
X450030Y54763D01*
G01X455130Y59763D02*
Y54763D01*
G01X453673Y59763D02*
X456587D01*
G01X412548Y60843D02*
X457880D01*
Y53384D01*
X412306D01*
Y60843D01*
X412548D01*
G01X406572Y58604D02*
X406417Y58374D01*
X406314Y58106D01*
Y57799D01*
X406469Y57454D01*
X406727Y57186D01*
X407037Y56994D01*
X407554Y56841D01*
X408019Y56803D01*
X408484Y56879D01*
X408794Y56994D01*
X409104Y57224D01*
X409311Y57493D01*
X409414Y57761D01*
Y58029D01*
X409311Y58298D01*
X409156Y58528D01*
X408949Y58719D01*
G01X409414Y60861D02*
X406314D01*
X406934Y60401D01*
G01X409414D02*
Y61321D01*
G01Y64421D02*
X406314D01*
X408536Y63003D01*
Y64919D01*
G01X406314Y67061D02*
X406417Y66754D01*
X406676Y66524D01*
X406986Y66371D01*
X407399Y66256D01*
X407864Y66218D01*
X408329Y66256D01*
X408742Y66371D01*
X409052Y66524D01*
X409311Y66754D01*
X409414Y67061D01*
X409311Y67368D01*
X409052Y67598D01*
X408742Y67751D01*
X408329Y67866D01*
X407864Y67904D01*
X407399Y67866D01*
X406986Y67751D01*
X406676Y67598D01*
X406417Y67368D01*
X406314Y67061D01*
G01X403043Y52472D02*
Y54972D01*
X402723Y54472D01*
G01Y52472D02*
X403363D01*
G01X405264Y71210D02*
Y68010D01*
G01X402164Y71110D02*
Y68110D01*
G01X413458Y68554D02*
X413228Y68709D01*
X412960Y68812D01*
X412653D01*
X412308Y68657D01*
X412040Y68399D01*
X411848Y68089D01*
X411695Y67572D01*
X411657Y67107D01*
X411733Y66642D01*
X411848Y66332D01*
X412078Y66022D01*
X412347Y65815D01*
X412615Y65712D01*
X412883D01*
X413152Y65815D01*
X413382Y65970D01*
X413573Y66177D01*
G01X415715Y65712D02*
Y68812D01*
X415255Y68192D01*
G01Y65712D02*
X416175D01*
G01X419275D02*
Y68812D01*
X417857Y66590D01*
X419773D01*
G01X421915Y65712D02*
Y68812D01*
X421455Y68192D01*
G01Y65712D02*
X422375D01*
G01X412049Y69606D02*
Y74206D01*
G01X417149Y69606D02*
X406949D01*
G01D02*
Y74206D01*
G01D02*
X417149D01*
G01X408265Y79527D02*
X429135D01*
G01X409646Y181496D02*
Y112204D01*
G01D02*
X409365D01*
G01X406580Y180840D02*
Y151230D01*
G01X405380Y152346D02*
X402280D01*
Y153305D01*
X402435Y153611D01*
X402642Y153803D01*
X403055Y153880D01*
X403468Y153803D01*
X403727Y153573D01*
X403882Y153305D01*
Y152346D01*
G01Y153305D02*
X405380Y153880D01*
G01Y156213D02*
X402280D01*
X402900Y155753D01*
G01X405380D02*
Y156673D01*
G01X404915Y158470D02*
X405173Y158700D01*
X405328Y158968D01*
X405380Y159313D01*
X405277Y159658D01*
X405070Y159926D01*
X404708Y160118D01*
X404295Y160156D01*
X403882Y160080D01*
X403623Y159888D01*
X403417Y159620D01*
X403365Y159351D01*
X403417Y159083D01*
X403623Y158738D01*
X402280Y158853D01*
Y159888D01*
G01X404088Y161685D02*
X403727Y161953D01*
X403520Y162183D01*
X403417Y162490D01*
X403520Y162758D01*
X403727Y162950D01*
X404037Y163103D01*
X404398Y163141D01*
X404708Y163103D01*
X405018Y162950D01*
X405277Y162720D01*
X405380Y162451D01*
X405277Y162145D01*
X404967Y161876D01*
X404502Y161723D01*
X403985Y161685D01*
X403313Y161761D01*
X402952Y161876D01*
X402590Y162068D01*
X402332Y162336D01*
X402280Y162605D01*
X402383Y162873D01*
X402642Y163065D01*
G01X405596Y164646D02*
X402496D01*
Y165605D01*
X402651Y165911D01*
X402858Y166103D01*
X403271Y166180D01*
X403684Y166103D01*
X403943Y165873D01*
X404098Y165605D01*
Y164646D01*
G01Y165605D02*
X405596Y166180D01*
G01Y168513D02*
X402496D01*
X403116Y168053D01*
G01X405596D02*
Y168973D01*
G01X402496Y171613D02*
X402599Y171306D01*
X402858Y171076D01*
X403168Y170923D01*
X403581Y170808D01*
X404046Y170770D01*
X404511Y170808D01*
X404924Y170923D01*
X405234Y171076D01*
X405493Y171306D01*
X405596Y171613D01*
X405493Y171920D01*
X405234Y172150D01*
X404924Y172303D01*
X404511Y172418D01*
X404046Y172456D01*
X403581Y172418D01*
X403168Y172303D01*
X402858Y172150D01*
X402599Y171920D01*
X402496Y171613D01*
G01X405131Y173870D02*
X405389Y174100D01*
X405544Y174368D01*
X405596Y174713D01*
X405493Y175058D01*
X405286Y175326D01*
X404924Y175518D01*
X404511Y175556D01*
X404098Y175480D01*
X403839Y175288D01*
X403633Y175020D01*
X403581Y174751D01*
X403633Y174483D01*
X403839Y174138D01*
X402496Y174253D01*
Y175288D01*
G01X431103Y181496D02*
X409646D01*
G01X402270Y208353D02*
X404930Y213353D01*
G01X402270D02*
X404930Y208353D01*
G01X407307D02*
Y213353D01*
X408573D01*
X409080Y213103D01*
X409460Y212770D01*
X409777Y212270D01*
X410030Y211686D01*
X410093Y210853D01*
X410030Y210020D01*
X409777Y209436D01*
X409460Y208936D01*
X409080Y208603D01*
X408573Y208353D01*
X407307D01*
G01X412533D02*
Y213353D01*
X414053D01*
X414560Y213103D01*
X414940Y212520D01*
X415067Y211853D01*
X414940Y211186D01*
X414623Y210686D01*
X414053Y210436D01*
X412533D01*
G01X425393Y212936D02*
X425013Y213186D01*
X424570Y213353D01*
X424063D01*
X423493Y213103D01*
X423050Y212686D01*
X422733Y212186D01*
X422480Y211353D01*
X422417Y210603D01*
X422543Y209853D01*
X422733Y209353D01*
X423113Y208853D01*
X423557Y208520D01*
X424000Y208353D01*
X424443D01*
X424887Y208520D01*
X425267Y208770D01*
X425583Y209103D01*
G01X429100Y208353D02*
X428593Y208436D01*
X428150Y208770D01*
X427770Y209270D01*
X427517Y209853D01*
X427390Y210520D01*
Y211186D01*
X427517Y211853D01*
X427770Y212436D01*
X428150Y212936D01*
X428593Y213270D01*
X429100Y213353D01*
X429607Y213270D01*
X430050Y212936D01*
X430430Y212436D01*
X430683Y211853D01*
X430810Y211186D01*
Y210520D01*
X430683Y209853D01*
X430430Y209270D01*
X430050Y208770D01*
X429607Y208436D01*
X429100Y208353D01*
G01X432743D02*
Y213353D01*
X435657Y208353D01*
Y213353D01*
G01X437843Y208353D02*
Y213353D01*
X440757Y208353D01*
Y213353D01*
G01X405089Y216590D02*
X444449D01*
Y206310D01*
X401123D01*
Y216590D01*
X405089D01*
G01X403349Y234360D02*
X403509Y234152D01*
X403696Y234027D01*
X403936Y233985D01*
X404176Y234068D01*
X404363Y234235D01*
X404496Y234527D01*
X404523Y234860D01*
X404469Y235193D01*
X404336Y235402D01*
X404149Y235568D01*
X403963Y235610D01*
X403776Y235568D01*
X403536Y235402D01*
X403616Y236485D01*
X404336D01*
G01X405683Y234277D02*
X405869Y234068D01*
X406083Y233985D01*
X406296Y234068D01*
X406483Y234318D01*
X406616Y234693D01*
X406669Y235068D01*
Y235527D01*
X406616Y235902D01*
X406483Y236235D01*
X406323Y236402D01*
X406136Y236485D01*
X405923Y236402D01*
X405763Y236235D01*
X405656Y235985D01*
X405603Y235652D01*
X405656Y235360D01*
X405789Y235068D01*
X405949Y234902D01*
X406136Y234860D01*
X406349Y234943D01*
X406509Y235152D01*
X406669Y235527D01*
G01X409356Y230385D02*
Y241875D01*
G01X431138Y230385D02*
X409356D01*
G01X407010Y302544D02*
Y305044D01*
X406690Y304544D01*
G01Y302544D02*
X407330D01*
G01X409356Y302662D02*
Y314243D01*
G01D02*
X431042D01*
G01X421641Y409430D02*
X406641D01*
G01Y416230D02*
X421641D01*
G01X406641Y409430D02*
Y416230D01*
G01X414141Y416130D02*
Y409530D01*
G01X406641Y417430D02*
Y424230D01*
G01X414141Y424130D02*
Y417530D01*
G01X421641Y417430D02*
X406641D01*
G01X421641Y433430D02*
X406641D01*
G01X414141Y440130D02*
Y433530D01*
G01X406641Y433430D02*
Y440230D01*
G01X421641Y425430D02*
X406641D01*
G01X414141Y432130D02*
Y425530D01*
G01X406641Y425430D02*
Y432230D01*
G01D02*
X421641D01*
G01X406641Y424230D02*
X421641D01*
G01X421447Y452246D02*
X415519D01*
G01D02*
Y480750D01*
G01X406641Y440230D02*
X421641D01*
G01Y441430D02*
X406641D01*
G01X414141Y448130D02*
Y441530D01*
G01X406641Y441430D02*
Y448230D01*
G01D02*
X421641D01*
G01X406811Y456130D02*
Y449530D01*
G01X414311Y456230D02*
Y449430D01*
G01X406811Y463874D02*
Y457274D01*
G01X414311Y463974D02*
Y457174D01*
G01X414334Y465133D02*
X406634D01*
Y468733D01*
X414434D01*
Y465133D01*
X414334D01*
G01X410648Y470261D02*
Y477961D01*
X414248D01*
Y470161D01*
X410648D01*
Y470261D01*
G01X415519Y480750D02*
X421447D01*
G01X406000Y504170D02*
Y490630D01*
G01X433220Y504170D02*
X406000D01*
G01X403770Y516870D02*
X425760D01*
G01X403770Y503520D02*
Y516870D01*
G01X411903Y518307D02*
X412063Y518015D01*
X412277Y517849D01*
X412517Y517807D01*
X412730Y517849D01*
X412943Y518057D01*
X413077Y518307D01*
X413103Y518557D01*
X413050Y518849D01*
X412863Y519057D01*
X412677Y519140D01*
X412437D01*
G01X412677D02*
X412837Y519265D01*
X412970Y519474D01*
X413023Y519724D01*
X412970Y519974D01*
X412837Y520182D01*
X412597Y520307D01*
X412357Y520265D01*
X412117Y520099D01*
G01X414690Y517807D02*
Y520307D01*
X414370Y519807D01*
G01Y517807D02*
X415010D01*
G01X401437Y520972D02*
Y514772D01*
G01X410008Y509345D02*
Y515545D01*
G01X413208Y509345D02*
X410008D01*
G01X413208Y515545D02*
Y509345D01*
G01X410008Y515545D02*
X413208D01*
G01X418588Y504677D02*
X413988D01*
G01Y514877D02*
X418588D01*
G01X413988Y504677D02*
Y514877D01*
G01X405670Y521650D02*
Y542980D01*
G01X406590Y525128D02*
X406750Y524836D01*
X406964Y524670D01*
X407204Y524628D01*
X407417Y524670D01*
X407630Y524878D01*
X407764Y525128D01*
X407790Y525378D01*
X407737Y525670D01*
X407550Y525878D01*
X407364Y525961D01*
X407124D01*
G01X407364D02*
X407524Y526086D01*
X407657Y526295D01*
X407710Y526545D01*
X407657Y526795D01*
X407524Y527003D01*
X407284Y527128D01*
X407044Y527086D01*
X406804Y526920D01*
G01X409377Y527128D02*
X409164Y527045D01*
X409004Y526836D01*
X408897Y526586D01*
X408817Y526253D01*
X408790Y525878D01*
X408817Y525503D01*
X408897Y525170D01*
X409004Y524920D01*
X409164Y524711D01*
X409377Y524628D01*
X409590Y524711D01*
X409750Y524920D01*
X409857Y525170D01*
X409937Y525503D01*
X409964Y525878D01*
X409937Y526253D01*
X409857Y526586D01*
X409750Y526836D01*
X409590Y527045D01*
X409377Y527128D01*
G01X406730Y524007D02*
X410730D01*
G01X413175Y521153D02*
Y523107D01*
G01X415157Y521153D02*
X413175D01*
G01X408718Y531881D02*
X410718D01*
G01X404829Y533616D02*
Y530416D01*
G01X404739Y529615D02*
Y526415D01*
G01X404701Y525691D02*
Y522491D01*
G01X409049Y542333D02*
X409209Y542583D01*
X409396Y542708D01*
X409609Y542750D01*
X409876Y542667D01*
X410063Y542458D01*
X410116Y542208D01*
X410089Y541958D01*
X409983Y541750D01*
X409449Y541333D01*
X409209Y541042D01*
X409049Y540625D01*
X408996Y540250D01*
X410116D01*
G01X411756Y542750D02*
X411543Y542667D01*
X411383Y542458D01*
X411276Y542208D01*
X411196Y541875D01*
X411169Y541500D01*
X411196Y541125D01*
X411276Y540792D01*
X411383Y540542D01*
X411543Y540333D01*
X411756Y540250D01*
X411969Y540333D01*
X412129Y540542D01*
X412236Y540792D01*
X412316Y541125D01*
X412343Y541500D01*
X412316Y541875D01*
X412236Y542208D01*
X412129Y542458D01*
X411969Y542667D01*
X411756Y542750D01*
G01X407743Y538452D02*
X407903Y538702D01*
X408090Y538827D01*
X408303Y538869D01*
X408570Y538786D01*
X408757Y538577D01*
X408810Y538327D01*
X408783Y538077D01*
X408677Y537869D01*
X408143Y537452D01*
X407903Y537161D01*
X407743Y536744D01*
X407690Y536369D01*
X408810D01*
G01X410450D02*
Y538869D01*
X410130Y538369D01*
G01Y536369D02*
X410770D01*
G01X413175Y541035D02*
X415157D01*
G01X413175Y539057D02*
Y541035D01*
G01X416029Y543494D02*
Y547494D01*
G01X410234Y543755D02*
Y549955D01*
G01X413434Y543755D02*
X410234D01*
G01X413434Y549955D02*
Y543755D01*
G01X410334Y546855D02*
X413334D01*
G01X409434Y543755D02*
X406234D01*
G01X409434Y549955D02*
Y543755D01*
G01X406234D02*
Y549955D01*
G01X414486Y548742D02*
Y551942D01*
G01X420686Y548742D02*
X414486D01*
G01X404712Y537727D02*
Y534527D01*
G01X404912Y541727D02*
Y538527D01*
G01X410234Y549955D02*
X413434D01*
G01X404306Y552802D02*
Y556002D01*
G01X410506Y552802D02*
X404306D01*
G01X410506Y556002D02*
Y552802D01*
G01X404306Y556002D02*
X410506D01*
G01X407406Y552902D02*
Y555902D01*
G01X406234Y549955D02*
X409434D01*
G01X412767Y561627D02*
Y564127D01*
X413407D01*
X413620Y564002D01*
X413780Y563710D01*
X413833Y563377D01*
X413780Y563044D01*
X413647Y562794D01*
X413407Y562669D01*
X412767D01*
G01X414967Y561627D02*
Y564127D01*
X415633D01*
X415847Y564002D01*
X415980Y563835D01*
X416033Y563502D01*
X415980Y563169D01*
X415820Y562960D01*
X415633Y562835D01*
X414967D01*
G01X415633D02*
X416033Y561627D01*
G01X417647D02*
X417700Y562169D01*
X417780Y562627D01*
X417887Y563044D01*
X418020Y563502D01*
X418233Y564127D01*
X417167D01*
G01X419393Y562669D02*
X419580Y562960D01*
X419740Y563127D01*
X419953Y563210D01*
X420140Y563127D01*
X420273Y562960D01*
X420380Y562710D01*
X420407Y562419D01*
X420380Y562169D01*
X420273Y561919D01*
X420113Y561710D01*
X419927Y561627D01*
X419713Y561710D01*
X419527Y561960D01*
X419420Y562335D01*
X419393Y562752D01*
X419447Y563294D01*
X419527Y563585D01*
X419660Y563877D01*
X419847Y564085D01*
X420033Y564127D01*
X420220Y564044D01*
X420353Y563835D01*
G01X414486Y551942D02*
X420686D01*
G01X414515Y557417D02*
Y560617D01*
G01X420715Y557417D02*
X414515D01*
G01Y560617D02*
X420715D01*
G01X412565Y566103D02*
Y568603D01*
X413205D01*
X413418Y568478D01*
X413578Y568186D01*
X413631Y567853D01*
X413578Y567520D01*
X413445Y567270D01*
X413205Y567145D01*
X412565D01*
G01X414765Y566103D02*
Y568603D01*
X415431D01*
X415645Y568478D01*
X415778Y568311D01*
X415831Y567978D01*
X415778Y567645D01*
X415618Y567436D01*
X415431Y567311D01*
X414765D01*
G01X415431D02*
X415831Y566103D01*
G01X417445D02*
X417498Y566645D01*
X417578Y567103D01*
X417685Y567520D01*
X417818Y567978D01*
X418031Y568603D01*
X416965D01*
G01X419645Y566103D02*
X419698Y566645D01*
X419778Y567103D01*
X419885Y567520D01*
X420018Y567978D01*
X420231Y568603D01*
X419165D01*
G01X414497Y555993D02*
X420697D01*
G01X414497Y552793D02*
Y555993D01*
G01X420697Y552793D02*
X414497D01*
G01X409294Y581828D02*
Y584328D01*
X409934D01*
X410147Y584203D01*
X410307Y583911D01*
X410360Y583578D01*
X410307Y583245D01*
X410174Y582995D01*
X409934Y582870D01*
X409294D01*
G01X412614Y584120D02*
X412454Y584245D01*
X412267Y584328D01*
X412054D01*
X411814Y584203D01*
X411627Y583995D01*
X411494Y583745D01*
X411387Y583328D01*
X411360Y582953D01*
X411414Y582578D01*
X411494Y582328D01*
X411654Y582078D01*
X411840Y581911D01*
X412027Y581828D01*
X412214D01*
X412400Y581911D01*
X412560Y582036D01*
X412694Y582203D01*
G01X414547Y581828D02*
Y584328D01*
X413560Y582536D01*
X414894D01*
G01X415920Y583911D02*
X416080Y584161D01*
X416267Y584286D01*
X416480Y584328D01*
X416747Y584245D01*
X416934Y584036D01*
X416987Y583786D01*
X416960Y583536D01*
X416854Y583328D01*
X416320Y582911D01*
X416080Y582620D01*
X415920Y582203D01*
X415867Y581828D01*
X416987D01*
G01X412565Y570103D02*
Y572603D01*
X413205D01*
X413418Y572478D01*
X413578Y572186D01*
X413631Y571853D01*
X413578Y571520D01*
X413445Y571270D01*
X413205Y571145D01*
X412565D01*
G01X414765Y570103D02*
Y572603D01*
X415431D01*
X415645Y572478D01*
X415778Y572311D01*
X415831Y571978D01*
X415778Y571645D01*
X415618Y571436D01*
X415431Y571311D01*
X414765D01*
G01X415431D02*
X415831Y570103D01*
G01X417445D02*
X417498Y570645D01*
X417578Y571103D01*
X417685Y571520D01*
X417818Y571978D01*
X418031Y572603D01*
X416965D01*
G01X420018Y570103D02*
Y572603D01*
X419031Y570811D01*
X420365D01*
G01X409294Y578092D02*
Y580592D01*
X409934D01*
X410147Y580467D01*
X410307Y580175D01*
X410360Y579842D01*
X410307Y579509D01*
X410174Y579259D01*
X409934Y579134D01*
X409294D01*
G01X411494Y578092D02*
Y580592D01*
X412160D01*
X412374Y580467D01*
X412507Y580300D01*
X412560Y579967D01*
X412507Y579634D01*
X412347Y579425D01*
X412160Y579300D01*
X411494D01*
G01X412160D02*
X412560Y578092D01*
G01X414227D02*
Y580592D01*
X413907Y580092D01*
G01Y578092D02*
X414547D01*
G01X415840Y578467D02*
X416000Y578259D01*
X416187Y578134D01*
X416427Y578092D01*
X416667Y578175D01*
X416854Y578342D01*
X416987Y578634D01*
X417014Y578967D01*
X416960Y579300D01*
X416827Y579509D01*
X416640Y579675D01*
X416454Y579717D01*
X416267Y579675D01*
X416027Y579509D01*
X416107Y580592D01*
X416827D01*
G01X406024Y584247D02*
X402924D01*
Y585167D01*
X403079Y585474D01*
X403441Y585704D01*
X403854Y585781D01*
X404267Y585704D01*
X404577Y585512D01*
X404732Y585167D01*
Y584247D01*
G01X403182Y588957D02*
X403027Y588727D01*
X402924Y588459D01*
Y588152D01*
X403079Y587807D01*
X403337Y587539D01*
X403647Y587347D01*
X404164Y587194D01*
X404629Y587156D01*
X405094Y587232D01*
X405404Y587347D01*
X405714Y587577D01*
X405921Y587846D01*
X406024Y588114D01*
Y588382D01*
X405921Y588651D01*
X405766Y588881D01*
X405559Y589072D01*
G01X405404Y590371D02*
X405766Y590601D01*
X405972Y590907D01*
X406024Y591252D01*
X405972Y591559D01*
X405714Y591866D01*
X405404Y592057D01*
X405094Y592096D01*
X404732Y592019D01*
X404474Y591751D01*
X404371Y591482D01*
Y591137D01*
G01Y591482D02*
X404216Y591712D01*
X403957Y591904D01*
X403647Y591981D01*
X403337Y591904D01*
X403079Y591712D01*
X402924Y591367D01*
X402976Y591022D01*
X403182Y590677D01*
G01X405559Y593471D02*
X405817Y593701D01*
X405972Y593969D01*
X406024Y594314D01*
X405921Y594659D01*
X405714Y594927D01*
X405352Y595119D01*
X404939Y595157D01*
X404526Y595081D01*
X404267Y594889D01*
X404061Y594621D01*
X404009Y594352D01*
X404061Y594084D01*
X404267Y593739D01*
X402924Y593854D01*
Y594889D01*
G01X408773Y598788D02*
Y595788D01*
G01X411873Y598888D02*
Y595688D01*
G01X405673D02*
Y598888D01*
G01X411873Y595688D02*
X405673D01*
G01X409294Y589720D02*
Y592220D01*
X409934D01*
X410147Y592095D01*
X410307Y591803D01*
X410360Y591470D01*
X410307Y591137D01*
X410174Y590887D01*
X409934Y590762D01*
X409294D01*
G01X412614Y592012D02*
X412454Y592137D01*
X412267Y592220D01*
X412054D01*
X411814Y592095D01*
X411627Y591887D01*
X411494Y591637D01*
X411387Y591220D01*
X411360Y590845D01*
X411414Y590470D01*
X411494Y590220D01*
X411654Y589970D01*
X411840Y589803D01*
X412027Y589720D01*
X412214D01*
X412400Y589803D01*
X412560Y589928D01*
X412694Y590095D01*
G01X414547Y589720D02*
Y592220D01*
X413560Y590428D01*
X414894D01*
G01X416427Y592220D02*
X416214Y592137D01*
X416054Y591928D01*
X415947Y591678D01*
X415867Y591345D01*
X415840Y590970D01*
X415867Y590595D01*
X415947Y590262D01*
X416054Y590012D01*
X416214Y589803D01*
X416427Y589720D01*
X416640Y589803D01*
X416800Y590012D01*
X416907Y590262D01*
X416987Y590595D01*
X417014Y590970D01*
X416987Y591345D01*
X416907Y591678D01*
X416800Y591928D01*
X416640Y592137D01*
X416427Y592220D01*
G01X402157Y595543D02*
Y588143D01*
G01X409294Y585938D02*
Y588438D01*
X409934D01*
X410147Y588313D01*
X410307Y588021D01*
X410360Y587688D01*
X410307Y587355D01*
X410174Y587105D01*
X409934Y586980D01*
X409294D01*
G01X411494Y585938D02*
Y588438D01*
X412160D01*
X412374Y588313D01*
X412507Y588146D01*
X412560Y587813D01*
X412507Y587480D01*
X412347Y587271D01*
X412160Y587146D01*
X411494D01*
G01X412160D02*
X412560Y585938D01*
G01X414227D02*
Y588438D01*
X413907Y587938D01*
G01Y585938D02*
X414547D01*
G01X415920Y586980D02*
X416107Y587271D01*
X416267Y587438D01*
X416480Y587521D01*
X416667Y587438D01*
X416800Y587271D01*
X416907Y587021D01*
X416934Y586730D01*
X416907Y586480D01*
X416800Y586230D01*
X416640Y586021D01*
X416454Y585938D01*
X416240Y586021D01*
X416054Y586271D01*
X415947Y586646D01*
X415920Y587063D01*
X415974Y587605D01*
X416054Y587896D01*
X416187Y588188D01*
X416374Y588396D01*
X416560Y588438D01*
X416747Y588355D01*
X416880Y588146D01*
G01X414017Y595700D02*
Y598900D01*
G01X420217Y595700D02*
X414017D01*
G01X413936Y606905D02*
X411436D01*
Y607545D01*
X411561Y607758D01*
X411853Y607918D01*
X412186Y607971D01*
X412519Y607918D01*
X412769Y607785D01*
X412894Y607545D01*
Y606905D01*
G01X411436Y609051D02*
X413228D01*
X413603Y609158D01*
X413853Y609371D01*
X413936Y609638D01*
X413853Y609905D01*
X413603Y610118D01*
X413228Y610225D01*
X411436D01*
G01X413936Y612158D02*
X411436D01*
X413228Y611171D01*
Y612505D01*
G01X407123Y600236D02*
Y602736D01*
X406803Y602236D01*
G01Y600236D02*
X407443D01*
G01X408816Y601278D02*
X409003Y601569D01*
X409163Y601736D01*
X409376Y601819D01*
X409563Y601736D01*
X409696Y601569D01*
X409803Y601319D01*
X409830Y601028D01*
X409803Y600778D01*
X409696Y600528D01*
X409536Y600319D01*
X409350Y600236D01*
X409136Y600319D01*
X408950Y600569D01*
X408843Y600944D01*
X408816Y601361D01*
X408870Y601903D01*
X408950Y602194D01*
X409083Y602486D01*
X409270Y602694D01*
X409456Y602736D01*
X409643Y602653D01*
X409776Y602444D01*
G01X409121Y603149D02*
Y605250D01*
G01X407120Y603149D02*
X409121D01*
G01X403927Y600097D02*
Y601297D01*
G01X405673Y598888D02*
X411873D01*
G01X414546Y611142D02*
X420746D01*
G01X414546Y607942D02*
Y611142D01*
G01X420746Y607942D02*
X414546D01*
G01X414017Y599657D02*
Y602857D01*
G01X420217Y599657D02*
X414017D01*
G01Y602857D02*
X420217D01*
G01X414546Y607100D02*
X420746D01*
G01X414546Y603900D02*
Y607100D01*
G01X420746Y603900D02*
X414546D01*
G01X414017Y598900D02*
X420217D01*
G01X406989Y616807D02*
X407149Y616599D01*
X407336Y616474D01*
X407576Y616432D01*
X407816Y616515D01*
X408003Y616682D01*
X408136Y616974D01*
X408163Y617307D01*
X408109Y617640D01*
X407976Y617849D01*
X407789Y618015D01*
X407603Y618057D01*
X407416Y618015D01*
X407176Y617849D01*
X407256Y618932D01*
X407976D01*
G01X409121Y615551D02*
X407220D01*
G01X409121Y613650D02*
Y615551D01*
G01X405873Y617397D02*
Y618597D01*
G01X417205Y613513D02*
X414005D01*
G01Y619713D02*
X417205D01*
G01X414005Y613513D02*
Y619713D01*
G01X417105Y616613D02*
X414105D01*
G01X413073Y620038D02*
X409873D01*
G01X413073Y626238D02*
Y620038D01*
G01X409873Y626238D02*
X413073D01*
G01X409873Y620038D02*
Y626238D01*
G01X405873D02*
X409073D01*
G01X405873Y620038D02*
Y626238D01*
G01X409073Y620038D02*
X405873D01*
G01X409073Y626238D02*
Y620038D01*
G01X416184Y620397D02*
X413684D01*
Y621037D01*
X413809Y621250D01*
X414101Y621410D01*
X414434Y621463D01*
X414767Y621410D01*
X415017Y621277D01*
X415142Y621037D01*
Y620397D01*
G01X415684Y622597D02*
X415934Y622730D01*
X416101Y622890D01*
X416184Y623077D01*
X416101Y623290D01*
X415934Y623450D01*
X415684Y623610D01*
X415351Y623663D01*
X413684D01*
G01X416184Y625650D02*
X413684D01*
X415476Y624663D01*
Y625997D01*
G01X406638Y639272D02*
Y642472D01*
G01X412838Y639272D02*
X406638D01*
G01X412838Y642472D02*
Y639272D01*
G01X406638Y642472D02*
X412838D01*
G01X414979Y643154D02*
Y646354D01*
G01X421179Y643154D02*
X414979D01*
G01X406182Y635247D02*
X421182D01*
G01Y628447D02*
X406182D01*
G01D02*
Y635247D01*
G01X402250Y632313D02*
X402410Y632021D01*
X402624Y631855D01*
X402864Y631813D01*
X403077Y631855D01*
X403290Y632063D01*
X403424Y632313D01*
X403450Y632563D01*
X403397Y632855D01*
X403210Y633063D01*
X403024Y633146D01*
X402784D01*
G01X403024D02*
X403184Y633271D01*
X403317Y633480D01*
X403370Y633730D01*
X403317Y633980D01*
X403184Y634188D01*
X402944Y634313D01*
X402704Y634271D01*
X402464Y634105D01*
G01X405023Y642781D02*
Y630969D01*
G01X401558Y663789D02*
Y644189D01*
G01X414979Y646354D02*
X421179D01*
G01X414894Y651132D02*
Y654332D01*
G01X421094Y651132D02*
X414894D01*
G01Y654332D02*
X421094D01*
G01X414894Y658483D02*
X421094D01*
G01X414894Y655283D02*
Y658483D01*
G01X421094Y655283D02*
X414894D01*
G01Y650299D02*
X421094D01*
G01X414894Y647099D02*
Y650299D01*
G01X421094Y647099D02*
X414894D01*
G01X410410Y665940D02*
X435790D01*
G01X401558Y686492D02*
Y666892D01*
G01X414894Y674694D02*
X421094D01*
G01X414894Y671494D02*
Y674694D01*
G01X421094Y671494D02*
X414894D01*
G01Y670627D02*
X421094D01*
G01X414894Y667427D02*
Y670627D01*
G01X421094Y667427D02*
X414894D01*
G01X414030Y690180D02*
Y694540D01*
G01X414540Y690180D02*
X414030D01*
G01X401118Y708556D02*
Y688756D01*
G01X414894Y675528D02*
Y678728D01*
G01X421094Y675528D02*
X414894D01*
G01Y678728D02*
X421094D01*
G01X414894Y682722D02*
X421094D01*
G01X414894Y679522D02*
Y682722D01*
G01X421094Y679522D02*
X414894D01*
G01X415902Y703064D02*
Y706264D01*
G01X422102Y703064D02*
X415902D01*
G01Y706264D02*
X422102D01*
G01X415902Y698313D02*
X422102D01*
G01X415902Y695113D02*
Y698313D01*
G01X422102Y695113D02*
X415902D01*
G01Y702269D02*
X422102D01*
G01X415902Y699069D02*
Y702269D01*
G01X422102Y699069D02*
X415902D01*
G01X414934Y696003D02*
X411834D01*
Y696962D01*
X411989Y697268D01*
X412196Y697460D01*
X412609Y697537D01*
X413022Y697460D01*
X413281Y697230D01*
X413436Y696962D01*
Y696003D01*
G01Y696962D02*
X414934Y697537D01*
G01Y699793D02*
X414262Y699870D01*
X413694Y699985D01*
X413177Y700138D01*
X412609Y700330D01*
X411834Y700637D01*
Y699103D01*
G01X413642Y702242D02*
X413281Y702510D01*
X413074Y702740D01*
X412971Y703047D01*
X413074Y703315D01*
X413281Y703507D01*
X413591Y703660D01*
X413952Y703698D01*
X414262Y703660D01*
X414572Y703507D01*
X414831Y703277D01*
X414934Y703008D01*
X414831Y702702D01*
X414521Y702433D01*
X414056Y702280D01*
X413539Y702242D01*
X412867Y702318D01*
X412506Y702433D01*
X412144Y702625D01*
X411886Y702893D01*
X411834Y703162D01*
X411937Y703430D01*
X412196Y703622D01*
G01X414469Y705227D02*
X414727Y705457D01*
X414882Y705725D01*
X414934Y706070D01*
X414831Y706415D01*
X414624Y706683D01*
X414262Y706875D01*
X413849Y706913D01*
X413436Y706837D01*
X413177Y706645D01*
X412971Y706377D01*
X412919Y706108D01*
X412971Y705840D01*
X413177Y705495D01*
X411834Y705610D01*
Y706645D01*
G01X400897Y718170D02*
Y709508D01*
G01X405071Y715335D02*
Y712335D01*
G01X408171Y715435D02*
Y712235D01*
G01X401971Y715435D02*
X408171D01*
G01X401971Y712235D02*
Y715435D01*
G01X408171Y712235D02*
X401971D01*
G01X411313Y778094D02*
X411505Y777784D01*
X411735Y777577D01*
X412003Y777474D01*
X412310Y777577D01*
X412540Y777784D01*
X412770Y778094D01*
X412847Y778507D01*
Y780574D01*
G01X415180Y777474D02*
Y780574D01*
X414720Y779954D01*
G01Y777474D02*
X415640D01*
G01X418280D02*
X418548Y777526D01*
X418855Y777681D01*
X419047Y777939D01*
X419123Y778301D01*
X419047Y778662D01*
X418817Y778972D01*
X418472Y779127D01*
X418088D01*
X417858Y779231D01*
X417667Y779489D01*
X417590Y779851D01*
X417705Y780212D01*
X417973Y780471D01*
X418280Y780574D01*
X418587Y780471D01*
X418855Y780212D01*
X418970Y779851D01*
X418893Y779489D01*
X418702Y779231D01*
X418472Y779127D01*
X418088D01*
X417743Y778972D01*
X417513Y778662D01*
X417437Y778301D01*
X417513Y777939D01*
X417705Y777681D01*
X418012Y777526D01*
X418280Y777474D01*
G01X411283Y784823D02*
X411390Y784948D01*
X411470Y785157D01*
X411523Y785448D01*
X411470Y785698D01*
X411363Y785865D01*
X411177Y785990D01*
X410457D01*
Y783490D01*
X411337D01*
X411523Y783657D01*
X411630Y783907D01*
X411683Y784198D01*
X411630Y784490D01*
X411470Y784740D01*
X411283Y784823D01*
X410457D01*
G01X413270Y783490D02*
X413457Y783532D01*
X413670Y783657D01*
X413803Y783865D01*
X413857Y784157D01*
X413803Y784448D01*
X413643Y784698D01*
X413403Y784823D01*
X413137D01*
X412977Y784907D01*
X412843Y785115D01*
X412790Y785407D01*
X412870Y785698D01*
X413057Y785907D01*
X413270Y785990D01*
X413483Y785907D01*
X413670Y785698D01*
X413750Y785407D01*
X413697Y785115D01*
X413563Y784907D01*
X413403Y784823D01*
X413137D01*
X412897Y784698D01*
X412737Y784448D01*
X412683Y784157D01*
X412737Y783865D01*
X412870Y783657D01*
X413083Y783532D01*
X413270Y783490D01*
G01X414963Y785573D02*
X415123Y785823D01*
X415310Y785948D01*
X415523Y785990D01*
X415790Y785907D01*
X415977Y785698D01*
X416030Y785448D01*
X416003Y785198D01*
X415897Y784990D01*
X415363Y784573D01*
X415123Y784282D01*
X414963Y783865D01*
X414910Y783490D01*
X416030D01*
G01X738841Y782281D02*
X406951D01*
G01Y819152D02*
Y788581D01*
G01X409451Y821652D02*
X406951Y819152D01*
G01X684648Y821652D02*
X409451D01*
G01X416293Y12423D02*
X421293D01*
G01X416293Y10966D02*
Y13880D01*
G01X421293Y16256D02*
X416293D01*
Y17776D01*
X416543Y18283D01*
X417126Y18663D01*
X417793Y18790D01*
X418460Y18663D01*
X418960Y18346D01*
X419210Y17776D01*
Y16256D01*
G01X421293Y20976D02*
X416293D01*
X420460Y22623D01*
X416293Y24270D01*
X421293D01*
G01X416710Y34216D02*
X416460Y33836D01*
X416293Y33393D01*
Y32886D01*
X416543Y32316D01*
X416960Y31873D01*
X417460Y31556D01*
X418293Y31303D01*
X419043Y31240D01*
X419793Y31366D01*
X420293Y31556D01*
X420793Y31936D01*
X421126Y32380D01*
X421293Y32823D01*
Y33266D01*
X421126Y33710D01*
X420876Y34090D01*
X420543Y34406D01*
G01X421293Y37923D02*
X421210Y37416D01*
X420876Y36973D01*
X420376Y36593D01*
X419793Y36340D01*
X419126Y36213D01*
X418460D01*
X417793Y36340D01*
X417210Y36593D01*
X416710Y36973D01*
X416376Y37416D01*
X416293Y37923D01*
X416376Y38430D01*
X416710Y38873D01*
X417210Y39253D01*
X417793Y39506D01*
X418460Y39633D01*
X419126D01*
X419793Y39506D01*
X420376Y39253D01*
X420876Y38873D01*
X421210Y38430D01*
X421293Y37923D01*
G01Y41566D02*
X416293D01*
X421293Y44480D01*
X416293D01*
G01X421293Y46666D02*
X416293D01*
X421293Y49580D01*
X416293D01*
G01X428504Y61110D02*
X428347D01*
Y77779D01*
X431210Y74916D01*
Y74720D01*
X431131Y74641D01*
X425718D01*
X425601Y74524D01*
Y75190D01*
X428307Y77896D01*
G01X417149Y74206D02*
Y69606D01*
G01X419857Y77383D02*
X420017Y77633D01*
X420204Y77758D01*
X420417Y77800D01*
X420684Y77717D01*
X420871Y77508D01*
X420924Y77258D01*
X420897Y77008D01*
X420791Y76800D01*
X420257Y76383D01*
X420017Y76092D01*
X419857Y75675D01*
X419804Y75300D01*
X420924D01*
G01X422564Y77800D02*
X422351Y77717D01*
X422191Y77508D01*
X422084Y77258D01*
X422004Y76925D01*
X421977Y76550D01*
X422004Y76175D01*
X422084Y75842D01*
X422191Y75592D01*
X422351Y75383D01*
X422564Y75300D01*
X422777Y75383D01*
X422937Y75592D01*
X423044Y75842D01*
X423124Y76175D01*
X423151Y76550D01*
X423124Y76925D01*
X423044Y77258D01*
X422937Y77508D01*
X422777Y77717D01*
X422564Y77800D01*
G01X424177Y75800D02*
X424337Y75508D01*
X424551Y75342D01*
X424791Y75300D01*
X425004Y75342D01*
X425217Y75550D01*
X425351Y75800D01*
X425377Y76050D01*
X425324Y76342D01*
X425137Y76550D01*
X424951Y76633D01*
X424711D01*
G01X424951D02*
X425111Y76758D01*
X425244Y76967D01*
X425297Y77217D01*
X425244Y77467D01*
X425111Y77675D01*
X424871Y77800D01*
X424631Y77758D01*
X424391Y77592D01*
G01X429135Y79527D02*
X430208Y135123D01*
G01X430608Y155827D02*
X431103Y181496D01*
G01X432116Y182304D02*
Y185404D01*
X433075D01*
X433381Y185249D01*
X433573Y185042D01*
X433650Y184629D01*
X433573Y184216D01*
X433343Y183957D01*
X433075Y183802D01*
X432116D01*
G01X433075D02*
X433650Y182304D01*
G01X435255Y183596D02*
X435523Y183957D01*
X435753Y184164D01*
X436060Y184267D01*
X436328Y184164D01*
X436520Y183957D01*
X436673Y183647D01*
X436711Y183286D01*
X436673Y182976D01*
X436520Y182666D01*
X436290Y182407D01*
X436021Y182304D01*
X435715Y182407D01*
X435446Y182717D01*
X435293Y183182D01*
X435255Y183699D01*
X435331Y184371D01*
X435446Y184732D01*
X435638Y185094D01*
X435906Y185352D01*
X436175Y185404D01*
X436443Y185301D01*
X436635Y185042D01*
G01X439083Y182304D02*
Y185404D01*
X438623Y184784D01*
G01Y182304D02*
X439543D01*
G01X441531Y182666D02*
X441800Y182407D01*
X442106Y182304D01*
X442413Y182407D01*
X442681Y182717D01*
X442873Y183182D01*
X442950Y183647D01*
Y184216D01*
X442873Y184681D01*
X442681Y185094D01*
X442451Y185301D01*
X442183Y185404D01*
X441876Y185301D01*
X441646Y185094D01*
X441493Y184784D01*
X441416Y184371D01*
X441493Y184009D01*
X441685Y183647D01*
X441915Y183441D01*
X442183Y183389D01*
X442490Y183492D01*
X442720Y183751D01*
X442950Y184216D01*
G01X428496Y228745D02*
X428159D01*
X425924Y226510D01*
X430752D01*
X430773Y226531D01*
X428580Y228724D01*
X428559D01*
Y216600D01*
X428900D01*
G01X420267Y316003D02*
X420459Y315693D01*
X420689Y315486D01*
X420957Y315383D01*
X421264Y315486D01*
X421494Y315693D01*
X421724Y316003D01*
X421801Y316416D01*
Y318483D01*
G01X423291Y316003D02*
X423521Y315641D01*
X423827Y315435D01*
X424172Y315383D01*
X424479Y315435D01*
X424786Y315693D01*
X424977Y316003D01*
X425016Y316313D01*
X424939Y316675D01*
X424671Y316933D01*
X424402Y317036D01*
X424057D01*
G01X424402D02*
X424632Y317191D01*
X424824Y317450D01*
X424901Y317760D01*
X424824Y318070D01*
X424632Y318328D01*
X424287Y318483D01*
X423942Y318431D01*
X423597Y318225D01*
G01X421641Y416230D02*
Y409430D01*
G01Y424230D02*
Y417430D01*
G01X428462Y421090D02*
X426582D01*
G01X427600Y419725D02*
Y422455D01*
G01X421641Y440230D02*
Y433430D01*
G01Y432230D02*
Y425430D01*
G01X428652Y440620D02*
X426772D01*
G01X427790Y439255D02*
Y441985D01*
G01X421641Y448230D02*
Y441430D01*
G01X417304Y482440D02*
Y483373D01*
G01X441714Y482440D02*
X417304D01*
G01Y497373D02*
Y498373D01*
G01Y492373D02*
Y493373D01*
G01Y487373D02*
Y488373D01*
G01X425760Y514190D02*
X433220D01*
G01X425760Y516870D02*
Y514190D01*
G01X426902Y515996D02*
Y518496D01*
X425915Y516704D01*
X427249D01*
G01X428782Y518496D02*
X428569Y518413D01*
X428409Y518204D01*
X428302Y517954D01*
X428222Y517621D01*
X428195Y517246D01*
X428222Y516871D01*
X428302Y516538D01*
X428409Y516288D01*
X428569Y516079D01*
X428782Y515996D01*
X428995Y516079D01*
X429155Y516288D01*
X429262Y516538D01*
X429342Y516871D01*
X429369Y517246D01*
X429342Y517621D01*
X429262Y517954D01*
X429155Y518204D01*
X428995Y518413D01*
X428782Y518496D01*
G01X430203Y514710D02*
Y518710D01*
G01X417304Y503306D02*
X441714D01*
G01X417304Y502373D02*
Y503306D01*
G01X429779Y505819D02*
Y508819D01*
G01X426679Y505719D02*
Y508919D01*
G01X432879Y505719D02*
X426679D01*
G01Y508919D02*
X432879D01*
G01X419488Y509777D02*
X424088D01*
G01Y504677D02*
X419488D01*
G01X424088Y514877D02*
Y504677D01*
G01X419488Y514877D02*
X424088D01*
G01X419488Y504677D02*
Y514877D01*
G01X426331Y513181D02*
X432531D01*
G01X426331Y509981D02*
Y513181D01*
G01X432531Y509981D02*
X426331D01*
G01X418588Y514877D02*
Y504677D01*
G01X433057Y521153D02*
X431107D01*
G01X421430Y548380D02*
X435740D01*
G01X421430Y556240D02*
Y548380D01*
G01X431860Y541107D02*
Y543607D01*
X431540Y543107D01*
G01Y541107D02*
X432180D01*
G01X434060D02*
Y543607D01*
X433740Y543107D01*
G01Y541107D02*
X434380D01*
G01X427393Y544307D02*
Y547407D01*
X428313D01*
X428620Y547252D01*
X428850Y546890D01*
X428927Y546477D01*
X428850Y546064D01*
X428658Y545754D01*
X428313Y545599D01*
X427393D01*
G01X430417Y547407D02*
Y545185D01*
X430570Y544720D01*
X430877Y544410D01*
X431260Y544307D01*
X431643Y544410D01*
X431950Y544720D01*
X432103Y545185D01*
Y547407D01*
G01X434360Y544307D02*
X434628Y544359D01*
X434935Y544514D01*
X435127Y544772D01*
X435203Y545134D01*
X435127Y545495D01*
X434897Y545805D01*
X434552Y545960D01*
X434168D01*
X433938Y546064D01*
X433747Y546322D01*
X433670Y546684D01*
X433785Y547045D01*
X434053Y547304D01*
X434360Y547407D01*
X434667Y547304D01*
X434935Y547045D01*
X435050Y546684D01*
X434973Y546322D01*
X434782Y546064D01*
X434552Y545960D01*
X434168D01*
X433823Y545805D01*
X433593Y545495D01*
X433517Y545134D01*
X433593Y544772D01*
X433785Y544514D01*
X434092Y544359D01*
X434360Y544307D01*
G01X423903Y543492D02*
Y545492D01*
G01X431107Y541035D02*
X433057D01*
G01X425445Y549448D02*
X422245D01*
G01X425445Y555648D02*
Y549448D01*
G01X422245D02*
Y555648D01*
G01X420686Y551942D02*
Y548742D01*
G01X429639Y549424D02*
X426439D01*
G01X429639Y555624D02*
Y549424D01*
G01X426439D02*
Y555624D01*
G01X433951Y549408D02*
X430751D01*
G01D02*
Y555608D01*
G01X437580Y556240D02*
X421430D01*
G01X422245Y555648D02*
X425445D01*
G01X425345Y552548D02*
X422345D01*
G01X426439Y555624D02*
X429639D01*
G01X420715Y560617D02*
Y557417D01*
G01X420697Y555993D02*
Y552793D01*
G01X429660Y557587D02*
X426460D01*
G01X429660Y563787D02*
Y557587D01*
G01X426460D02*
Y563787D01*
G01D02*
X429660D01*
G01X425429Y557507D02*
X422229D01*
G01X425429Y563707D02*
Y557507D01*
G01X422229D02*
Y563707D01*
G01D02*
X425429D01*
G01X433752Y557573D02*
X430552D01*
G01D02*
Y563773D01*
G01D02*
X433752D01*
G01X430751Y555608D02*
X433951D01*
G01X422799Y564525D02*
Y567725D01*
G01X428999Y564525D02*
X422799D01*
G01X428999Y567725D02*
Y564525D01*
G01X429551Y568542D02*
X427051D01*
Y569182D01*
X427176Y569395D01*
X427468Y569555D01*
X427801Y569608D01*
X428134Y569555D01*
X428384Y569422D01*
X428509Y569182D01*
Y568542D01*
G01X429551Y570742D02*
X427051D01*
Y571408D01*
X427176Y571622D01*
X427343Y571755D01*
X427676Y571808D01*
X428009Y571755D01*
X428218Y571595D01*
X428343Y571408D01*
Y570742D01*
G01Y571408D02*
X429551Y571808D01*
G01X428509Y572968D02*
X428218Y573155D01*
X428051Y573315D01*
X427968Y573528D01*
X428051Y573715D01*
X428218Y573848D01*
X428468Y573955D01*
X428759Y573982D01*
X429009Y573955D01*
X429259Y573848D01*
X429468Y573688D01*
X429551Y573502D01*
X429468Y573288D01*
X429218Y573102D01*
X428843Y572995D01*
X428426Y572968D01*
X427884Y573022D01*
X427593Y573102D01*
X427301Y573235D01*
X427093Y573422D01*
X427051Y573608D01*
X427134Y573795D01*
X427343Y573928D01*
G01X429551Y575995D02*
X427051D01*
X428843Y575008D01*
Y576342D01*
G01X425320Y568462D02*
X422820D01*
Y569102D01*
X422945Y569315D01*
X423237Y569475D01*
X423570Y569528D01*
X423903Y569475D01*
X424153Y569342D01*
X424278Y569102D01*
Y568462D01*
G01X425320Y570662D02*
X422820D01*
Y571328D01*
X422945Y571542D01*
X423112Y571675D01*
X423445Y571728D01*
X423778Y571675D01*
X423987Y571515D01*
X424112Y571328D01*
Y570662D01*
G01Y571328D02*
X425320Y571728D01*
G01Y573342D02*
X424778Y573395D01*
X424320Y573475D01*
X423903Y573582D01*
X423445Y573715D01*
X422820Y573928D01*
Y572862D01*
G01X424820Y575008D02*
X425112Y575168D01*
X425278Y575382D01*
X425320Y575622D01*
X425278Y575835D01*
X425070Y576048D01*
X424820Y576182D01*
X424570Y576208D01*
X424278Y576155D01*
X424070Y575968D01*
X423987Y575782D01*
Y575542D01*
G01Y575782D02*
X423862Y575942D01*
X423653Y576075D01*
X423403Y576128D01*
X423153Y576075D01*
X422945Y575942D01*
X422820Y575702D01*
X422862Y575462D01*
X423028Y575222D01*
G01X433643Y568528D02*
X431143D01*
Y569168D01*
X431268Y569381D01*
X431560Y569541D01*
X431893Y569594D01*
X432226Y569541D01*
X432476Y569408D01*
X432601Y569168D01*
Y568528D01*
G01X433643Y570728D02*
X431143D01*
Y571394D01*
X431268Y571608D01*
X431435Y571741D01*
X431768Y571794D01*
X432101Y571741D01*
X432310Y571581D01*
X432435Y571394D01*
Y570728D01*
G01Y571394D02*
X433643Y571794D01*
G01X432601Y572954D02*
X432310Y573141D01*
X432143Y573301D01*
X432060Y573514D01*
X432143Y573701D01*
X432310Y573834D01*
X432560Y573941D01*
X432851Y573968D01*
X433101Y573941D01*
X433351Y573834D01*
X433560Y573674D01*
X433643Y573488D01*
X433560Y573274D01*
X433310Y573088D01*
X432935Y572981D01*
X432518Y572954D01*
X431976Y573008D01*
X431685Y573088D01*
X431393Y573221D01*
X431185Y573408D01*
X431143Y573594D01*
X431226Y573781D01*
X431435Y573914D01*
G01X433643Y575661D02*
X431143D01*
X431643Y575341D01*
G01X433643D02*
Y575981D01*
G01X422765Y577073D02*
Y579573D01*
X423405D01*
X423618Y579448D01*
X423778Y579156D01*
X423831Y578823D01*
X423778Y578490D01*
X423645Y578240D01*
X423405Y578115D01*
X422765D01*
G01X424965Y577073D02*
Y579573D01*
X425631D01*
X425845Y579448D01*
X425978Y579281D01*
X426031Y578948D01*
X425978Y578615D01*
X425818Y578406D01*
X425631Y578281D01*
X424965D01*
G01X425631D02*
X426031Y577073D01*
G01X427645D02*
X427698Y577615D01*
X427778Y578073D01*
X427885Y578490D01*
X428018Y578948D01*
X428231Y579573D01*
X427165D01*
G01X429391Y579156D02*
X429551Y579406D01*
X429738Y579531D01*
X429951Y579573D01*
X430218Y579490D01*
X430405Y579281D01*
X430458Y579031D01*
X430431Y578781D01*
X430325Y578573D01*
X429791Y578156D01*
X429551Y577865D01*
X429391Y577448D01*
X429338Y577073D01*
X430458D01*
G01X422799Y567725D02*
X428999D01*
G01X436092Y585979D02*
X429892D01*
G01Y589179D02*
X436092D01*
G01X429892Y585979D02*
Y589179D01*
G01X422724Y582151D02*
Y584651D01*
X423390D01*
X423604Y584526D01*
X423737Y584359D01*
X423790Y584026D01*
X423737Y583693D01*
X423577Y583484D01*
X423390Y583359D01*
X422724D01*
G01X423390D02*
X423790Y582151D01*
G01X424950Y583193D02*
X425137Y583484D01*
X425297Y583651D01*
X425510Y583734D01*
X425697Y583651D01*
X425830Y583484D01*
X425937Y583234D01*
X425964Y582943D01*
X425937Y582693D01*
X425830Y582443D01*
X425670Y582234D01*
X425484Y582151D01*
X425270Y582234D01*
X425084Y582484D01*
X424977Y582859D01*
X424950Y583276D01*
X425004Y583818D01*
X425084Y584109D01*
X425217Y584401D01*
X425404Y584609D01*
X425590Y584651D01*
X425777Y584568D01*
X425910Y584359D01*
G01X427070Y582526D02*
X427230Y582318D01*
X427417Y582193D01*
X427657Y582151D01*
X427897Y582234D01*
X428084Y582401D01*
X428217Y582693D01*
X428244Y583026D01*
X428190Y583359D01*
X428057Y583568D01*
X427870Y583734D01*
X427684Y583776D01*
X427497Y583734D01*
X427257Y583568D01*
X427337Y584651D01*
X428057D01*
G01X429804Y582151D02*
X429857Y582693D01*
X429937Y583151D01*
X430044Y583568D01*
X430177Y584026D01*
X430390Y584651D01*
X429324D01*
G01X431278Y582364D02*
Y584864D01*
X431944D01*
X432158Y584739D01*
X432291Y584572D01*
X432344Y584239D01*
X432291Y583906D01*
X432131Y583697D01*
X431944Y583572D01*
X431278D01*
G01X431944D02*
X432344Y582364D01*
G01X434011D02*
Y584864D01*
X433691Y584364D01*
G01Y582364D02*
X434331D01*
G01X436211D02*
Y584864D01*
X435891Y584364D01*
G01Y582364D02*
X436531D01*
G01X437904Y584447D02*
X438064Y584697D01*
X438251Y584822D01*
X438464Y584864D01*
X438731Y584781D01*
X438918Y584572D01*
X438971Y584322D01*
X438944Y584072D01*
X438838Y583864D01*
X438304Y583447D01*
X438064Y583156D01*
X437904Y582739D01*
X437851Y582364D01*
X438971D01*
G01X440611D02*
X440798Y582406D01*
X441011Y582531D01*
X441144Y582739D01*
X441198Y583031D01*
X441144Y583322D01*
X440984Y583572D01*
X440744Y583697D01*
X440478D01*
X440318Y583781D01*
X440184Y583989D01*
X440131Y584281D01*
X440211Y584572D01*
X440398Y584781D01*
X440611Y584864D01*
X440824Y584781D01*
X441011Y584572D01*
X441091Y584281D01*
X441038Y583989D01*
X440904Y583781D01*
X440744Y583697D01*
X440478D01*
X440238Y583572D01*
X440078Y583322D01*
X440024Y583031D01*
X440078Y582739D01*
X440211Y582531D01*
X440424Y582406D01*
X440611Y582364D01*
G01X420217Y598900D02*
Y595700D01*
G01X420870Y584589D02*
X418370D01*
Y585255D01*
X418495Y585469D01*
X418662Y585602D01*
X418995Y585655D01*
X419328Y585602D01*
X419537Y585442D01*
X419662Y585255D01*
Y584589D01*
G01Y585255D02*
X420870Y585655D01*
G01Y587322D02*
X418370D01*
X418870Y587002D01*
G01X420870D02*
Y587642D01*
G01Y589522D02*
X418370D01*
X418870Y589202D01*
G01X420870D02*
Y589842D01*
G01X420370Y591135D02*
X420662Y591295D01*
X420828Y591509D01*
X420870Y591749D01*
X420828Y591962D01*
X420620Y592175D01*
X420370Y592309D01*
X420120Y592335D01*
X419828Y592282D01*
X419620Y592095D01*
X419537Y591909D01*
Y591669D01*
G01Y591909D02*
X419412Y592069D01*
X419203Y592202D01*
X418953Y592255D01*
X418703Y592202D01*
X418495Y592069D01*
X418370Y591829D01*
X418412Y591589D01*
X418578Y591349D01*
G01X418370Y593922D02*
X418453Y593709D01*
X418662Y593549D01*
X418912Y593442D01*
X419245Y593362D01*
X419620Y593335D01*
X419995Y593362D01*
X420328Y593442D01*
X420578Y593549D01*
X420787Y593709D01*
X420870Y593922D01*
X420787Y594135D01*
X420578Y594295D01*
X420328Y594402D01*
X419995Y594482D01*
X419620Y594509D01*
X419245Y594482D01*
X418912Y594402D01*
X418662Y594295D01*
X418453Y594135D01*
X418370Y593922D01*
G01X428304Y587058D02*
X421504D01*
G01D02*
Y602058D01*
G01X428304D02*
Y587058D01*
G01X440986Y590133D02*
X429174D01*
G01D02*
Y601851D01*
G01X420746Y611142D02*
Y607942D01*
G01X417646Y611042D02*
Y608042D01*
G01X420217Y602857D02*
Y599657D01*
G01X417117Y599757D02*
Y602757D01*
G01X423576Y606942D02*
X421076D01*
Y607582D01*
X421201Y607795D01*
X421493Y607955D01*
X421826Y608008D01*
X422159Y607955D01*
X422409Y607822D01*
X422534Y607582D01*
Y606942D01*
G01X421284Y610262D02*
X421159Y610102D01*
X421076Y609915D01*
Y609702D01*
X421201Y609462D01*
X421409Y609275D01*
X421659Y609142D01*
X422076Y609035D01*
X422451Y609008D01*
X422826Y609062D01*
X423076Y609142D01*
X423326Y609302D01*
X423493Y609488D01*
X423576Y609675D01*
Y609862D01*
X423493Y610048D01*
X423368Y610208D01*
X423201Y610342D01*
G01X423576Y612195D02*
X421076D01*
X422868Y611208D01*
Y612542D01*
G01X423576Y614075D02*
X421076D01*
X421576Y613755D01*
G01X423576D02*
Y614395D01*
G01X423626Y606120D02*
X429826D01*
G01Y602920D02*
X423626D01*
G01D02*
Y606120D01*
G01X429826D02*
Y602920D01*
G01X436844D02*
X430644D01*
G01D02*
Y606120D01*
G01D02*
X436844D01*
G01X420746Y607100D02*
Y603900D01*
G01X421504Y602058D02*
X428304D01*
G01X429174Y601851D02*
X440986D01*
G01X425996Y608736D02*
Y611236D01*
X426530D01*
X426743Y611111D01*
X426903Y610944D01*
X427036Y610694D01*
X427143Y610403D01*
X427170Y609986D01*
X427143Y609569D01*
X427036Y609278D01*
X426903Y609028D01*
X426743Y608861D01*
X426530Y608736D01*
X425996D01*
G01X423815Y607973D02*
Y622973D01*
G01X436815Y607973D02*
X423815D01*
G01X421950Y624500D02*
Y627490D01*
G01X438600Y624500D02*
X421950D01*
G01X417205Y619713D02*
Y613513D01*
G01X423120Y616468D02*
X420620D01*
Y617108D01*
X420745Y617321D01*
X421037Y617481D01*
X421370Y617534D01*
X421703Y617481D01*
X421953Y617348D01*
X422078Y617108D01*
Y616468D01*
G01X423120Y618668D02*
X420620D01*
Y619334D01*
X420745Y619548D01*
X420912Y619681D01*
X421245Y619734D01*
X421578Y619681D01*
X421787Y619521D01*
X421912Y619334D01*
Y618668D01*
G01Y619334D02*
X423120Y619734D01*
G01Y621401D02*
X420620D01*
X421120Y621081D01*
G01X423120D02*
Y621721D01*
G01X422620Y623014D02*
X422912Y623174D01*
X423078Y623388D01*
X423120Y623628D01*
X423078Y623841D01*
X422870Y624054D01*
X422620Y624188D01*
X422370Y624214D01*
X422078Y624161D01*
X421870Y623974D01*
X421787Y623788D01*
Y623548D01*
G01Y623788D02*
X421662Y623948D01*
X421453Y624081D01*
X421203Y624134D01*
X420953Y624081D01*
X420745Y623948D01*
X420620Y623708D01*
X420662Y623468D01*
X420828Y623228D01*
G01X420003Y616420D02*
X417503D01*
Y617060D01*
X417628Y617273D01*
X417920Y617433D01*
X418253Y617486D01*
X418586Y617433D01*
X418836Y617300D01*
X418961Y617060D01*
Y616420D01*
G01X420003Y618620D02*
X417503D01*
Y619286D01*
X417628Y619500D01*
X417795Y619633D01*
X418128Y619686D01*
X418461Y619633D01*
X418670Y619473D01*
X418795Y619286D01*
Y618620D01*
G01Y619286D02*
X420003Y619686D01*
G01Y621353D02*
X417503D01*
X418003Y621033D01*
G01X420003D02*
Y621673D01*
G01Y623873D02*
X417503D01*
X419295Y622886D01*
Y624220D01*
G01X430650Y627295D02*
X431183D01*
Y626545D01*
X431023Y626295D01*
X430837Y626128D01*
X430570Y626045D01*
X430303Y626128D01*
X430117Y626295D01*
X429957Y626545D01*
X429850Y626837D01*
X429797Y627170D01*
Y627462D01*
X429850Y627712D01*
X429957Y628003D01*
X430117Y628253D01*
X430277Y628420D01*
X430490Y628545D01*
X430677D01*
X430890Y628462D01*
X431050Y628295D01*
G01X437781Y624977D02*
X422781D01*
G01D02*
Y637977D01*
G01X430090Y620124D02*
X430623D01*
Y619374D01*
X430463Y619124D01*
X430277Y618957D01*
X430010Y618874D01*
X429743Y618957D01*
X429557Y619124D01*
X429397Y619374D01*
X429290Y619666D01*
X429237Y619999D01*
Y620291D01*
X429290Y620541D01*
X429397Y620832D01*
X429557Y621082D01*
X429717Y621249D01*
X429930Y621374D01*
X430117D01*
X430330Y621291D01*
X430490Y621124D01*
G01X423815Y622973D02*
X436815D01*
G01X423636Y639080D02*
Y642280D01*
G01X429836D02*
Y639080D01*
G01X423636Y642280D02*
X429836D01*
G01Y639080D02*
X423636D01*
G01X421179Y646354D02*
Y643154D01*
G01X421182Y635247D02*
Y628447D01*
G01X420796Y637011D02*
Y639511D01*
X421330D01*
X421543Y639386D01*
X421703Y639219D01*
X421836Y638969D01*
X421943Y638678D01*
X421970Y638261D01*
X421943Y637844D01*
X421836Y637553D01*
X421703Y637303D01*
X421543Y637136D01*
X421330Y637011D01*
X420796D01*
G01X422781Y637977D02*
X437781D01*
G01X421940Y658156D02*
Y664756D01*
G01X424440Y656656D02*
X421940Y658156D01*
G01Y655156D02*
X424440Y656656D01*
G01X421940Y648556D02*
Y655156D01*
G01X434940Y648556D02*
X421940D01*
G01X424745Y644500D02*
Y647700D01*
G01X430945Y644500D02*
X424745D01*
G01X430945Y647700D02*
Y644500D01*
G01X424745Y647700D02*
X430945D01*
G01X421094Y654332D02*
Y651132D01*
G01Y658483D02*
Y655283D01*
G01Y650299D02*
Y647099D01*
G01X421940Y664756D02*
X434940D01*
G01X423128Y674892D02*
Y677992D01*
X424087D01*
X424393Y677837D01*
X424585Y677630D01*
X424662Y677217D01*
X424585Y676804D01*
X424355Y676545D01*
X424087Y676390D01*
X423128D01*
G01X424087D02*
X424662Y674892D01*
G01X426918D02*
X426995Y675564D01*
X427110Y676132D01*
X427263Y676649D01*
X427455Y677217D01*
X427762Y677992D01*
X426228D01*
G01X429367Y676184D02*
X429635Y676545D01*
X429865Y676752D01*
X430172Y676855D01*
X430440Y676752D01*
X430632Y676545D01*
X430785Y676235D01*
X430823Y675874D01*
X430785Y675564D01*
X430632Y675254D01*
X430402Y674995D01*
X430133Y674892D01*
X429827Y674995D01*
X429558Y675305D01*
X429405Y675770D01*
X429367Y676287D01*
X429443Y676959D01*
X429558Y677320D01*
X429750Y677682D01*
X430018Y677940D01*
X430287Y677992D01*
X430555Y677889D01*
X430747Y677630D01*
G01X432467Y677475D02*
X432697Y677785D01*
X432965Y677940D01*
X433272Y677992D01*
X433655Y677889D01*
X433923Y677630D01*
X434000Y677320D01*
X433962Y677010D01*
X433808Y676752D01*
X433042Y676235D01*
X432697Y675874D01*
X432467Y675357D01*
X432390Y674892D01*
X434000D01*
G01X423128Y670934D02*
Y674034D01*
X424087D01*
X424393Y673879D01*
X424585Y673672D01*
X424662Y673259D01*
X424585Y672846D01*
X424355Y672587D01*
X424087Y672432D01*
X423128D01*
G01X424087D02*
X424662Y670934D01*
G01X426918D02*
X426995Y671606D01*
X427110Y672174D01*
X427263Y672691D01*
X427455Y673259D01*
X427762Y674034D01*
X426228D01*
G01X429367Y672226D02*
X429635Y672587D01*
X429865Y672794D01*
X430172Y672897D01*
X430440Y672794D01*
X430632Y672587D01*
X430785Y672277D01*
X430823Y671916D01*
X430785Y671606D01*
X430632Y671296D01*
X430402Y671037D01*
X430133Y670934D01*
X429827Y671037D01*
X429558Y671347D01*
X429405Y671812D01*
X429367Y672329D01*
X429443Y673001D01*
X429558Y673362D01*
X429750Y673724D01*
X430018Y673982D01*
X430287Y674034D01*
X430555Y673931D01*
X430747Y673672D01*
G01X432352Y671554D02*
X432582Y671192D01*
X432888Y670986D01*
X433233Y670934D01*
X433540Y670986D01*
X433847Y671244D01*
X434038Y671554D01*
X434077Y671864D01*
X434000Y672226D01*
X433732Y672484D01*
X433463Y672587D01*
X433118D01*
G01X433463D02*
X433693Y672742D01*
X433885Y673001D01*
X433962Y673311D01*
X433885Y673621D01*
X433693Y673879D01*
X433348Y674034D01*
X433003Y673982D01*
X432658Y673776D01*
G01X421094Y674694D02*
Y671494D01*
G01X423128Y666995D02*
Y670095D01*
X424087D01*
X424393Y669940D01*
X424585Y669733D01*
X424662Y669320D01*
X424585Y668907D01*
X424355Y668648D01*
X424087Y668493D01*
X423128D01*
G01X424087D02*
X424662Y666995D01*
G01X426918D02*
X426995Y667667D01*
X427110Y668235D01*
X427263Y668752D01*
X427455Y669320D01*
X427762Y670095D01*
X426228D01*
G01X429367Y668287D02*
X429635Y668648D01*
X429865Y668855D01*
X430172Y668958D01*
X430440Y668855D01*
X430632Y668648D01*
X430785Y668338D01*
X430823Y667977D01*
X430785Y667667D01*
X430632Y667357D01*
X430402Y667098D01*
X430133Y666995D01*
X429827Y667098D01*
X429558Y667408D01*
X429405Y667873D01*
X429367Y668390D01*
X429443Y669062D01*
X429558Y669423D01*
X429750Y669785D01*
X430018Y670043D01*
X430287Y670095D01*
X430555Y669992D01*
X430747Y669733D01*
G01X433195Y666995D02*
Y670095D01*
X432735Y669475D01*
G01Y666995D02*
X433655D01*
G01X421094Y670627D02*
Y667427D01*
G01X431770Y688830D02*
X436550D01*
G01X431770Y723430D02*
Y688830D01*
G01X421943Y691839D02*
X421713Y691994D01*
X421445Y692097D01*
X421138D01*
X420793Y691942D01*
X420525Y691684D01*
X420333Y691374D01*
X420180Y690857D01*
X420142Y690392D01*
X420218Y689927D01*
X420333Y689617D01*
X420563Y689307D01*
X420832Y689100D01*
X421100Y688997D01*
X421368D01*
X421637Y689100D01*
X421867Y689255D01*
X422058Y689462D01*
G01X423357D02*
X423587Y689204D01*
X423855Y689049D01*
X424200Y688997D01*
X424545Y689100D01*
X424813Y689307D01*
X425005Y689669D01*
X425043Y690082D01*
X424967Y690495D01*
X424775Y690754D01*
X424507Y690960D01*
X424238Y691012D01*
X423970Y690960D01*
X423625Y690754D01*
X423740Y692097D01*
X424775D01*
G01X427223Y688997D02*
X427300Y689669D01*
X427415Y690237D01*
X427568Y690754D01*
X427760Y691322D01*
X428067Y692097D01*
X426533D01*
G01X430860Y688997D02*
Y692097D01*
X429442Y689875D01*
X431358D01*
G01X424510Y683927D02*
Y686927D01*
G01X421410Y683827D02*
Y687027D01*
G01X427610Y683827D02*
X421410D01*
G01X427610Y687027D02*
Y683827D01*
G01X421410Y687027D02*
X427610D01*
G01X416181Y690815D02*
X419381D01*
G01X416181Y684615D02*
Y690815D01*
G01X419381Y684615D02*
X416181D01*
G01X419381Y690815D02*
Y684615D01*
G01X421094Y678728D02*
Y675528D01*
G01X423128Y678954D02*
Y682054D01*
X424087D01*
X424393Y681899D01*
X424585Y681692D01*
X424662Y681279D01*
X424585Y680866D01*
X424355Y680607D01*
X424087Y680452D01*
X423128D01*
G01X424087D02*
X424662Y678954D01*
G01X426918D02*
X426995Y679626D01*
X427110Y680194D01*
X427263Y680711D01*
X427455Y681279D01*
X427762Y682054D01*
X426228D01*
G01X429367Y680246D02*
X429635Y680607D01*
X429865Y680814D01*
X430172Y680917D01*
X430440Y680814D01*
X430632Y680607D01*
X430785Y680297D01*
X430823Y679936D01*
X430785Y679626D01*
X430632Y679316D01*
X430402Y679057D01*
X430133Y678954D01*
X429827Y679057D01*
X429558Y679367D01*
X429405Y679832D01*
X429367Y680349D01*
X429443Y681021D01*
X429558Y681382D01*
X429750Y681744D01*
X430018Y682002D01*
X430287Y682054D01*
X430555Y681951D01*
X430747Y681692D01*
G01X433195Y682054D02*
X432888Y681951D01*
X432658Y681692D01*
X432505Y681382D01*
X432390Y680969D01*
X432352Y680504D01*
X432390Y680039D01*
X432505Y679626D01*
X432658Y679316D01*
X432888Y679057D01*
X433195Y678954D01*
X433502Y679057D01*
X433732Y679316D01*
X433885Y679626D01*
X434000Y680039D01*
X434038Y680504D01*
X434000Y680969D01*
X433885Y681382D01*
X433732Y681692D01*
X433502Y681951D01*
X433195Y682054D01*
G01X421094Y682722D02*
Y679522D01*
G01X419002Y703164D02*
Y706164D01*
G01X422102Y706264D02*
Y703064D01*
G01X417238Y707458D02*
Y710558D01*
X418197D01*
X418503Y710403D01*
X418695Y710196D01*
X418772Y709783D01*
X418695Y709370D01*
X418465Y709111D01*
X418197Y708956D01*
X417238D01*
G01X418197D02*
X418772Y707458D01*
G01X421028D02*
X421105Y708130D01*
X421220Y708698D01*
X421373Y709215D01*
X421565Y709783D01*
X421872Y710558D01*
X420338D01*
G01X423362Y708078D02*
X423592Y707716D01*
X423898Y707510D01*
X424243Y707458D01*
X424550Y707510D01*
X424857Y707768D01*
X425048Y708078D01*
X425087Y708388D01*
X425010Y708750D01*
X424742Y709008D01*
X424473Y709111D01*
X424128D01*
G01X424473D02*
X424703Y709266D01*
X424895Y709525D01*
X424972Y709835D01*
X424895Y710145D01*
X424703Y710403D01*
X424358Y710558D01*
X424013Y710506D01*
X423668Y710300D01*
G01X426462Y707923D02*
X426692Y707665D01*
X426960Y707510D01*
X427305Y707458D01*
X427650Y707561D01*
X427918Y707768D01*
X428110Y708130D01*
X428148Y708543D01*
X428072Y708956D01*
X427880Y709215D01*
X427612Y709421D01*
X427343Y709473D01*
X427075Y709421D01*
X426730Y709215D01*
X426845Y710558D01*
X427880D01*
G01X422102Y698313D02*
Y695113D01*
G01Y702269D02*
Y699069D01*
G01X419253Y721909D02*
X419023Y722064D01*
X418755Y722167D01*
X418448D01*
X418103Y722012D01*
X417835Y721754D01*
X417643Y721444D01*
X417490Y720927D01*
X417452Y720462D01*
X417528Y719997D01*
X417643Y719687D01*
X417873Y719377D01*
X418142Y719170D01*
X418410Y719067D01*
X418678D01*
X418947Y719170D01*
X419177Y719325D01*
X419368Y719532D01*
G01X420667D02*
X420897Y719274D01*
X421165Y719119D01*
X421510Y719067D01*
X421855Y719170D01*
X422123Y719377D01*
X422315Y719739D01*
X422353Y720152D01*
X422277Y720565D01*
X422085Y720824D01*
X421817Y721030D01*
X421548Y721082D01*
X421280Y721030D01*
X420935Y720824D01*
X421050Y722167D01*
X422085D01*
G01X424533Y719067D02*
X424610Y719739D01*
X424725Y720307D01*
X424878Y720824D01*
X425070Y721392D01*
X425377Y722167D01*
X423843D01*
G01X426867Y719687D02*
X427097Y719325D01*
X427403Y719119D01*
X427748Y719067D01*
X428055Y719119D01*
X428362Y719377D01*
X428553Y719687D01*
X428592Y719997D01*
X428515Y720359D01*
X428247Y720617D01*
X427978Y720720D01*
X427633D01*
G01X427978D02*
X428208Y720875D01*
X428400Y721134D01*
X428477Y721444D01*
X428400Y721754D01*
X428208Y722012D01*
X427863Y722167D01*
X427518Y722115D01*
X427173Y721909D01*
G01X417198Y711860D02*
Y714960D01*
X418157D01*
X418463Y714805D01*
X418655Y714598D01*
X418732Y714185D01*
X418655Y713772D01*
X418425Y713513D01*
X418157Y713358D01*
X417198D01*
G01X418157D02*
X418732Y711860D01*
G01X420988D02*
X421065Y712532D01*
X421180Y713100D01*
X421333Y713617D01*
X421525Y714185D01*
X421832Y714960D01*
X420298D01*
G01X423322Y712325D02*
X423552Y712067D01*
X423820Y711912D01*
X424165Y711860D01*
X424510Y711963D01*
X424778Y712170D01*
X424970Y712532D01*
X425008Y712945D01*
X424932Y713358D01*
X424740Y713617D01*
X424472Y713823D01*
X424203Y713875D01*
X423935Y713823D01*
X423590Y713617D01*
X423705Y714960D01*
X424740D01*
G01X427265Y711860D02*
Y714960D01*
X426805Y714340D01*
G01Y711860D02*
X427725D01*
G01X442450Y723430D02*
X431770D01*
G01X420040Y737556D02*
X416840D01*
G01D02*
Y743756D01*
G01X420040D02*
Y737556D01*
G01X432540D02*
X429340D01*
G01D02*
Y743756D01*
G01X428040Y737556D02*
X424840D01*
G01X428040Y743756D02*
Y737556D01*
G01X424840D02*
Y743756D01*
G01X423440Y729156D02*
X420440D01*
G01X423540Y726056D02*
X420340D01*
G01X423540Y732256D02*
Y726056D01*
G01X420340Y732256D02*
X423540D01*
G01X420340Y726056D02*
Y732256D01*
G01X420840Y737556D02*
Y743756D01*
G01X424040Y737556D02*
X420840D01*
G01X424040Y743756D02*
Y737556D01*
G01X429340Y732256D02*
X432540D01*
G01X429340Y726056D02*
Y732256D01*
G01X432540Y726056D02*
X429340D01*
G01X424840Y732256D02*
X428040D01*
G01X424840Y726056D02*
Y732256D01*
G01X428040Y726056D02*
X424840D01*
G01X428040Y732256D02*
Y726056D01*
G01X419940Y740656D02*
X416940D01*
G01X416840Y743756D02*
X420040D01*
G01X432440Y740656D02*
X429440D01*
G01X429340Y743756D02*
X432540D01*
G01X427940Y740656D02*
X424940D01*
G01X424840Y743756D02*
X428040D01*
G01X423870Y749921D02*
X423715Y749691D01*
X423612Y749423D01*
Y749116D01*
X423767Y748771D01*
X424025Y748503D01*
X424335Y748311D01*
X424852Y748158D01*
X425317Y748120D01*
X425782Y748196D01*
X426092Y748311D01*
X426402Y748541D01*
X426609Y748810D01*
X426712Y749078D01*
Y749346D01*
X426609Y749615D01*
X426454Y749845D01*
X426247Y750036D01*
G01X425420Y751450D02*
X425059Y751718D01*
X424852Y751948D01*
X424749Y752255D01*
X424852Y752523D01*
X425059Y752715D01*
X425369Y752868D01*
X425730Y752906D01*
X426040Y752868D01*
X426350Y752715D01*
X426609Y752485D01*
X426712Y752216D01*
X426609Y751910D01*
X426299Y751641D01*
X425834Y751488D01*
X425317Y751450D01*
X424645Y751526D01*
X424284Y751641D01*
X423922Y751833D01*
X423664Y752101D01*
X423612Y752370D01*
X423715Y752638D01*
X423974Y752830D01*
G01X426350Y754626D02*
X426609Y754895D01*
X426712Y755201D01*
X426609Y755508D01*
X426299Y755776D01*
X425834Y755968D01*
X425369Y756045D01*
X424800D01*
X424335Y755968D01*
X423922Y755776D01*
X423715Y755546D01*
X423612Y755278D01*
X423715Y754971D01*
X423922Y754741D01*
X424232Y754588D01*
X424645Y754511D01*
X425007Y754588D01*
X425369Y754780D01*
X425575Y755010D01*
X425627Y755278D01*
X425524Y755585D01*
X425265Y755815D01*
X424800Y756045D01*
G01X425420Y757650D02*
X425059Y757918D01*
X424852Y758148D01*
X424749Y758455D01*
X424852Y758723D01*
X425059Y758915D01*
X425369Y759068D01*
X425730Y759106D01*
X426040Y759068D01*
X426350Y758915D01*
X426609Y758685D01*
X426712Y758416D01*
X426609Y758110D01*
X426299Y757841D01*
X425834Y757688D01*
X425317Y757650D01*
X424645Y757726D01*
X424284Y757841D01*
X423922Y758033D01*
X423664Y758301D01*
X423612Y758570D01*
X423715Y758838D01*
X423974Y759030D01*
G01X420840Y743756D02*
X424040D01*
G01X430687Y748311D02*
X427587D01*
Y749270D01*
X427742Y749576D01*
X427949Y749768D01*
X428362Y749845D01*
X428775Y749768D01*
X429034Y749538D01*
X429189Y749270D01*
Y748311D01*
G01Y749270D02*
X430687Y749845D01*
G01Y752178D02*
X430635Y752446D01*
X430480Y752753D01*
X430222Y752945D01*
X429860Y753021D01*
X429499Y752945D01*
X429189Y752715D01*
X429034Y752370D01*
Y751986D01*
X428930Y751756D01*
X428672Y751565D01*
X428310Y751488D01*
X427949Y751603D01*
X427690Y751871D01*
X427587Y752178D01*
X427690Y752485D01*
X427949Y752753D01*
X428310Y752868D01*
X428672Y752791D01*
X428930Y752600D01*
X429034Y752370D01*
Y751986D01*
X429189Y751641D01*
X429499Y751411D01*
X429860Y751335D01*
X430222Y751411D01*
X430480Y751603D01*
X430635Y751910D01*
X430687Y752178D01*
G01X430325Y754626D02*
X430584Y754895D01*
X430687Y755201D01*
X430584Y755508D01*
X430274Y755776D01*
X429809Y755968D01*
X429344Y756045D01*
X428775D01*
X428310Y755968D01*
X427897Y755776D01*
X427690Y755546D01*
X427587Y755278D01*
X427690Y754971D01*
X427897Y754741D01*
X428207Y754588D01*
X428620Y754511D01*
X428982Y754588D01*
X429344Y754780D01*
X429550Y755010D01*
X429602Y755278D01*
X429499Y755585D01*
X429240Y755815D01*
X428775Y756045D01*
G01X430067Y757535D02*
X430429Y757765D01*
X430635Y758071D01*
X430687Y758416D01*
X430635Y758723D01*
X430377Y759030D01*
X430067Y759221D01*
X429757Y759260D01*
X429395Y759183D01*
X429137Y758915D01*
X429034Y758646D01*
Y758301D01*
G01Y758646D02*
X428879Y758876D01*
X428620Y759068D01*
X428310Y759145D01*
X428000Y759068D01*
X427742Y758876D01*
X427587Y758531D01*
X427639Y758186D01*
X427845Y757841D01*
G01X420004Y762932D02*
X419849Y762702D01*
X419746Y762434D01*
Y762127D01*
X419901Y761782D01*
X420159Y761514D01*
X420469Y761322D01*
X420986Y761169D01*
X421451Y761131D01*
X421916Y761207D01*
X422226Y761322D01*
X422536Y761552D01*
X422743Y761821D01*
X422846Y762089D01*
Y762357D01*
X422743Y762626D01*
X422588Y762856D01*
X422381Y763047D01*
G01X421554Y764461D02*
X421193Y764729D01*
X420986Y764959D01*
X420883Y765266D01*
X420986Y765534D01*
X421193Y765726D01*
X421503Y765879D01*
X421864Y765917D01*
X422174Y765879D01*
X422484Y765726D01*
X422743Y765496D01*
X422846Y765227D01*
X422743Y764921D01*
X422433Y764652D01*
X421968Y764499D01*
X421451Y764461D01*
X420779Y764537D01*
X420418Y764652D01*
X420056Y764844D01*
X419798Y765112D01*
X419746Y765381D01*
X419849Y765649D01*
X420108Y765841D01*
G01X422484Y767637D02*
X422743Y767906D01*
X422846Y768212D01*
X422743Y768519D01*
X422433Y768787D01*
X421968Y768979D01*
X421503Y769056D01*
X420934D01*
X420469Y768979D01*
X420056Y768787D01*
X419849Y768557D01*
X419746Y768289D01*
X419849Y767982D01*
X420056Y767752D01*
X420366Y767599D01*
X420779Y767522D01*
X421141Y767599D01*
X421503Y767791D01*
X421709Y768021D01*
X421761Y768289D01*
X421658Y768596D01*
X421399Y768826D01*
X420934Y769056D01*
G01X422484Y770737D02*
X422743Y771006D01*
X422846Y771312D01*
X422743Y771619D01*
X422433Y771887D01*
X421968Y772079D01*
X421503Y772156D01*
X420934D01*
X420469Y772079D01*
X420056Y771887D01*
X419849Y771657D01*
X419746Y771389D01*
X419849Y771082D01*
X420056Y770852D01*
X420366Y770699D01*
X420779Y770622D01*
X421141Y770699D01*
X421503Y770891D01*
X421709Y771121D01*
X421761Y771389D01*
X421658Y771696D01*
X421399Y771926D01*
X420934Y772156D01*
G01X428111Y762932D02*
X427956Y762702D01*
X427853Y762434D01*
Y762127D01*
X428008Y761782D01*
X428266Y761514D01*
X428576Y761322D01*
X429093Y761169D01*
X429558Y761131D01*
X430023Y761207D01*
X430333Y761322D01*
X430643Y761552D01*
X430850Y761821D01*
X430953Y762089D01*
Y762357D01*
X430850Y762626D01*
X430695Y762856D01*
X430488Y763047D01*
G01X429661Y764461D02*
X429300Y764729D01*
X429093Y764959D01*
X428990Y765266D01*
X429093Y765534D01*
X429300Y765726D01*
X429610Y765879D01*
X429971Y765917D01*
X430281Y765879D01*
X430591Y765726D01*
X430850Y765496D01*
X430953Y765227D01*
X430850Y764921D01*
X430540Y764652D01*
X430075Y764499D01*
X429558Y764461D01*
X428886Y764537D01*
X428525Y764652D01*
X428163Y764844D01*
X427905Y765112D01*
X427853Y765381D01*
X427956Y765649D01*
X428215Y765841D01*
G01X430488Y767446D02*
X430746Y767676D01*
X430901Y767944D01*
X430953Y768289D01*
X430850Y768634D01*
X430643Y768902D01*
X430281Y769094D01*
X429868Y769132D01*
X429455Y769056D01*
X429196Y768864D01*
X428990Y768596D01*
X428938Y768327D01*
X428990Y768059D01*
X429196Y767714D01*
X427853Y767829D01*
Y768864D01*
G01X429661Y770661D02*
X429300Y770929D01*
X429093Y771159D01*
X428990Y771466D01*
X429093Y771734D01*
X429300Y771926D01*
X429610Y772079D01*
X429971Y772117D01*
X430281Y772079D01*
X430591Y771926D01*
X430850Y771696D01*
X430953Y771427D01*
X430850Y771121D01*
X430540Y770852D01*
X430075Y770699D01*
X429558Y770661D01*
X428886Y770737D01*
X428525Y770852D01*
X428163Y771044D01*
X427905Y771312D01*
X427853Y771581D01*
X427956Y771849D01*
X428215Y772041D01*
G01X426925Y761322D02*
X423825D01*
Y762281D01*
X423980Y762587D01*
X424187Y762779D01*
X424600Y762856D01*
X425013Y762779D01*
X425272Y762549D01*
X425427Y762281D01*
Y761322D01*
G01Y762281D02*
X426925Y762856D01*
G01X426563Y764537D02*
X426822Y764806D01*
X426925Y765112D01*
X426822Y765419D01*
X426512Y765687D01*
X426047Y765879D01*
X425582Y765956D01*
X425013D01*
X424548Y765879D01*
X424135Y765687D01*
X423928Y765457D01*
X423825Y765189D01*
X423928Y764882D01*
X424135Y764652D01*
X424445Y764499D01*
X424858Y764422D01*
X425220Y764499D01*
X425582Y764691D01*
X425788Y764921D01*
X425840Y765189D01*
X425737Y765496D01*
X425478Y765726D01*
X425013Y765956D01*
G01X426305Y767446D02*
X426667Y767676D01*
X426873Y767982D01*
X426925Y768327D01*
X426873Y768634D01*
X426615Y768941D01*
X426305Y769132D01*
X425995Y769171D01*
X425633Y769094D01*
X425375Y768826D01*
X425272Y768557D01*
Y768212D01*
G01Y768557D02*
X425117Y768787D01*
X424858Y768979D01*
X424548Y769056D01*
X424238Y768979D01*
X423980Y768787D01*
X423825Y768442D01*
X423877Y768097D01*
X424083Y767752D01*
G01X426305Y770546D02*
X426667Y770776D01*
X426873Y771082D01*
X426925Y771427D01*
X426873Y771734D01*
X426615Y772041D01*
X426305Y772232D01*
X425995Y772271D01*
X425633Y772194D01*
X425375Y771926D01*
X425272Y771657D01*
Y771312D01*
G01Y771657D02*
X425117Y771887D01*
X424858Y772079D01*
X424548Y772156D01*
X424238Y772079D01*
X423980Y771887D01*
X423825Y771542D01*
X423877Y771197D01*
X424083Y770852D01*
G01X447904Y70323D02*
X444704D01*
G01X447804Y73423D02*
X444804D01*
G01X444704Y70323D02*
Y76523D01*
G01D02*
X447904D01*
G01X441207Y82227D02*
X443429D01*
X443894Y82380D01*
X444204Y82687D01*
X444307Y83070D01*
X444204Y83453D01*
X443894Y83760D01*
X443429Y83913D01*
X441207D01*
G01X444307Y86170D02*
X441207D01*
X441827Y85710D01*
G01X444307D02*
Y86630D01*
G01X441724Y88542D02*
X441414Y88772D01*
X441259Y89040D01*
X441207Y89347D01*
X441310Y89730D01*
X441569Y89998D01*
X441879Y90075D01*
X442189Y90037D01*
X442447Y89883D01*
X442964Y89117D01*
X443325Y88772D01*
X443842Y88542D01*
X444307Y88465D01*
Y90075D01*
G01X443687Y91527D02*
X444049Y91757D01*
X444255Y92063D01*
X444307Y92408D01*
X444255Y92715D01*
X443997Y93022D01*
X443687Y93213D01*
X443377Y93252D01*
X443015Y93175D01*
X442757Y92907D01*
X442654Y92638D01*
Y92293D01*
G01Y92638D02*
X442499Y92868D01*
X442240Y93060D01*
X441930Y93137D01*
X441620Y93060D01*
X441362Y92868D01*
X441207Y92523D01*
X441259Y92178D01*
X441465Y91833D01*
G01X446536Y81509D02*
X446349Y81218D01*
X446189Y81051D01*
X445976Y80968D01*
X445789Y81051D01*
X445656Y81218D01*
X445549Y81468D01*
X445522Y81759D01*
X445549Y82009D01*
X445656Y82259D01*
X445816Y82468D01*
X446002Y82551D01*
X446216Y82468D01*
X446402Y82218D01*
X446509Y81843D01*
X446536Y81426D01*
X446482Y80884D01*
X446402Y80593D01*
X446269Y80301D01*
X446082Y80093D01*
X445896Y80051D01*
X445709Y80134D01*
X445576Y80343D01*
G01X445381Y93908D02*
X445541Y93700D01*
X445728Y93575D01*
X445968Y93533D01*
X446208Y93616D01*
X446395Y93783D01*
X446528Y94075D01*
X446555Y94408D01*
X446501Y94741D01*
X446368Y94950D01*
X446181Y95116D01*
X445995Y95158D01*
X445808Y95116D01*
X445568Y94950D01*
X445648Y96033D01*
X446368D01*
G01X447104Y121665D02*
Y106665D01*
G01X440304D02*
Y121665D01*
G01X447104Y106665D02*
X440304D01*
G01X439337Y121793D02*
Y106793D01*
G01X432537D02*
Y121793D01*
G01X439337Y106793D02*
X432537D01*
G01X434786Y100635D02*
X434978Y100325D01*
X435208Y100118D01*
X435476Y100015D01*
X435783Y100118D01*
X436013Y100325D01*
X436243Y100635D01*
X436320Y101048D01*
Y103115D01*
G01X437925Y102598D02*
X438155Y102908D01*
X438423Y103063D01*
X438730Y103115D01*
X439113Y103012D01*
X439381Y102753D01*
X439458Y102443D01*
X439420Y102133D01*
X439266Y101875D01*
X438500Y101358D01*
X438155Y100997D01*
X437925Y100480D01*
X437848Y100015D01*
X439458D01*
G01X442213D02*
Y103115D01*
X440795Y100893D01*
X442711D01*
G01X445109Y125032D02*
X444954Y124802D01*
X444851Y124534D01*
Y124227D01*
X445006Y123882D01*
X445264Y123614D01*
X445574Y123422D01*
X446091Y123269D01*
X446556Y123231D01*
X447021Y123307D01*
X447331Y123422D01*
X447641Y123652D01*
X447848Y123921D01*
X447951Y124189D01*
Y124457D01*
X447848Y124726D01*
X447693Y124956D01*
X447486Y125147D01*
G01X447951Y127289D02*
X447899Y127557D01*
X447744Y127864D01*
X447486Y128056D01*
X447124Y128132D01*
X446763Y128056D01*
X446453Y127826D01*
X446298Y127481D01*
Y127097D01*
X446194Y126867D01*
X445936Y126676D01*
X445574Y126599D01*
X445213Y126714D01*
X444954Y126982D01*
X444851Y127289D01*
X444954Y127596D01*
X445213Y127864D01*
X445574Y127979D01*
X445936Y127902D01*
X446194Y127711D01*
X446298Y127481D01*
Y127097D01*
X446453Y126752D01*
X446763Y126522D01*
X447124Y126446D01*
X447486Y126522D01*
X447744Y126714D01*
X447899Y127021D01*
X447951Y127289D01*
G01X447486Y129546D02*
X447744Y129776D01*
X447899Y130044D01*
X447951Y130389D01*
X447848Y130734D01*
X447641Y131002D01*
X447279Y131194D01*
X446866Y131232D01*
X446453Y131156D01*
X446194Y130964D01*
X445988Y130696D01*
X445936Y130427D01*
X445988Y130159D01*
X446194Y129814D01*
X444851Y129929D01*
Y130964D01*
G01X447951Y133489D02*
X447899Y133757D01*
X447744Y134064D01*
X447486Y134256D01*
X447124Y134332D01*
X446763Y134256D01*
X446453Y134026D01*
X446298Y133681D01*
Y133297D01*
X446194Y133067D01*
X445936Y132876D01*
X445574Y132799D01*
X445213Y132914D01*
X444954Y133182D01*
X444851Y133489D01*
X444954Y133796D01*
X445213Y134064D01*
X445574Y134179D01*
X445936Y134102D01*
X446194Y133911D01*
X446298Y133681D01*
Y133297D01*
X446453Y132952D01*
X446763Y132722D01*
X447124Y132646D01*
X447486Y132722D01*
X447744Y132914D01*
X447899Y133221D01*
X447951Y133489D01*
G01X440304Y121665D02*
X447104D01*
G01X440404Y114165D02*
X447004D01*
G01X435943Y124536D02*
X435788Y124306D01*
X435685Y124038D01*
Y123731D01*
X435840Y123386D01*
X436098Y123118D01*
X436408Y122926D01*
X436925Y122773D01*
X437390Y122735D01*
X437855Y122811D01*
X438165Y122926D01*
X438475Y123156D01*
X438682Y123425D01*
X438785Y123693D01*
Y123961D01*
X438682Y124230D01*
X438527Y124460D01*
X438320Y124651D01*
G01X438785Y126793D02*
X438733Y127061D01*
X438578Y127368D01*
X438320Y127560D01*
X437958Y127636D01*
X437597Y127560D01*
X437287Y127330D01*
X437132Y126985D01*
Y126601D01*
X437028Y126371D01*
X436770Y126180D01*
X436408Y126103D01*
X436047Y126218D01*
X435788Y126486D01*
X435685Y126793D01*
X435788Y127100D01*
X436047Y127368D01*
X436408Y127483D01*
X436770Y127406D01*
X437028Y127215D01*
X437132Y126985D01*
Y126601D01*
X437287Y126256D01*
X437597Y126026D01*
X437958Y125950D01*
X438320Y126026D01*
X438578Y126218D01*
X438733Y126525D01*
X438785Y126793D01*
G01X438320Y129050D02*
X438578Y129280D01*
X438733Y129548D01*
X438785Y129893D01*
X438682Y130238D01*
X438475Y130506D01*
X438113Y130698D01*
X437700Y130736D01*
X437287Y130660D01*
X437028Y130468D01*
X436822Y130200D01*
X436770Y129931D01*
X436822Y129663D01*
X437028Y129318D01*
X435685Y129433D01*
Y130468D01*
G01X438423Y132341D02*
X438682Y132610D01*
X438785Y132916D01*
X438682Y133223D01*
X438372Y133491D01*
X437907Y133683D01*
X437442Y133760D01*
X436873D01*
X436408Y133683D01*
X435995Y133491D01*
X435788Y133261D01*
X435685Y132993D01*
X435788Y132686D01*
X435995Y132456D01*
X436305Y132303D01*
X436718Y132226D01*
X437080Y132303D01*
X437442Y132495D01*
X437648Y132725D01*
X437700Y132993D01*
X437597Y133300D01*
X437338Y133530D01*
X436873Y133760D01*
G01X432537Y121793D02*
X439337D01*
G01X432637Y114293D02*
X439237D01*
G01X442307Y157499D02*
X442467Y157749D01*
X442654Y157874D01*
X442867Y157916D01*
X443134Y157833D01*
X443321Y157624D01*
X443374Y157374D01*
X443347Y157124D01*
X443241Y156916D01*
X442707Y156499D01*
X442467Y156208D01*
X442307Y155791D01*
X442254Y155416D01*
X443374D01*
G01X464874Y152967D02*
X444402D01*
G01D02*
Y181313D01*
G01X443031Y173279D02*
Y175779D01*
X442711Y175279D01*
G01Y173279D02*
X443351D01*
G01X444402Y181313D02*
X464874D01*
G01X445501Y186038D02*
X451701D01*
G01Y182838D02*
X445501D01*
G01D02*
Y186038D01*
G01X446667Y189938D02*
X446512Y189708D01*
X446409Y189440D01*
Y189133D01*
X446564Y188788D01*
X446822Y188520D01*
X447132Y188328D01*
X447649Y188175D01*
X448114Y188137D01*
X448579Y188213D01*
X448889Y188328D01*
X449199Y188558D01*
X449406Y188827D01*
X449509Y189095D01*
Y189363D01*
X449406Y189632D01*
X449251Y189862D01*
X449044Y190053D01*
G01X449509Y192655D02*
X446409D01*
X448631Y191237D01*
Y193153D01*
G01X449509Y195295D02*
X449457Y195563D01*
X449302Y195870D01*
X449044Y196062D01*
X448682Y196138D01*
X448321Y196062D01*
X448011Y195832D01*
X447856Y195487D01*
Y195103D01*
X447752Y194873D01*
X447494Y194682D01*
X447132Y194605D01*
X446771Y194720D01*
X446512Y194988D01*
X446409Y195295D01*
X446512Y195602D01*
X446771Y195870D01*
X447132Y195985D01*
X447494Y195908D01*
X447752Y195717D01*
X447856Y195487D01*
Y195103D01*
X448011Y194758D01*
X448321Y194528D01*
X448682Y194452D01*
X449044Y194528D01*
X449302Y194720D01*
X449457Y195027D01*
X449509Y195295D01*
G01Y198855D02*
X446409D01*
X448631Y197437D01*
Y199353D01*
G01X438790Y231946D02*
X438977Y232237D01*
X439137Y232404D01*
X439350Y232487D01*
X439537Y232404D01*
X439670Y232237D01*
X439777Y231987D01*
X439804Y231696D01*
X439777Y231446D01*
X439670Y231196D01*
X439510Y230987D01*
X439324Y230904D01*
X439110Y230987D01*
X438924Y231237D01*
X438817Y231612D01*
X438790Y232029D01*
X438844Y232571D01*
X438924Y232862D01*
X439057Y233154D01*
X439244Y233362D01*
X439430Y233404D01*
X439617Y233321D01*
X439750Y233112D01*
G01X441497Y233404D02*
X441284Y233321D01*
X441124Y233112D01*
X441017Y232862D01*
X440937Y232529D01*
X440910Y232154D01*
X440937Y231779D01*
X441017Y231446D01*
X441124Y231196D01*
X441284Y230987D01*
X441497Y230904D01*
X441710Y230987D01*
X441870Y231196D01*
X441977Y231446D01*
X442057Y231779D01*
X442084Y232154D01*
X442057Y232529D01*
X441977Y232862D01*
X441870Y233112D01*
X441710Y233321D01*
X441497Y233404D01*
G01X437856Y241875D02*
Y230385D01*
G01X452435Y247804D02*
X446235D01*
G01D02*
Y251004D01*
G01X452101Y243562D02*
X445901D01*
G01D02*
Y246762D01*
G01D02*
X452101D01*
G01X445901Y242762D02*
X452101D01*
G01Y239562D02*
X445901D01*
G01D02*
Y242762D01*
G01X452101Y235562D02*
X445901D01*
G01D02*
Y238762D01*
G01D02*
X452101D01*
G01X446235Y251004D02*
X452435D01*
G01X445982Y264591D02*
X456182D01*
G01Y259991D02*
X445982D01*
G01D02*
Y264591D01*
G01X439981Y304844D02*
X440141Y305094D01*
X440328Y305219D01*
X440541Y305261D01*
X440808Y305178D01*
X440995Y304969D01*
X441048Y304719D01*
X441021Y304469D01*
X440915Y304261D01*
X440381Y303844D01*
X440141Y303553D01*
X439981Y303136D01*
X439928Y302761D01*
X441048D01*
G01X437856Y314243D02*
Y302662D01*
G01X442515Y393903D02*
Y397003D01*
G01X444125D02*
Y393903D01*
G01Y395453D02*
X442515D01*
G01X445577Y394368D02*
X445807Y394110D01*
X446075Y393955D01*
X446420Y393903D01*
X446765Y394006D01*
X447033Y394213D01*
X447225Y394575D01*
X447263Y394988D01*
X447187Y395401D01*
X446995Y395660D01*
X446727Y395866D01*
X446458Y395918D01*
X446190Y395866D01*
X445845Y395660D01*
X445960Y397003D01*
X446995D01*
G01X470012Y409847D02*
X434316D01*
G01D02*
Y427563D01*
G01D02*
X470012D01*
G01X434316Y429847D02*
Y447563D01*
G01X470012Y429847D02*
X434316D01*
G01X446343Y454593D02*
X443243D01*
Y455513D01*
X443398Y455820D01*
X443760Y456050D01*
X444173Y456127D01*
X444586Y456050D01*
X444896Y455858D01*
X445051Y455513D01*
Y454593D01*
G01X443243Y457693D02*
X446343D01*
Y459227D01*
G01Y461560D02*
X446291Y461828D01*
X446136Y462135D01*
X445878Y462327D01*
X445516Y462403D01*
X445155Y462327D01*
X444845Y462097D01*
X444690Y461752D01*
Y461368D01*
X444586Y461138D01*
X444328Y460947D01*
X443966Y460870D01*
X443605Y460985D01*
X443346Y461253D01*
X443243Y461560D01*
X443346Y461867D01*
X443605Y462135D01*
X443966Y462250D01*
X444328Y462173D01*
X444586Y461982D01*
X444690Y461752D01*
Y461368D01*
X444845Y461023D01*
X445155Y460793D01*
X445516Y460717D01*
X445878Y460793D01*
X446136Y460985D01*
X446291Y461292D01*
X446343Y461560D01*
G01X441975Y452246D02*
X436047D01*
G01X441975Y480750D02*
Y452246D01*
G01X434316Y447563D02*
X470012D01*
G01X441714Y483373D02*
Y482440D01*
G01X436047Y480750D02*
X441975D01*
G01X446404Y491607D02*
X448626D01*
X449091Y491760D01*
X449401Y492067D01*
X449504Y492450D01*
X449401Y492833D01*
X449091Y493140D01*
X448626Y493293D01*
X446404D01*
G01X449504Y495550D02*
X446404D01*
X447024Y495090D01*
G01X449504D02*
Y496010D01*
G01X446921Y497922D02*
X446611Y498152D01*
X446456Y498420D01*
X446404Y498727D01*
X446507Y499110D01*
X446766Y499378D01*
X447076Y499455D01*
X447386Y499417D01*
X447644Y499263D01*
X448161Y498497D01*
X448522Y498152D01*
X449039Y497922D01*
X449504Y497845D01*
Y499455D01*
G01Y502210D02*
X446404D01*
X448626Y500792D01*
Y502708D01*
G01X441714Y487373D02*
Y488373D01*
G01Y492373D02*
Y493373D01*
G01Y497373D02*
Y498373D01*
G01X433220Y514190D02*
Y504170D01*
G01X441714Y503306D02*
Y502373D01*
G01X432879Y508919D02*
Y505719D01*
G01X437534Y504843D02*
X434434D01*
Y505763D01*
X434589Y506070D01*
X434951Y506300D01*
X435364Y506377D01*
X435777Y506300D01*
X436087Y506108D01*
X436242Y505763D01*
Y504843D01*
G01X434692Y509553D02*
X434537Y509323D01*
X434434Y509055D01*
Y508748D01*
X434589Y508403D01*
X434847Y508135D01*
X435157Y507943D01*
X435674Y507790D01*
X436139Y507752D01*
X436604Y507828D01*
X436914Y507943D01*
X437224Y508173D01*
X437431Y508442D01*
X437534Y508710D01*
Y508978D01*
X437431Y509247D01*
X437276Y509477D01*
X437069Y509668D01*
G01X437172Y511158D02*
X437431Y511427D01*
X437534Y511733D01*
X437431Y512040D01*
X437121Y512308D01*
X436656Y512500D01*
X436191Y512577D01*
X435622D01*
X435157Y512500D01*
X434744Y512308D01*
X434537Y512078D01*
X434434Y511810D01*
X434537Y511503D01*
X434744Y511273D01*
X435054Y511120D01*
X435467Y511043D01*
X435829Y511120D01*
X436191Y511312D01*
X436397Y511542D01*
X436449Y511810D01*
X436346Y512117D01*
X436087Y512347D01*
X435622Y512577D01*
G01X437069Y514067D02*
X437327Y514297D01*
X437482Y514565D01*
X437534Y514910D01*
X437431Y515255D01*
X437224Y515523D01*
X436862Y515715D01*
X436449Y515753D01*
X436036Y515677D01*
X435777Y515485D01*
X435571Y515217D01*
X435519Y514948D01*
X435571Y514680D01*
X435777Y514335D01*
X434434Y514450D01*
Y515485D01*
G01X441249Y511212D02*
X438249D01*
G01X441349Y508112D02*
X438149D01*
G01X441349Y514312D02*
Y508112D01*
G01X438149Y514312D02*
X441349D01*
G01X438149Y508112D02*
Y514312D01*
G01X432531Y513181D02*
Y509981D01*
G01X445368Y516636D02*
X442168D01*
G01X445368Y522836D02*
Y516636D01*
G01X442168D02*
Y522836D01*
G01X441362Y516581D02*
X438162D01*
G01X441362Y522781D02*
Y516581D01*
G01X438162D02*
Y522781D01*
G01X449358Y516636D02*
X446158D01*
G01D02*
Y522836D01*
G01X449314Y503403D02*
X446214D01*
Y504323D01*
X446369Y504630D01*
X446731Y504860D01*
X447144Y504937D01*
X447557Y504860D01*
X447867Y504668D01*
X448022Y504323D01*
Y503403D01*
G01X449314Y506503D02*
X446214D01*
Y507462D01*
X446369Y507768D01*
X446576Y507960D01*
X446989Y508037D01*
X447402Y507960D01*
X447661Y507730D01*
X447816Y507462D01*
Y506503D01*
G01Y507462D02*
X449314Y508037D01*
G01Y510830D02*
X446214D01*
X448436Y509412D01*
Y511328D01*
G01X448694Y512627D02*
X449056Y512857D01*
X449262Y513163D01*
X449314Y513508D01*
X449262Y513815D01*
X449004Y514122D01*
X448694Y514313D01*
X448384Y514352D01*
X448022Y514275D01*
X447764Y514007D01*
X447661Y513738D01*
Y513393D01*
G01Y513738D02*
X447506Y513968D01*
X447247Y514160D01*
X446937Y514237D01*
X446627Y514160D01*
X446369Y513968D01*
X446214Y513623D01*
X446266Y513278D01*
X446472Y512933D01*
G01X445445Y508110D02*
X442245D01*
G01X445445Y514310D02*
Y508110D01*
G01X442245Y514310D02*
X445445D01*
G01X442245Y508110D02*
Y514310D01*
G01X439320Y524150D02*
X451400D01*
G01X439320Y539830D02*
Y524150D01*
G01X436920Y519157D02*
Y522257D01*
X436460Y521637D01*
G01Y519157D02*
X437380D01*
G01X435493Y530307D02*
X437493D01*
G01X433057Y523107D02*
Y521153D01*
G01X444129Y529521D02*
Y535721D01*
G01X447329Y529521D02*
X444129D01*
G01X447329Y535721D02*
Y529521D01*
G01X444229Y532621D02*
X447229D01*
G01X443665Y524918D02*
Y528118D01*
G01X449865Y524918D02*
X443665D01*
G01Y528118D02*
X449865D01*
G01X446765Y525018D02*
Y528018D01*
G01X440051Y529601D02*
Y535801D01*
G01X443251Y529601D02*
X440051D01*
G01X443251Y535801D02*
Y529601D01*
G01X442168Y522836D02*
X445368D01*
G01X438162Y522781D02*
X441362D01*
G01X446158Y522836D02*
X449358D01*
G01X435740Y539830D02*
X439320D01*
G01X435740Y548380D02*
Y539830D01*
G01X436070Y534810D02*
Y537310D01*
X435750Y536810D01*
G01Y534810D02*
X436390D01*
G01X438270Y537310D02*
X438057Y537227D01*
X437897Y537018D01*
X437790Y536768D01*
X437710Y536435D01*
X437683Y536060D01*
X437710Y535685D01*
X437790Y535352D01*
X437897Y535102D01*
X438057Y534893D01*
X438270Y534810D01*
X438483Y534893D01*
X438643Y535102D01*
X438750Y535352D01*
X438830Y535685D01*
X438857Y536060D01*
X438830Y536435D01*
X438750Y536768D01*
X438643Y537018D01*
X438483Y537227D01*
X438270Y537310D01*
G01X435502Y538181D02*
X439502D01*
G01X433057Y541035D02*
Y539057D01*
G01X444129Y535721D02*
X447329D01*
G01X444628Y541602D02*
X441428D01*
G01X444628Y547802D02*
Y541602D01*
G01X441428D02*
Y547802D01*
G01X444528Y544702D02*
X441528D01*
G01X441428Y547802D02*
X444628D01*
G01X435958Y545989D02*
X440558D01*
G01Y540889D02*
X435958D01*
G01X440558Y551089D02*
Y540889D01*
G01X435958D02*
Y551089D01*
G01X433951Y555608D02*
Y549408D01*
G01X440051Y535801D02*
X443251D01*
G01X444936Y548843D02*
Y555043D01*
G01X448136Y548843D02*
X444936D01*
G01X438760Y556060D02*
X436670D01*
G01X438760Y574470D02*
Y556060D01*
G01X442078Y563155D02*
X439578D01*
Y563795D01*
X439703Y564008D01*
X439995Y564168D01*
X440328Y564221D01*
X440661Y564168D01*
X440911Y564035D01*
X441036Y563795D01*
Y563155D01*
G01X439786Y566475D02*
X439661Y566315D01*
X439578Y566128D01*
Y565915D01*
X439703Y565675D01*
X439911Y565488D01*
X440161Y565355D01*
X440578Y565248D01*
X440953Y565221D01*
X441328Y565275D01*
X441578Y565355D01*
X441828Y565515D01*
X441995Y565701D01*
X442078Y565888D01*
Y566075D01*
X441995Y566261D01*
X441870Y566421D01*
X441703Y566555D01*
G01X442078Y568088D02*
X439578D01*
X440078Y567768D01*
G01X442078D02*
Y568408D01*
G01Y570288D02*
X439578D01*
X440078Y569968D01*
G01X442078D02*
Y570608D01*
G01Y572488D02*
X439578D01*
X440078Y572168D01*
G01X442078D02*
Y572808D01*
G01X435958Y551089D02*
X440558D01*
G01X445422Y563215D02*
X442922D01*
Y563855D01*
X443047Y564068D01*
X443339Y564228D01*
X443672Y564281D01*
X444005Y564228D01*
X444255Y564095D01*
X444380Y563855D01*
Y563215D01*
G01X445422Y565415D02*
X442922D01*
Y566081D01*
X443047Y566295D01*
X443214Y566428D01*
X443547Y566481D01*
X443880Y566428D01*
X444089Y566268D01*
X444214Y566081D01*
Y565415D01*
G01Y566081D02*
X445422Y566481D01*
G01X444380Y567641D02*
X444089Y567828D01*
X443922Y567988D01*
X443839Y568201D01*
X443922Y568388D01*
X444089Y568521D01*
X444339Y568628D01*
X444630Y568655D01*
X444880Y568628D01*
X445130Y568521D01*
X445339Y568361D01*
X445422Y568175D01*
X445339Y567961D01*
X445089Y567775D01*
X444714Y567668D01*
X444297Y567641D01*
X443755Y567695D01*
X443464Y567775D01*
X443172Y567908D01*
X442964Y568095D01*
X442922Y568281D01*
X443005Y568468D01*
X443214Y568601D01*
G01X445047Y569761D02*
X445255Y569921D01*
X445380Y570108D01*
X445422Y570348D01*
X445339Y570588D01*
X445172Y570775D01*
X444880Y570908D01*
X444547Y570935D01*
X444214Y570881D01*
X444005Y570748D01*
X443839Y570561D01*
X443797Y570375D01*
X443839Y570188D01*
X444005Y569948D01*
X442922Y570028D01*
Y570748D01*
G01X433752Y563773D02*
Y557573D01*
G01X448594Y563307D02*
X446094D01*
Y563947D01*
X446219Y564160D01*
X446511Y564320D01*
X446844Y564373D01*
X447177Y564320D01*
X447427Y564187D01*
X447552Y563947D01*
Y563307D01*
G01X448594Y565507D02*
X446094D01*
Y566173D01*
X446219Y566387D01*
X446386Y566520D01*
X446719Y566573D01*
X447052Y566520D01*
X447261Y566360D01*
X447386Y566173D01*
Y565507D01*
G01Y566173D02*
X448594Y566573D01*
G01X447552Y567733D02*
X447261Y567920D01*
X447094Y568080D01*
X447011Y568293D01*
X447094Y568480D01*
X447261Y568613D01*
X447511Y568720D01*
X447802Y568747D01*
X448052Y568720D01*
X448302Y568613D01*
X448511Y568453D01*
X448594Y568267D01*
X448511Y568053D01*
X448261Y567867D01*
X447886Y567760D01*
X447469Y567733D01*
X446927Y567787D01*
X446636Y567867D01*
X446344Y568000D01*
X446136Y568187D01*
X446094Y568373D01*
X446177Y568560D01*
X446386Y568693D01*
G01X446511Y569933D02*
X446261Y570093D01*
X446136Y570280D01*
X446094Y570493D01*
X446177Y570760D01*
X446386Y570947D01*
X446636Y571000D01*
X446886Y570973D01*
X447094Y570867D01*
X447511Y570333D01*
X447802Y570093D01*
X448219Y569933D01*
X448594Y569880D01*
Y571000D01*
G01X444936Y555043D02*
X448136D01*
G01X437819Y557608D02*
X434619D01*
G01X437819Y563808D02*
Y557608D01*
G01X434619D02*
Y563808D01*
G01D02*
X437819D01*
G01X434765Y551737D02*
Y554937D01*
G01X440965Y551737D02*
X434765D01*
G01X440965Y554937D02*
Y551737D01*
G01X434765Y554937D02*
X440965D01*
G01X458470Y574470D02*
X438760D01*
G01X447351Y575987D02*
Y578487D01*
X448017D01*
X448231Y578362D01*
X448364Y578195D01*
X448417Y577862D01*
X448364Y577529D01*
X448204Y577320D01*
X448017Y577195D01*
X447351D01*
G01X448017D02*
X448417Y575987D01*
G01X450084D02*
Y578487D01*
X449764Y577987D01*
G01Y575987D02*
X450404D01*
G01X452284Y578487D02*
X452071Y578404D01*
X451911Y578195D01*
X451804Y577945D01*
X451724Y577612D01*
X451697Y577237D01*
X451724Y576862D01*
X451804Y576529D01*
X451911Y576279D01*
X452071Y576070D01*
X452284Y575987D01*
X452497Y576070D01*
X452657Y576279D01*
X452764Y576529D01*
X452844Y576862D01*
X452871Y577237D01*
X452844Y577612D01*
X452764Y577945D01*
X452657Y578195D01*
X452497Y578404D01*
X452284Y578487D01*
G01X453897Y576487D02*
X454057Y576195D01*
X454271Y576029D01*
X454511Y575987D01*
X454724Y576029D01*
X454937Y576237D01*
X455071Y576487D01*
X455097Y576737D01*
X455044Y577029D01*
X454857Y577237D01*
X454671Y577320D01*
X454431D01*
G01X454671D02*
X454831Y577445D01*
X454964Y577654D01*
X455017Y577904D01*
X454964Y578154D01*
X454831Y578362D01*
X454591Y578487D01*
X454351Y578445D01*
X454111Y578279D01*
G01X456684Y575987D02*
X456871Y576029D01*
X457084Y576154D01*
X457217Y576362D01*
X457271Y576654D01*
X457217Y576945D01*
X457057Y577195D01*
X456817Y577320D01*
X456551D01*
X456391Y577404D01*
X456257Y577612D01*
X456204Y577904D01*
X456284Y578195D01*
X456471Y578404D01*
X456684Y578487D01*
X456897Y578404D01*
X457084Y578195D01*
X457164Y577904D01*
X457111Y577612D01*
X456977Y577404D01*
X456817Y577320D01*
X456551D01*
X456311Y577195D01*
X456151Y576945D01*
X456097Y576654D01*
X456151Y576362D01*
X456284Y576154D01*
X456497Y576029D01*
X456684Y575987D01*
G01X437710Y568563D02*
X435210D01*
Y569203D01*
X435335Y569416D01*
X435627Y569576D01*
X435960Y569629D01*
X436293Y569576D01*
X436543Y569443D01*
X436668Y569203D01*
Y568563D01*
G01X437710Y570763D02*
X435210D01*
Y571429D01*
X435335Y571643D01*
X435502Y571776D01*
X435835Y571829D01*
X436168Y571776D01*
X436377Y571616D01*
X436502Y571429D01*
Y570763D01*
G01Y571429D02*
X437710Y571829D01*
G01X437335Y572909D02*
X437543Y573069D01*
X437668Y573256D01*
X437710Y573496D01*
X437627Y573736D01*
X437460Y573923D01*
X437168Y574056D01*
X436835Y574083D01*
X436502Y574029D01*
X436293Y573896D01*
X436127Y573709D01*
X436085Y573523D01*
X436127Y573336D01*
X436293Y573096D01*
X435210Y573176D01*
Y573896D01*
G01X437710Y575643D02*
X437168Y575696D01*
X436710Y575776D01*
X436293Y575883D01*
X435835Y576016D01*
X435210Y576229D01*
Y575163D01*
G01X445476Y579081D02*
Y581581D01*
X446142D01*
X446356Y581456D01*
X446489Y581289D01*
X446542Y580956D01*
X446489Y580623D01*
X446329Y580414D01*
X446142Y580289D01*
X445476D01*
G01X446142D02*
X446542Y579081D01*
G01X448209D02*
Y581581D01*
X447889Y581081D01*
G01Y579081D02*
X448529D01*
G01X449902Y581164D02*
X450062Y581414D01*
X450249Y581539D01*
X450462Y581581D01*
X450729Y581498D01*
X450916Y581289D01*
X450969Y581039D01*
X450942Y580789D01*
X450836Y580581D01*
X450302Y580164D01*
X450062Y579873D01*
X449902Y579456D01*
X449849Y579081D01*
X450969D01*
G01X452929D02*
Y581581D01*
X451942Y579789D01*
X453276D01*
G01X454356Y579373D02*
X454542Y579164D01*
X454756Y579081D01*
X454969Y579164D01*
X455156Y579414D01*
X455289Y579789D01*
X455342Y580164D01*
Y580623D01*
X455289Y580998D01*
X455156Y581331D01*
X454996Y581498D01*
X454809Y581581D01*
X454596Y581498D01*
X454436Y581331D01*
X454329Y581081D01*
X454276Y580748D01*
X454329Y580456D01*
X454462Y580164D01*
X454622Y579998D01*
X454809Y579956D01*
X455022Y580039D01*
X455182Y580248D01*
X455342Y580623D01*
G01X433624Y578534D02*
X433317Y578586D01*
X433049Y578792D01*
X432819Y579102D01*
X432666Y579464D01*
X432589Y579877D01*
Y580291D01*
X432666Y580704D01*
X432819Y581066D01*
X433049Y581376D01*
X433317Y581582D01*
X433624Y581634D01*
X433931Y581582D01*
X434199Y581376D01*
X434429Y581066D01*
X434582Y580704D01*
X434659Y580291D01*
Y579877D01*
X434582Y579464D01*
X434429Y579102D01*
X434199Y578792D01*
X433931Y578586D01*
X433624Y578534D01*
G01X433931Y579361D02*
X434391Y578534D01*
G01X437184D02*
Y581634D01*
X435766Y579412D01*
X437682D01*
G01X438981Y578999D02*
X439211Y578741D01*
X439479Y578586D01*
X439824Y578534D01*
X440169Y578637D01*
X440437Y578844D01*
X440629Y579206D01*
X440667Y579619D01*
X440591Y580032D01*
X440399Y580291D01*
X440131Y580497D01*
X439862Y580549D01*
X439594Y580497D01*
X439249Y580291D01*
X439364Y581634D01*
X440399D01*
G01X448116Y598153D02*
X447956Y598278D01*
X447769Y598361D01*
X447556D01*
X447316Y598236D01*
X447129Y598028D01*
X446996Y597778D01*
X446889Y597361D01*
X446862Y596986D01*
X446916Y596611D01*
X446996Y596361D01*
X447156Y596111D01*
X447342Y595944D01*
X447529Y595861D01*
X447716D01*
X447902Y595944D01*
X448062Y596069D01*
X448196Y596236D01*
G01X449729Y595861D02*
X449916Y595903D01*
X450129Y596028D01*
X450262Y596236D01*
X450316Y596528D01*
X450262Y596819D01*
X450102Y597069D01*
X449862Y597194D01*
X449596D01*
X449436Y597278D01*
X449302Y597486D01*
X449249Y597778D01*
X449329Y598069D01*
X449516Y598278D01*
X449729Y598361D01*
X449942Y598278D01*
X450129Y598069D01*
X450209Y597778D01*
X450156Y597486D01*
X450022Y597278D01*
X449862Y597194D01*
X449596D01*
X449356Y597069D01*
X449196Y596819D01*
X449142Y596528D01*
X449196Y596236D01*
X449329Y596028D01*
X449542Y595903D01*
X449729Y595861D01*
G01X451929D02*
X452116Y595903D01*
X452329Y596028D01*
X452462Y596236D01*
X452516Y596528D01*
X452462Y596819D01*
X452302Y597069D01*
X452062Y597194D01*
X451796D01*
X451636Y597278D01*
X451502Y597486D01*
X451449Y597778D01*
X451529Y598069D01*
X451716Y598278D01*
X451929Y598361D01*
X452142Y598278D01*
X452329Y598069D01*
X452409Y597778D01*
X452356Y597486D01*
X452222Y597278D01*
X452062Y597194D01*
X451796D01*
X451556Y597069D01*
X451396Y596819D01*
X451342Y596528D01*
X451396Y596236D01*
X451529Y596028D01*
X451742Y595903D01*
X451929Y595861D01*
G01X454076D02*
X454129Y596403D01*
X454209Y596861D01*
X454316Y597278D01*
X454449Y597736D01*
X454662Y598361D01*
X453596D01*
G01X441901Y585125D02*
Y587625D01*
X442567D01*
X442781Y587500D01*
X442914Y587333D01*
X442967Y587000D01*
X442914Y586667D01*
X442754Y586458D01*
X442567Y586333D01*
X441901D01*
G01X442567D02*
X442967Y585125D01*
G01X444634D02*
Y587625D01*
X444314Y587125D01*
G01Y585125D02*
X444954D01*
G01X446834Y587625D02*
X446621Y587542D01*
X446461Y587333D01*
X446354Y587083D01*
X446274Y586750D01*
X446247Y586375D01*
X446274Y586000D01*
X446354Y585667D01*
X446461Y585417D01*
X446621Y585208D01*
X446834Y585125D01*
X447047Y585208D01*
X447207Y585417D01*
X447314Y585667D01*
X447394Y586000D01*
X447421Y586375D01*
X447394Y586750D01*
X447314Y587083D01*
X447207Y587333D01*
X447047Y587542D01*
X446834Y587625D01*
G01X449034D02*
X448821Y587542D01*
X448661Y587333D01*
X448554Y587083D01*
X448474Y586750D01*
X448447Y586375D01*
X448474Y586000D01*
X448554Y585667D01*
X448661Y585417D01*
X448821Y585208D01*
X449034Y585125D01*
X449247Y585208D01*
X449407Y585417D01*
X449514Y585667D01*
X449594Y586000D01*
X449621Y586375D01*
X449594Y586750D01*
X449514Y587083D01*
X449407Y587333D01*
X449247Y587542D01*
X449034Y587625D01*
G01X451554Y585125D02*
Y587625D01*
X450567Y585833D01*
X451901D01*
G01X436092Y589179D02*
Y585979D01*
G01X434144Y596599D02*
Y599099D01*
X433824Y598599D01*
G01Y596599D02*
X434464D01*
G01X441980Y592976D02*
X442140Y593226D01*
X442327Y593351D01*
X442540Y593393D01*
X442807Y593310D01*
X442994Y593101D01*
X443047Y592851D01*
X443020Y592601D01*
X442914Y592393D01*
X442380Y591976D01*
X442140Y591685D01*
X441980Y591268D01*
X441927Y590893D01*
X443047D01*
G01X441900Y595752D02*
X442060Y595460D01*
X442274Y595294D01*
X442514Y595252D01*
X442727Y595294D01*
X442940Y595502D01*
X443074Y595752D01*
X443100Y596002D01*
X443047Y596294D01*
X442860Y596502D01*
X442674Y596585D01*
X442434D01*
G01X442674D02*
X442834Y596710D01*
X442967Y596919D01*
X443020Y597169D01*
X442967Y597419D01*
X442834Y597627D01*
X442594Y597752D01*
X442354Y597710D01*
X442114Y597544D01*
G01X440986Y601851D02*
Y590133D01*
G01X444833Y594320D02*
Y592528D01*
X444940Y592153D01*
X445153Y591903D01*
X445420Y591820D01*
X445687Y591903D01*
X445900Y592153D01*
X446007Y592528D01*
Y594320D01*
G01X447620Y591820D02*
Y594320D01*
X447300Y593820D01*
G01Y591820D02*
X447940D01*
G01X449820D02*
Y594320D01*
X449500Y593820D01*
G01Y591820D02*
X450140D01*
G01X452020D02*
Y594320D01*
X451700Y593820D01*
G01Y591820D02*
X452340D01*
G01X445775Y602222D02*
Y606822D01*
G01X455975Y602222D02*
X445775D01*
G01Y606822D02*
X455975D01*
G01X436844Y606120D02*
Y602920D01*
G01X441882Y598995D02*
Y601495D01*
X442548D01*
X442762Y601370D01*
X442895Y601203D01*
X442948Y600870D01*
X442895Y600537D01*
X442735Y600328D01*
X442548Y600203D01*
X441882D01*
G01X442548D02*
X442948Y598995D01*
G01X444615D02*
X444802Y599037D01*
X445015Y599162D01*
X445148Y599370D01*
X445202Y599662D01*
X445148Y599953D01*
X444988Y600203D01*
X444748Y600328D01*
X444482D01*
X444322Y600412D01*
X444188Y600620D01*
X444135Y600912D01*
X444215Y601203D01*
X444402Y601412D01*
X444615Y601495D01*
X444828Y601412D01*
X445015Y601203D01*
X445095Y600912D01*
X445042Y600620D01*
X444908Y600412D01*
X444748Y600328D01*
X444482D01*
X444242Y600203D01*
X444082Y599953D01*
X444028Y599662D01*
X444082Y599370D01*
X444215Y599162D01*
X444428Y599037D01*
X444615Y598995D01*
G01X446815Y601495D02*
X446602Y601412D01*
X446442Y601203D01*
X446335Y600953D01*
X446255Y600620D01*
X446228Y600245D01*
X446255Y599870D01*
X446335Y599537D01*
X446442Y599287D01*
X446602Y599078D01*
X446815Y598995D01*
X447028Y599078D01*
X447188Y599287D01*
X447295Y599537D01*
X447375Y599870D01*
X447402Y600245D01*
X447375Y600620D01*
X447295Y600953D01*
X447188Y601203D01*
X447028Y601412D01*
X446815Y601495D01*
G01X448508Y601078D02*
X448668Y601328D01*
X448855Y601453D01*
X449068Y601495D01*
X449335Y601412D01*
X449522Y601203D01*
X449575Y600953D01*
X449548Y600703D01*
X449442Y600495D01*
X448908Y600078D01*
X448668Y599787D01*
X448508Y599370D01*
X448455Y598995D01*
X449575D01*
G01X444715Y603471D02*
X438515D01*
G01X444715Y606671D02*
Y603471D01*
G01X438515Y606671D02*
X444715D01*
G01X438515Y603471D02*
Y606671D01*
G01X439088Y610483D02*
Y612983D01*
X439622D01*
X439835Y612858D01*
X439995Y612691D01*
X440128Y612441D01*
X440235Y612150D01*
X440262Y611733D01*
X440235Y611316D01*
X440128Y611025D01*
X439995Y610775D01*
X439835Y610608D01*
X439622Y610483D01*
X439088D01*
G01X450635Y607973D02*
X437635D01*
G01D02*
Y622973D01*
G01X433877Y609626D02*
X434090Y609418D01*
X434330Y609293D01*
X434544D01*
X434757Y609418D01*
X434917Y609626D01*
X434997Y609918D01*
X434944Y610210D01*
X434810Y610460D01*
X434570Y610626D01*
X434250Y610710D01*
X434064Y610876D01*
X433984Y611168D01*
X434037Y611460D01*
X434170Y611668D01*
X434357Y611793D01*
X434544D01*
X434730Y611710D01*
X434890Y611501D01*
G01X436815Y622973D02*
Y607973D01*
G01X438600Y639200D02*
Y624500D01*
G01X441345Y623662D02*
X435984D01*
Y623363D01*
G01X443807Y627520D02*
X440607D01*
G01X443807Y633720D02*
Y627520D01*
G01X440607D02*
Y633720D01*
G01X437781Y637977D02*
Y624977D01*
G01X443070Y619860D02*
X443283Y619652D01*
X443523Y619527D01*
X443737D01*
X443950Y619652D01*
X444110Y619860D01*
X444190Y620152D01*
X444137Y620444D01*
X444003Y620694D01*
X443763Y620860D01*
X443443Y620944D01*
X443257Y621110D01*
X443177Y621402D01*
X443230Y621694D01*
X443363Y621902D01*
X443550Y622027D01*
X443737D01*
X443923Y621944D01*
X444083Y621735D01*
G01X437635Y622973D02*
X450635D01*
G01X445878Y623555D02*
X447670D01*
X448045Y623662D01*
X448295Y623875D01*
X448378Y624142D01*
X448295Y624409D01*
X448045Y624622D01*
X447670Y624729D01*
X445878D01*
G01X448378Y626342D02*
X445878D01*
X446378Y626022D01*
G01X448378D02*
Y626662D01*
G01X445878Y628542D02*
X445961Y628329D01*
X446170Y628169D01*
X446420Y628062D01*
X446753Y627982D01*
X447128Y627955D01*
X447503Y627982D01*
X447836Y628062D01*
X448086Y628169D01*
X448295Y628329D01*
X448378Y628542D01*
X448295Y628755D01*
X448086Y628915D01*
X447836Y629022D01*
X447503Y629102D01*
X447128Y629129D01*
X446753Y629102D01*
X446420Y629022D01*
X446170Y628915D01*
X445961Y628755D01*
X445878Y628542D01*
G01X448378Y630742D02*
X448336Y630929D01*
X448211Y631142D01*
X448003Y631275D01*
X447711Y631329D01*
X447420Y631275D01*
X447170Y631115D01*
X447045Y630875D01*
Y630609D01*
X446961Y630449D01*
X446753Y630315D01*
X446461Y630262D01*
X446170Y630342D01*
X445961Y630529D01*
X445878Y630742D01*
X445961Y630955D01*
X446170Y631142D01*
X446461Y631222D01*
X446753Y631169D01*
X446961Y631035D01*
X447045Y630875D01*
Y630609D01*
X447170Y630369D01*
X447420Y630209D01*
X447711Y630155D01*
X448003Y630209D01*
X448211Y630342D01*
X448336Y630555D01*
X448378Y630742D01*
G01X435790Y639200D02*
X438600D01*
G01X435790Y665940D02*
Y639200D01*
G01X444930Y640310D02*
Y723430D01*
G01X436550Y640310D02*
X444930D01*
G01X436550Y688830D02*
Y640310D01*
G01X446190Y632600D02*
Y632650D01*
G01X444480Y632600D02*
X446190D01*
G01X447237Y632157D02*
Y634657D01*
X447903D01*
X448117Y634532D01*
X448250Y634365D01*
X448303Y634032D01*
X448250Y633699D01*
X448090Y633490D01*
X447903Y633365D01*
X447237D01*
G01X447903D02*
X448303Y632157D01*
G01X449970D02*
Y634657D01*
X449650Y634157D01*
G01Y632157D02*
X450290D01*
G01X451663Y634240D02*
X451823Y634490D01*
X452010Y634615D01*
X452223Y634657D01*
X452490Y634574D01*
X452677Y634365D01*
X452730Y634115D01*
X452703Y633865D01*
X452597Y633657D01*
X452063Y633240D01*
X451823Y632949D01*
X451663Y632532D01*
X451610Y632157D01*
X452730D01*
G01X454370D02*
X454557Y632199D01*
X454770Y632324D01*
X454903Y632532D01*
X454957Y632824D01*
X454903Y633115D01*
X454743Y633365D01*
X454503Y633490D01*
X454237D01*
X454077Y633574D01*
X453943Y633782D01*
X453890Y634074D01*
X453970Y634365D01*
X454157Y634574D01*
X454370Y634657D01*
X454583Y634574D01*
X454770Y634365D01*
X454850Y634074D01*
X454797Y633782D01*
X454663Y633574D01*
X454503Y633490D01*
X454237D01*
X453997Y633365D01*
X453837Y633115D01*
X453783Y632824D01*
X453837Y632532D01*
X453970Y632324D01*
X454183Y632199D01*
X454370Y632157D01*
G01X455983Y632657D02*
X456143Y632365D01*
X456357Y632199D01*
X456597Y632157D01*
X456810Y632199D01*
X457023Y632407D01*
X457157Y632657D01*
X457183Y632907D01*
X457130Y633199D01*
X456943Y633407D01*
X456757Y633490D01*
X456517D01*
G01X456757D02*
X456917Y633615D01*
X457050Y633824D01*
X457103Y634074D01*
X457050Y634324D01*
X456917Y634532D01*
X456677Y634657D01*
X456437Y634615D01*
X456197Y634449D01*
G01X440607Y633720D02*
X443807D01*
G01X444317Y641243D02*
X438117D01*
G01X444317Y644443D02*
Y641243D01*
G01X438117D02*
Y644443D01*
G01X439855Y635443D02*
X440068Y635235D01*
X440308Y635110D01*
X440522D01*
X440735Y635235D01*
X440895Y635443D01*
X440975Y635735D01*
X440922Y636027D01*
X440788Y636277D01*
X440548Y636443D01*
X440228Y636527D01*
X440042Y636693D01*
X439962Y636985D01*
X440015Y637277D01*
X440148Y637485D01*
X440335Y637610D01*
X440522D01*
X440708Y637527D01*
X440868Y637318D01*
G01X434940Y664756D02*
Y648556D01*
G01X437338Y653995D02*
Y657195D01*
G01X443538Y653995D02*
X437338D01*
G01X443538Y657195D02*
Y653995D01*
G01X437338Y657195D02*
X443538D01*
G01Y653195D02*
Y649995D01*
G01X437338Y653195D02*
X443538D01*
G01X437338Y649995D02*
Y653195D01*
G01X443538Y649995D02*
X437338D01*
G01X438117Y644443D02*
X444317D01*
G01X444311Y645271D02*
X438111D01*
G01X444311Y648471D02*
Y645271D01*
G01X438111Y648471D02*
X444311D01*
G01X438111Y645271D02*
Y648471D01*
G01X443540Y669228D02*
Y666028D01*
G01X437340Y669228D02*
X443540D01*
G01X437340Y666028D02*
Y669228D01*
G01X443540Y666028D02*
X437340D01*
G01X443540Y673228D02*
Y670028D01*
G01X437340Y673228D02*
X443540D01*
G01X437340Y670028D02*
Y673228D01*
G01X443540Y670028D02*
X437340D01*
G01X443540Y677228D02*
Y674028D01*
G01X437340D02*
Y677228D01*
G01X443540Y674028D02*
X437340D01*
G01X443540Y681228D02*
Y678028D01*
G01X437340Y681228D02*
X443540D01*
G01X437340Y678028D02*
Y681228D01*
G01X443540Y678028D02*
X437340D01*
G01Y677228D02*
X443540D01*
G01X433273Y690277D02*
Y693377D01*
X434232D01*
X434538Y693222D01*
X434730Y693015D01*
X434807Y692602D01*
X434730Y692189D01*
X434500Y691930D01*
X434232Y691775D01*
X433273D01*
G01X434232D02*
X434807Y690277D01*
G01X436412Y691569D02*
X436680Y691930D01*
X436910Y692137D01*
X437217Y692240D01*
X437485Y692137D01*
X437677Y691930D01*
X437830Y691620D01*
X437868Y691259D01*
X437830Y690949D01*
X437677Y690639D01*
X437447Y690380D01*
X437178Y690277D01*
X436872Y690380D01*
X436603Y690690D01*
X436450Y691155D01*
X436412Y691672D01*
X436488Y692344D01*
X436603Y692705D01*
X436795Y693067D01*
X437063Y693325D01*
X437332Y693377D01*
X437600Y693274D01*
X437792Y693015D01*
G01X440240Y690277D02*
X440508Y690329D01*
X440815Y690484D01*
X441007Y690742D01*
X441083Y691104D01*
X441007Y691465D01*
X440777Y691775D01*
X440432Y691930D01*
X440048D01*
X439818Y692034D01*
X439627Y692292D01*
X439550Y692654D01*
X439665Y693015D01*
X439933Y693274D01*
X440240Y693377D01*
X440547Y693274D01*
X440815Y693015D01*
X440930Y692654D01*
X440853Y692292D01*
X440662Y692034D01*
X440432Y691930D01*
X440048D01*
X439703Y691775D01*
X439473Y691465D01*
X439397Y691104D01*
X439473Y690742D01*
X439665Y690484D01*
X439972Y690329D01*
X440240Y690277D01*
G01X442497Y690897D02*
X442727Y690535D01*
X443033Y690329D01*
X443378Y690277D01*
X443685Y690329D01*
X443992Y690587D01*
X444183Y690897D01*
X444222Y691207D01*
X444145Y691569D01*
X443877Y691827D01*
X443608Y691930D01*
X443263D01*
G01X443608D02*
X443838Y692085D01*
X444030Y692344D01*
X444107Y692654D01*
X444030Y692964D01*
X443838Y693222D01*
X443493Y693377D01*
X443148Y693325D01*
X442803Y693119D01*
G01X445240Y700956D02*
Y711356D01*
G01X449640Y700956D02*
X445240D01*
G01X449640Y700356D02*
X445240D01*
G01Y699756D02*
X449640D01*
G01Y699156D02*
X445240D01*
G01D02*
Y700956D01*
G01X433103Y707447D02*
Y710547D01*
X434062D01*
X434368Y710392D01*
X434560Y710185D01*
X434637Y709772D01*
X434560Y709359D01*
X434330Y709100D01*
X434062Y708945D01*
X433103D01*
G01X434062D02*
X434637Y707447D01*
G01X436242Y708739D02*
X436510Y709100D01*
X436740Y709307D01*
X437047Y709410D01*
X437315Y709307D01*
X437507Y709100D01*
X437660Y708790D01*
X437698Y708429D01*
X437660Y708119D01*
X437507Y707809D01*
X437277Y707550D01*
X437008Y707447D01*
X436702Y707550D01*
X436433Y707860D01*
X436280Y708325D01*
X436242Y708842D01*
X436318Y709514D01*
X436433Y709875D01*
X436625Y710237D01*
X436893Y710495D01*
X437162Y710547D01*
X437430Y710444D01*
X437622Y710185D01*
G01X439342Y708739D02*
X439610Y709100D01*
X439840Y709307D01*
X440147Y709410D01*
X440415Y709307D01*
X440607Y709100D01*
X440760Y708790D01*
X440798Y708429D01*
X440760Y708119D01*
X440607Y707809D01*
X440377Y707550D01*
X440108Y707447D01*
X439802Y707550D01*
X439533Y707860D01*
X439380Y708325D01*
X439342Y708842D01*
X439418Y709514D01*
X439533Y709875D01*
X439725Y710237D01*
X439993Y710495D01*
X440262Y710547D01*
X440530Y710444D01*
X440722Y710185D01*
G01X443093Y707447D02*
X443170Y708119D01*
X443285Y708687D01*
X443438Y709204D01*
X443630Y709772D01*
X443937Y710547D01*
X442403D01*
G01X433273Y703437D02*
Y706537D01*
X434232D01*
X434538Y706382D01*
X434730Y706175D01*
X434807Y705762D01*
X434730Y705349D01*
X434500Y705090D01*
X434232Y704935D01*
X433273D01*
G01X434232D02*
X434807Y703437D01*
G01X436412Y704729D02*
X436680Y705090D01*
X436910Y705297D01*
X437217Y705400D01*
X437485Y705297D01*
X437677Y705090D01*
X437830Y704780D01*
X437868Y704419D01*
X437830Y704109D01*
X437677Y703799D01*
X437447Y703540D01*
X437178Y703437D01*
X436872Y703540D01*
X436603Y703850D01*
X436450Y704315D01*
X436412Y704832D01*
X436488Y705504D01*
X436603Y705865D01*
X436795Y706227D01*
X437063Y706485D01*
X437332Y706537D01*
X437600Y706434D01*
X437792Y706175D01*
G01X440163Y703437D02*
X440240Y704109D01*
X440355Y704677D01*
X440508Y705194D01*
X440700Y705762D01*
X441007Y706537D01*
X439473D01*
G01X442497Y704057D02*
X442727Y703695D01*
X443033Y703489D01*
X443378Y703437D01*
X443685Y703489D01*
X443992Y703747D01*
X444183Y704057D01*
X444222Y704367D01*
X444145Y704729D01*
X443877Y704987D01*
X443608Y705090D01*
X443263D01*
G01X443608D02*
X443838Y705245D01*
X444030Y705504D01*
X444107Y705814D01*
X444030Y706124D01*
X443838Y706382D01*
X443493Y706537D01*
X443148Y706485D01*
X442803Y706279D01*
G01X433273Y698647D02*
Y701747D01*
X434232D01*
X434538Y701592D01*
X434730Y701385D01*
X434807Y700972D01*
X434730Y700559D01*
X434500Y700300D01*
X434232Y700145D01*
X433273D01*
G01X434232D02*
X434807Y698647D01*
G01X436412Y699939D02*
X436680Y700300D01*
X436910Y700507D01*
X437217Y700610D01*
X437485Y700507D01*
X437677Y700300D01*
X437830Y699990D01*
X437868Y699629D01*
X437830Y699319D01*
X437677Y699009D01*
X437447Y698750D01*
X437178Y698647D01*
X436872Y698750D01*
X436603Y699060D01*
X436450Y699525D01*
X436412Y700042D01*
X436488Y700714D01*
X436603Y701075D01*
X436795Y701437D01*
X437063Y701695D01*
X437332Y701747D01*
X437600Y701644D01*
X437792Y701385D01*
G01X440163Y698647D02*
X440240Y699319D01*
X440355Y699887D01*
X440508Y700404D01*
X440700Y700972D01*
X441007Y701747D01*
X439473D01*
G01X443263Y698647D02*
X443340Y699319D01*
X443455Y699887D01*
X443608Y700404D01*
X443800Y700972D01*
X444107Y701747D01*
X442573D01*
G01X433363Y694637D02*
Y697737D01*
X434322D01*
X434628Y697582D01*
X434820Y697375D01*
X434897Y696962D01*
X434820Y696549D01*
X434590Y696290D01*
X434322Y696135D01*
X433363D01*
G01X434322D02*
X434897Y694637D01*
G01X436502Y695929D02*
X436770Y696290D01*
X437000Y696497D01*
X437307Y696600D01*
X437575Y696497D01*
X437767Y696290D01*
X437920Y695980D01*
X437958Y695619D01*
X437920Y695309D01*
X437767Y694999D01*
X437537Y694740D01*
X437268Y694637D01*
X436962Y694740D01*
X436693Y695050D01*
X436540Y695515D01*
X436502Y696032D01*
X436578Y696704D01*
X436693Y697065D01*
X436885Y697427D01*
X437153Y697685D01*
X437422Y697737D01*
X437690Y697634D01*
X437882Y697375D01*
G01X440330Y694637D02*
X440598Y694689D01*
X440905Y694844D01*
X441097Y695102D01*
X441173Y695464D01*
X441097Y695825D01*
X440867Y696135D01*
X440522Y696290D01*
X440138D01*
X439908Y696394D01*
X439717Y696652D01*
X439640Y697014D01*
X439755Y697375D01*
X440023Y697634D01*
X440330Y697737D01*
X440637Y697634D01*
X440905Y697375D01*
X441020Y697014D01*
X440943Y696652D01*
X440752Y696394D01*
X440522Y696290D01*
X440138D01*
X439793Y696135D01*
X439563Y695825D01*
X439487Y695464D01*
X439563Y695102D01*
X439755Y694844D01*
X440062Y694689D01*
X440330Y694637D01*
G01X443430D02*
Y697737D01*
X442970Y697117D01*
G01Y694637D02*
X443890D01*
G01X445762Y714939D02*
X446142Y714522D01*
X446585Y714272D01*
X447155Y714189D01*
X447725Y714356D01*
X448168Y714689D01*
X448485Y715272D01*
X448548Y715939D01*
X448422Y716606D01*
X448105Y717022D01*
X447662Y717356D01*
X447218Y717439D01*
X446775Y717356D01*
X446205Y717022D01*
X446395Y719189D01*
X448105D01*
G01X445240Y711356D02*
X449640D01*
G01X432673Y719077D02*
Y722177D01*
X433632D01*
X433938Y722022D01*
X434130Y721815D01*
X434207Y721402D01*
X434130Y720989D01*
X433900Y720730D01*
X433632Y720575D01*
X432673D01*
G01X433632D02*
X434207Y719077D01*
G01X435812Y720369D02*
X436080Y720730D01*
X436310Y720937D01*
X436617Y721040D01*
X436885Y720937D01*
X437077Y720730D01*
X437230Y720420D01*
X437268Y720059D01*
X437230Y719749D01*
X437077Y719439D01*
X436847Y719180D01*
X436578Y719077D01*
X436272Y719180D01*
X436003Y719490D01*
X435850Y719955D01*
X435812Y720472D01*
X435888Y721144D01*
X436003Y721505D01*
X436195Y721867D01*
X436463Y722125D01*
X436732Y722177D01*
X437000Y722074D01*
X437192Y721815D01*
G01X438912Y720369D02*
X439180Y720730D01*
X439410Y720937D01*
X439717Y721040D01*
X439985Y720937D01*
X440177Y720730D01*
X440330Y720420D01*
X440368Y720059D01*
X440330Y719749D01*
X440177Y719439D01*
X439947Y719180D01*
X439678Y719077D01*
X439372Y719180D01*
X439103Y719490D01*
X438950Y719955D01*
X438912Y720472D01*
X438988Y721144D01*
X439103Y721505D01*
X439295Y721867D01*
X439563Y722125D01*
X439832Y722177D01*
X440100Y722074D01*
X440292Y721815D01*
G01X441897Y719697D02*
X442127Y719335D01*
X442433Y719129D01*
X442778Y719077D01*
X443085Y719129D01*
X443392Y719387D01*
X443583Y719697D01*
X443622Y720007D01*
X443545Y720369D01*
X443277Y720627D01*
X443008Y720730D01*
X442663D01*
G01X443008D02*
X443238Y720885D01*
X443430Y721144D01*
X443507Y721454D01*
X443430Y721764D01*
X443238Y722022D01*
X442893Y722177D01*
X442548Y722125D01*
X442203Y721919D01*
G01X432853Y711467D02*
Y714567D01*
X433812D01*
X434118Y714412D01*
X434310Y714205D01*
X434387Y713792D01*
X434310Y713379D01*
X434080Y713120D01*
X433812Y712965D01*
X432853D01*
G01X433812D02*
X434387Y711467D01*
G01X435992Y712759D02*
X436260Y713120D01*
X436490Y713327D01*
X436797Y713430D01*
X437065Y713327D01*
X437257Y713120D01*
X437410Y712810D01*
X437448Y712449D01*
X437410Y712139D01*
X437257Y711829D01*
X437027Y711570D01*
X436758Y711467D01*
X436452Y711570D01*
X436183Y711880D01*
X436030Y712345D01*
X435992Y712862D01*
X436068Y713534D01*
X436183Y713895D01*
X436375Y714257D01*
X436643Y714515D01*
X436912Y714567D01*
X437180Y714464D01*
X437372Y714205D01*
G01X439092Y712759D02*
X439360Y713120D01*
X439590Y713327D01*
X439897Y713430D01*
X440165Y713327D01*
X440357Y713120D01*
X440510Y712810D01*
X440548Y712449D01*
X440510Y712139D01*
X440357Y711829D01*
X440127Y711570D01*
X439858Y711467D01*
X439552Y711570D01*
X439283Y711880D01*
X439130Y712345D01*
X439092Y712862D01*
X439168Y713534D01*
X439283Y713895D01*
X439475Y714257D01*
X439743Y714515D01*
X440012Y714567D01*
X440280Y714464D01*
X440472Y714205D01*
G01X442192Y712759D02*
X442460Y713120D01*
X442690Y713327D01*
X442997Y713430D01*
X443265Y713327D01*
X443457Y713120D01*
X443610Y712810D01*
X443648Y712449D01*
X443610Y712139D01*
X443457Y711829D01*
X443227Y711570D01*
X442958Y711467D01*
X442652Y711570D01*
X442383Y711880D01*
X442230Y712345D01*
X442192Y712862D01*
X442268Y713534D01*
X442383Y713895D01*
X442575Y714257D01*
X442843Y714515D01*
X443112Y714567D01*
X443380Y714464D01*
X443572Y714205D01*
G01X432853Y715317D02*
Y718417D01*
X433812D01*
X434118Y718262D01*
X434310Y718055D01*
X434387Y717642D01*
X434310Y717229D01*
X434080Y716970D01*
X433812Y716815D01*
X432853D01*
G01X433812D02*
X434387Y715317D01*
G01X435992Y716609D02*
X436260Y716970D01*
X436490Y717177D01*
X436797Y717280D01*
X437065Y717177D01*
X437257Y716970D01*
X437410Y716660D01*
X437448Y716299D01*
X437410Y715989D01*
X437257Y715679D01*
X437027Y715420D01*
X436758Y715317D01*
X436452Y715420D01*
X436183Y715730D01*
X436030Y716195D01*
X435992Y716712D01*
X436068Y717384D01*
X436183Y717745D01*
X436375Y718107D01*
X436643Y718365D01*
X436912Y718417D01*
X437180Y718314D01*
X437372Y718055D01*
G01X439092Y716609D02*
X439360Y716970D01*
X439590Y717177D01*
X439897Y717280D01*
X440165Y717177D01*
X440357Y716970D01*
X440510Y716660D01*
X440548Y716299D01*
X440510Y715989D01*
X440357Y715679D01*
X440127Y715420D01*
X439858Y715317D01*
X439552Y715420D01*
X439283Y715730D01*
X439130Y716195D01*
X439092Y716712D01*
X439168Y717384D01*
X439283Y717745D01*
X439475Y718107D01*
X439743Y718365D01*
X440012Y718417D01*
X440280Y718314D01*
X440472Y718055D01*
G01X443380Y715317D02*
Y718417D01*
X441962Y716195D01*
X443878D01*
G01X444930Y723430D02*
X442450D01*
G01X445540Y737556D02*
X442340D01*
G01X445540Y743756D02*
Y737556D01*
G01X442340D02*
Y743756D01*
G01X449940Y729156D02*
X446940D01*
G01X450040Y726056D02*
X446840D01*
G01Y732256D02*
X450040D01*
G01X446840Y726056D02*
Y732256D01*
G01X432540Y743756D02*
Y737556D01*
G01X441540D02*
X438340D01*
G01X441540Y743756D02*
Y737556D01*
G01X438340D02*
Y743756D01*
G01X437040Y737556D02*
X433840D01*
G01X437040Y743756D02*
Y737556D01*
G01X433840D02*
Y743756D01*
G01X446840Y737556D02*
Y743756D01*
G01X450040Y737556D02*
X446840D01*
G01X433840Y732256D02*
X437040D01*
G01X433840Y726056D02*
Y732256D01*
G01X437040Y726056D02*
X433840D01*
G01X437040Y732256D02*
Y726056D01*
G01X432540Y732256D02*
Y726056D01*
G01X438340Y732256D02*
X441540D01*
G01X438340Y726056D02*
Y732256D01*
G01X441540Y726056D02*
X438340D01*
G01X441540Y732256D02*
Y726056D01*
G01X445440Y740656D02*
X442440D01*
G01X442340Y743756D02*
X445540D01*
G01X446501Y749777D02*
X446346Y749547D01*
X446243Y749279D01*
Y748972D01*
X446398Y748627D01*
X446656Y748359D01*
X446966Y748167D01*
X447483Y748014D01*
X447948Y747976D01*
X448413Y748052D01*
X448723Y748167D01*
X449033Y748397D01*
X449240Y748666D01*
X449343Y748934D01*
Y749202D01*
X449240Y749471D01*
X449085Y749701D01*
X448878Y749892D01*
G01X449343Y751957D02*
X448671Y752034D01*
X448103Y752149D01*
X447586Y752302D01*
X447018Y752494D01*
X446243Y752801D01*
Y751267D01*
G01X448051Y754406D02*
X447690Y754674D01*
X447483Y754904D01*
X447380Y755211D01*
X447483Y755479D01*
X447690Y755671D01*
X448000Y755824D01*
X448361Y755862D01*
X448671Y755824D01*
X448981Y755671D01*
X449240Y755441D01*
X449343Y755172D01*
X449240Y754866D01*
X448930Y754597D01*
X448465Y754444D01*
X447948Y754406D01*
X447276Y754482D01*
X446915Y754597D01*
X446553Y754789D01*
X446295Y755057D01*
X446243Y755326D01*
X446346Y755594D01*
X446605Y755786D01*
G01X446243Y758234D02*
X446346Y757927D01*
X446605Y757697D01*
X446915Y757544D01*
X447328Y757429D01*
X447793Y757391D01*
X448258Y757429D01*
X448671Y757544D01*
X448981Y757697D01*
X449240Y757927D01*
X449343Y758234D01*
X449240Y758541D01*
X448981Y758771D01*
X448671Y758924D01*
X448258Y759039D01*
X447793Y759077D01*
X447328Y759039D01*
X446915Y758924D01*
X446605Y758771D01*
X446346Y758541D01*
X446243Y758234D01*
G01X441440Y740656D02*
X438440D01*
G01X438340Y743756D02*
X441540D01*
G01X436940Y740656D02*
X433940D01*
G01X433840Y743756D02*
X437040D01*
G01X446840D02*
X450040D01*
G01X439687Y748311D02*
X436587D01*
Y749270D01*
X436742Y749576D01*
X436949Y749768D01*
X437362Y749845D01*
X437775Y749768D01*
X438034Y749538D01*
X438189Y749270D01*
Y748311D01*
G01Y749270D02*
X439687Y749845D01*
G01Y752178D02*
X439635Y752446D01*
X439480Y752753D01*
X439222Y752945D01*
X438860Y753021D01*
X438499Y752945D01*
X438189Y752715D01*
X438034Y752370D01*
Y751986D01*
X437930Y751756D01*
X437672Y751565D01*
X437310Y751488D01*
X436949Y751603D01*
X436690Y751871D01*
X436587Y752178D01*
X436690Y752485D01*
X436949Y752753D01*
X437310Y752868D01*
X437672Y752791D01*
X437930Y752600D01*
X438034Y752370D01*
Y751986D01*
X438189Y751641D01*
X438499Y751411D01*
X438860Y751335D01*
X439222Y751411D01*
X439480Y751603D01*
X439635Y751910D01*
X439687Y752178D01*
G01Y755278D02*
X439635Y755546D01*
X439480Y755853D01*
X439222Y756045D01*
X438860Y756121D01*
X438499Y756045D01*
X438189Y755815D01*
X438034Y755470D01*
Y755086D01*
X437930Y754856D01*
X437672Y754665D01*
X437310Y754588D01*
X436949Y754703D01*
X436690Y754971D01*
X436587Y755278D01*
X436690Y755585D01*
X436949Y755853D01*
X437310Y755968D01*
X437672Y755891D01*
X437930Y755700D01*
X438034Y755470D01*
Y755086D01*
X438189Y754741D01*
X438499Y754511D01*
X438860Y754435D01*
X439222Y754511D01*
X439480Y754703D01*
X439635Y755010D01*
X439687Y755278D01*
G01Y758301D02*
X439015Y758378D01*
X438447Y758493D01*
X437930Y758646D01*
X437362Y758838D01*
X436587Y759145D01*
Y757611D01*
G01X435187Y748311D02*
X432087D01*
Y749270D01*
X432242Y749576D01*
X432449Y749768D01*
X432862Y749845D01*
X433275Y749768D01*
X433534Y749538D01*
X433689Y749270D01*
Y748311D01*
G01Y749270D02*
X435187Y749845D01*
G01Y752178D02*
X435135Y752446D01*
X434980Y752753D01*
X434722Y752945D01*
X434360Y753021D01*
X433999Y752945D01*
X433689Y752715D01*
X433534Y752370D01*
Y751986D01*
X433430Y751756D01*
X433172Y751565D01*
X432810Y751488D01*
X432449Y751603D01*
X432190Y751871D01*
X432087Y752178D01*
X432190Y752485D01*
X432449Y752753D01*
X432810Y752868D01*
X433172Y752791D01*
X433430Y752600D01*
X433534Y752370D01*
Y751986D01*
X433689Y751641D01*
X433999Y751411D01*
X434360Y751335D01*
X434722Y751411D01*
X434980Y751603D01*
X435135Y751910D01*
X435187Y752178D01*
G01X434825Y754626D02*
X435084Y754895D01*
X435187Y755201D01*
X435084Y755508D01*
X434774Y755776D01*
X434309Y755968D01*
X433844Y756045D01*
X433275D01*
X432810Y755968D01*
X432397Y755776D01*
X432190Y755546D01*
X432087Y755278D01*
X432190Y754971D01*
X432397Y754741D01*
X432707Y754588D01*
X433120Y754511D01*
X433482Y754588D01*
X433844Y754780D01*
X434050Y755010D01*
X434102Y755278D01*
X433999Y755585D01*
X433740Y755815D01*
X433275Y756045D01*
G01X432087Y758378D02*
X432190Y758071D01*
X432449Y757841D01*
X432759Y757688D01*
X433172Y757573D01*
X433637Y757535D01*
X434102Y757573D01*
X434515Y757688D01*
X434825Y757841D01*
X435084Y758071D01*
X435187Y758378D01*
X435084Y758685D01*
X434825Y758915D01*
X434515Y759068D01*
X434102Y759183D01*
X433637Y759221D01*
X433172Y759183D01*
X432759Y759068D01*
X432449Y758915D01*
X432190Y758685D01*
X432087Y758378D01*
G01X444187Y748311D02*
X441087D01*
Y749270D01*
X441242Y749576D01*
X441449Y749768D01*
X441862Y749845D01*
X442275Y749768D01*
X442534Y749538D01*
X442689Y749270D01*
Y748311D01*
G01Y749270D02*
X444187Y749845D01*
G01Y752178D02*
X444135Y752446D01*
X443980Y752753D01*
X443722Y752945D01*
X443360Y753021D01*
X442999Y752945D01*
X442689Y752715D01*
X442534Y752370D01*
Y751986D01*
X442430Y751756D01*
X442172Y751565D01*
X441810Y751488D01*
X441449Y751603D01*
X441190Y751871D01*
X441087Y752178D01*
X441190Y752485D01*
X441449Y752753D01*
X441810Y752868D01*
X442172Y752791D01*
X442430Y752600D01*
X442534Y752370D01*
Y751986D01*
X442689Y751641D01*
X442999Y751411D01*
X443360Y751335D01*
X443722Y751411D01*
X443980Y751603D01*
X444135Y751910D01*
X444187Y752178D01*
G01Y755278D02*
X444135Y755546D01*
X443980Y755853D01*
X443722Y756045D01*
X443360Y756121D01*
X442999Y756045D01*
X442689Y755815D01*
X442534Y755470D01*
Y755086D01*
X442430Y754856D01*
X442172Y754665D01*
X441810Y754588D01*
X441449Y754703D01*
X441190Y754971D01*
X441087Y755278D01*
X441190Y755585D01*
X441449Y755853D01*
X441810Y755968D01*
X442172Y755891D01*
X442430Y755700D01*
X442534Y755470D01*
Y755086D01*
X442689Y754741D01*
X442999Y754511D01*
X443360Y754435D01*
X443722Y754511D01*
X443980Y754703D01*
X444135Y755010D01*
X444187Y755278D01*
G01Y758838D02*
X441087D01*
X443309Y757420D01*
Y759336D01*
G01X441006Y762932D02*
X440851Y762702D01*
X440748Y762434D01*
Y762127D01*
X440903Y761782D01*
X441161Y761514D01*
X441471Y761322D01*
X441988Y761169D01*
X442453Y761131D01*
X442918Y761207D01*
X443228Y761322D01*
X443538Y761552D01*
X443745Y761821D01*
X443848Y762089D01*
Y762357D01*
X443745Y762626D01*
X443590Y762856D01*
X443383Y763047D01*
G01X443848Y765112D02*
X443176Y765189D01*
X442608Y765304D01*
X442091Y765457D01*
X441523Y765649D01*
X440748Y765956D01*
Y764422D01*
G01X442556Y767561D02*
X442195Y767829D01*
X441988Y768059D01*
X441885Y768366D01*
X441988Y768634D01*
X442195Y768826D01*
X442505Y768979D01*
X442866Y769017D01*
X443176Y768979D01*
X443486Y768826D01*
X443745Y768596D01*
X443848Y768327D01*
X443745Y768021D01*
X443435Y767752D01*
X442970Y767599D01*
X442453Y767561D01*
X441781Y767637D01*
X441420Y767752D01*
X441058Y767944D01*
X440800Y768212D01*
X440748Y768481D01*
X440851Y768749D01*
X441110Y768941D01*
G01X443228Y770546D02*
X443590Y770776D01*
X443796Y771082D01*
X443848Y771427D01*
X443796Y771734D01*
X443538Y772041D01*
X443228Y772232D01*
X442918Y772271D01*
X442556Y772194D01*
X442298Y771926D01*
X442195Y771657D01*
Y771312D01*
G01Y771657D02*
X442040Y771887D01*
X441781Y772079D01*
X441471Y772156D01*
X441161Y772079D01*
X440903Y771887D01*
X440748Y771542D01*
X440800Y771197D01*
X441006Y770852D01*
G01X432611Y762932D02*
X432456Y762702D01*
X432353Y762434D01*
Y762127D01*
X432508Y761782D01*
X432766Y761514D01*
X433076Y761322D01*
X433593Y761169D01*
X434058Y761131D01*
X434523Y761207D01*
X434833Y761322D01*
X435143Y761552D01*
X435350Y761821D01*
X435453Y762089D01*
Y762357D01*
X435350Y762626D01*
X435195Y762856D01*
X434988Y763047D01*
G01X434161Y764461D02*
X433800Y764729D01*
X433593Y764959D01*
X433490Y765266D01*
X433593Y765534D01*
X433800Y765726D01*
X434110Y765879D01*
X434471Y765917D01*
X434781Y765879D01*
X435091Y765726D01*
X435350Y765496D01*
X435453Y765227D01*
X435350Y764921D01*
X435040Y764652D01*
X434575Y764499D01*
X434058Y764461D01*
X433386Y764537D01*
X433025Y764652D01*
X432663Y764844D01*
X432405Y765112D01*
X432353Y765381D01*
X432456Y765649D01*
X432715Y765841D01*
G01X434988Y767446D02*
X435246Y767676D01*
X435401Y767944D01*
X435453Y768289D01*
X435350Y768634D01*
X435143Y768902D01*
X434781Y769094D01*
X434368Y769132D01*
X433955Y769056D01*
X433696Y768864D01*
X433490Y768596D01*
X433438Y768327D01*
X433490Y768059D01*
X433696Y767714D01*
X432353Y767829D01*
Y768864D01*
G01X434833Y770546D02*
X435195Y770776D01*
X435401Y771082D01*
X435453Y771427D01*
X435401Y771734D01*
X435143Y772041D01*
X434833Y772232D01*
X434523Y772271D01*
X434161Y772194D01*
X433903Y771926D01*
X433800Y771657D01*
Y771312D01*
G01Y771657D02*
X433645Y771887D01*
X433386Y772079D01*
X433076Y772156D01*
X432766Y772079D01*
X432508Y771887D01*
X432353Y771542D01*
X432405Y771197D01*
X432611Y770852D01*
G01X444861Y762932D02*
X444706Y762702D01*
X444603Y762434D01*
Y762127D01*
X444758Y761782D01*
X445016Y761514D01*
X445326Y761322D01*
X445843Y761169D01*
X446308Y761131D01*
X446773Y761207D01*
X447083Y761322D01*
X447393Y761552D01*
X447600Y761821D01*
X447703Y762089D01*
Y762357D01*
X447600Y762626D01*
X447445Y762856D01*
X447238Y763047D01*
G01X446411Y764461D02*
X446050Y764729D01*
X445843Y764959D01*
X445740Y765266D01*
X445843Y765534D01*
X446050Y765726D01*
X446360Y765879D01*
X446721Y765917D01*
X447031Y765879D01*
X447341Y765726D01*
X447600Y765496D01*
X447703Y765227D01*
X447600Y764921D01*
X447290Y764652D01*
X446825Y764499D01*
X446308Y764461D01*
X445636Y764537D01*
X445275Y764652D01*
X444913Y764844D01*
X444655Y765112D01*
X444603Y765381D01*
X444706Y765649D01*
X444965Y765841D01*
G01X447703Y768749D02*
X444603D01*
X446825Y767331D01*
Y769247D01*
G01X447703Y771312D02*
X447031Y771389D01*
X446463Y771504D01*
X445946Y771657D01*
X445378Y771849D01*
X444603Y772156D01*
Y770622D01*
G01X437111Y762932D02*
X436956Y762702D01*
X436853Y762434D01*
Y762127D01*
X437008Y761782D01*
X437266Y761514D01*
X437576Y761322D01*
X438093Y761169D01*
X438558Y761131D01*
X439023Y761207D01*
X439333Y761322D01*
X439643Y761552D01*
X439850Y761821D01*
X439953Y762089D01*
Y762357D01*
X439850Y762626D01*
X439695Y762856D01*
X439488Y763047D01*
G01X438661Y764461D02*
X438300Y764729D01*
X438093Y764959D01*
X437990Y765266D01*
X438093Y765534D01*
X438300Y765726D01*
X438610Y765879D01*
X438971Y765917D01*
X439281Y765879D01*
X439591Y765726D01*
X439850Y765496D01*
X439953Y765227D01*
X439850Y764921D01*
X439540Y764652D01*
X439075Y764499D01*
X438558Y764461D01*
X437886Y764537D01*
X437525Y764652D01*
X437163Y764844D01*
X436905Y765112D01*
X436853Y765381D01*
X436956Y765649D01*
X437215Y765841D01*
G01X439488Y767446D02*
X439746Y767676D01*
X439901Y767944D01*
X439953Y768289D01*
X439850Y768634D01*
X439643Y768902D01*
X439281Y769094D01*
X438868Y769132D01*
X438455Y769056D01*
X438196Y768864D01*
X437990Y768596D01*
X437938Y768327D01*
X437990Y768059D01*
X438196Y767714D01*
X436853Y767829D01*
Y768864D01*
G01Y771389D02*
X436956Y771082D01*
X437215Y770852D01*
X437525Y770699D01*
X437938Y770584D01*
X438403Y770546D01*
X438868Y770584D01*
X439281Y770699D01*
X439591Y770852D01*
X439850Y771082D01*
X439953Y771389D01*
X439850Y771696D01*
X439591Y771926D01*
X439281Y772079D01*
X438868Y772194D01*
X438403Y772232D01*
X437938Y772194D01*
X437525Y772079D01*
X437215Y771926D01*
X436956Y771696D01*
X436853Y771389D01*
G01X448911Y62262D02*
Y65362D01*
X449870D01*
X450176Y65207D01*
X450368Y65000D01*
X450445Y64587D01*
X450368Y64174D01*
X450138Y63915D01*
X449870Y63760D01*
X448911D01*
G01X449870D02*
X450445Y62262D01*
G01X452778D02*
Y65362D01*
X452318Y64742D01*
G01Y62262D02*
X453238D01*
G01X455150Y64845D02*
X455380Y65155D01*
X455648Y65310D01*
X455955Y65362D01*
X456338Y65259D01*
X456606Y65000D01*
X456683Y64690D01*
X456645Y64380D01*
X456491Y64122D01*
X455725Y63605D01*
X455380Y63244D01*
X455150Y62727D01*
X455073Y62262D01*
X456683D01*
G01X459438D02*
Y65362D01*
X458020Y63140D01*
X459936D01*
G01X461350Y64845D02*
X461580Y65155D01*
X461848Y65310D01*
X462155Y65362D01*
X462538Y65259D01*
X462806Y65000D01*
X462883Y64690D01*
X462845Y64380D01*
X462691Y64122D01*
X461925Y63605D01*
X461580Y63244D01*
X461350Y62727D01*
X461273Y62262D01*
X462883D01*
G01X466292Y73397D02*
X460092D01*
G01X463192Y76497D02*
Y73497D01*
G01X460092Y73397D02*
Y76597D01*
G01D02*
X466292D01*
G01X449082Y70165D02*
Y76365D01*
G01D02*
X452282D01*
G01D02*
Y70165D01*
G01D02*
X449082D01*
G01X452182Y73265D02*
X449182D01*
G01X447904Y76523D02*
Y70323D01*
G01X459257Y76374D02*
Y73174D01*
G01X453057Y76374D02*
X459257D01*
G01Y73174D02*
X453057D01*
G01D02*
Y76374D01*
G01X452908Y67594D02*
Y70794D01*
G01X459108Y67594D02*
X452908D01*
G01X459108Y70794D02*
Y67594D01*
G01X452908Y70794D02*
X459108D01*
G01X462331Y79696D02*
Y82196D01*
X462011Y81696D01*
G01Y79696D02*
X462651D01*
G01X464531Y82196D02*
X464318Y82113D01*
X464158Y81904D01*
X464051Y81654D01*
X463971Y81321D01*
X463944Y80946D01*
X463971Y80571D01*
X464051Y80238D01*
X464158Y79988D01*
X464318Y79779D01*
X464531Y79696D01*
X464744Y79779D01*
X464904Y79988D01*
X465011Y80238D01*
X465091Y80571D01*
X465118Y80946D01*
X465091Y81321D01*
X465011Y81654D01*
X464904Y81904D01*
X464744Y82113D01*
X464531Y82196D01*
G01X460661Y83816D02*
Y81418D01*
G01D02*
X459263D01*
G01X449263D02*
X447865D01*
G01D02*
Y83816D01*
G01X460661Y94214D02*
Y91816D01*
G01X447865D02*
Y94214D01*
G01X462574Y121590D02*
Y106590D01*
G01X455774D02*
Y121590D01*
G01X462574Y106590D02*
X455774D01*
G01X454801Y121665D02*
Y106665D01*
G01X448001D02*
Y121665D01*
G01X454801Y106665D02*
X448001D01*
G01X461070Y94965D02*
Y97465D01*
X460750Y96965D01*
G01Y94965D02*
X461390D01*
G01X459263Y94214D02*
X460661D01*
G01X447865D02*
X449263D01*
G01X469155Y97147D02*
X462955D01*
G01D02*
Y100347D01*
G01D02*
X469155D01*
G01X469151Y93143D02*
X462951D01*
G01D02*
Y96343D01*
G01D02*
X469151D01*
G01X463316Y104336D02*
Y101136D01*
G01D02*
X457116D01*
G01D02*
Y104336D01*
G01D02*
X463316D01*
G01X460702Y124092D02*
X460547Y123862D01*
X460444Y123594D01*
Y123287D01*
X460599Y122942D01*
X460857Y122674D01*
X461167Y122482D01*
X461684Y122329D01*
X462149Y122291D01*
X462614Y122367D01*
X462924Y122482D01*
X463234Y122712D01*
X463441Y122981D01*
X463544Y123249D01*
Y123517D01*
X463441Y123786D01*
X463286Y124016D01*
X463079Y124207D01*
G01X463544Y126349D02*
X463492Y126617D01*
X463337Y126924D01*
X463079Y127116D01*
X462717Y127192D01*
X462356Y127116D01*
X462046Y126886D01*
X461891Y126541D01*
Y126157D01*
X461787Y125927D01*
X461529Y125736D01*
X461167Y125659D01*
X460806Y125774D01*
X460547Y126042D01*
X460444Y126349D01*
X460547Y126656D01*
X460806Y126924D01*
X461167Y127039D01*
X461529Y126962D01*
X461787Y126771D01*
X461891Y126541D01*
Y126157D01*
X462046Y125812D01*
X462356Y125582D01*
X462717Y125506D01*
X463079Y125582D01*
X463337Y125774D01*
X463492Y126081D01*
X463544Y126349D01*
G01X463079Y128606D02*
X463337Y128836D01*
X463492Y129104D01*
X463544Y129449D01*
X463441Y129794D01*
X463234Y130062D01*
X462872Y130254D01*
X462459Y130292D01*
X462046Y130216D01*
X461787Y130024D01*
X461581Y129756D01*
X461529Y129487D01*
X461581Y129219D01*
X461787Y128874D01*
X460444Y128989D01*
Y130024D01*
G01X463544Y133009D02*
X460444D01*
X462666Y131591D01*
Y133507D01*
G01X455774Y121590D02*
X462574D01*
G01X455874Y114090D02*
X462474D01*
G01X453712Y124766D02*
X453557Y124536D01*
X453454Y124268D01*
Y123961D01*
X453609Y123616D01*
X453867Y123348D01*
X454177Y123156D01*
X454694Y123003D01*
X455159Y122965D01*
X455624Y123041D01*
X455934Y123156D01*
X456244Y123386D01*
X456451Y123655D01*
X456554Y123923D01*
Y124191D01*
X456451Y124460D01*
X456296Y124690D01*
X456089Y124881D01*
G01X456554Y127023D02*
X456502Y127291D01*
X456347Y127598D01*
X456089Y127790D01*
X455727Y127866D01*
X455366Y127790D01*
X455056Y127560D01*
X454901Y127215D01*
Y126831D01*
X454797Y126601D01*
X454539Y126410D01*
X454177Y126333D01*
X453816Y126448D01*
X453557Y126716D01*
X453454Y127023D01*
X453557Y127330D01*
X453816Y127598D01*
X454177Y127713D01*
X454539Y127636D01*
X454797Y127445D01*
X454901Y127215D01*
Y126831D01*
X455056Y126486D01*
X455366Y126256D01*
X455727Y126180D01*
X456089Y126256D01*
X456347Y126448D01*
X456502Y126755D01*
X456554Y127023D01*
G01X456089Y129280D02*
X456347Y129510D01*
X456502Y129778D01*
X456554Y130123D01*
X456451Y130468D01*
X456244Y130736D01*
X455882Y130928D01*
X455469Y130966D01*
X455056Y130890D01*
X454797Y130698D01*
X454591Y130430D01*
X454539Y130161D01*
X454591Y129893D01*
X454797Y129548D01*
X453454Y129663D01*
Y130698D01*
G01X456554Y133146D02*
X455882Y133223D01*
X455314Y133338D01*
X454797Y133491D01*
X454229Y133683D01*
X453454Y133990D01*
Y132456D01*
G01X448001Y121665D02*
X454801D01*
G01X448101Y114165D02*
X454701D01*
G01X451942Y148960D02*
X451635Y149012D01*
X451367Y149218D01*
X451137Y149528D01*
X450984Y149890D01*
X450907Y150303D01*
Y150717D01*
X450984Y151130D01*
X451137Y151492D01*
X451367Y151802D01*
X451635Y152008D01*
X451942Y152060D01*
X452249Y152008D01*
X452517Y151802D01*
X452747Y151492D01*
X452900Y151130D01*
X452977Y150717D01*
Y150303D01*
X452900Y149890D01*
X452747Y149528D01*
X452517Y149218D01*
X452249Y149012D01*
X451942Y148960D01*
G01X454237Y149373D02*
X454544Y149115D01*
X454889Y148960D01*
X455195D01*
X455502Y149115D01*
X455732Y149373D01*
X455847Y149735D01*
X455770Y150097D01*
X455579Y150407D01*
X455234Y150613D01*
X454774Y150717D01*
X454505Y150923D01*
X454390Y151285D01*
X454467Y151647D01*
X454659Y151905D01*
X454927Y152060D01*
X455195D01*
X455464Y151957D01*
X455694Y151698D01*
G01X458985Y151802D02*
X458755Y151957D01*
X458487Y152060D01*
X458180D01*
X457835Y151905D01*
X457567Y151647D01*
X457375Y151337D01*
X457222Y150820D01*
X457184Y150355D01*
X457260Y149890D01*
X457375Y149580D01*
X457605Y149270D01*
X457874Y149063D01*
X458142Y148960D01*
X458410D01*
X458679Y149063D01*
X458909Y149218D01*
X459100Y149425D01*
G01X461702Y148960D02*
Y152060D01*
X460284Y149838D01*
X462200D01*
G01X450515Y187144D02*
Y193344D01*
G01X453715Y187144D02*
X450515D01*
G01X453715Y193344D02*
Y187144D01*
G01X459794Y184905D02*
Y189505D01*
G01X460794Y184905D02*
Y189505D01*
G01X455194Y184705D02*
Y189705D01*
G01X465394Y184705D02*
X455194D01*
G01X451701Y186038D02*
Y182838D01*
G01X450515Y193344D02*
X453715D01*
G01X450615Y190244D02*
X453615D01*
G01X456567Y194056D02*
Y190956D01*
X458101D01*
G01X459706Y193539D02*
X459936Y193849D01*
X460204Y194004D01*
X460511Y194056D01*
X460894Y193953D01*
X461162Y193694D01*
X461239Y193384D01*
X461201Y193074D01*
X461047Y192816D01*
X460281Y192299D01*
X459936Y191938D01*
X459706Y191421D01*
X459629Y190956D01*
X461239D01*
G01X463534Y194056D02*
X463227Y193953D01*
X462997Y193694D01*
X462844Y193384D01*
X462729Y192971D01*
X462691Y192506D01*
X462729Y192041D01*
X462844Y191628D01*
X462997Y191318D01*
X463227Y191059D01*
X463534Y190956D01*
X463841Y191059D01*
X464071Y191318D01*
X464224Y191628D01*
X464339Y192041D01*
X464377Y192506D01*
X464339Y192971D01*
X464224Y193384D01*
X464071Y193694D01*
X463841Y193953D01*
X463534Y194056D01*
G01X455194Y189705D02*
X465394D01*
G01X454076Y232445D02*
Y235545D01*
X455035D01*
X455341Y235390D01*
X455533Y235183D01*
X455610Y234770D01*
X455533Y234357D01*
X455303Y234098D01*
X455035Y233943D01*
X454076D01*
G01X455035D02*
X455610Y232445D01*
G01X457215Y235028D02*
X457445Y235338D01*
X457713Y235493D01*
X458020Y235545D01*
X458403Y235442D01*
X458671Y235183D01*
X458748Y234873D01*
X458710Y234563D01*
X458556Y234305D01*
X457790Y233788D01*
X457445Y233427D01*
X457215Y232910D01*
X457138Y232445D01*
X458748D01*
G01X460315Y235028D02*
X460545Y235338D01*
X460813Y235493D01*
X461120Y235545D01*
X461503Y235442D01*
X461771Y235183D01*
X461848Y234873D01*
X461810Y234563D01*
X461656Y234305D01*
X460890Y233788D01*
X460545Y233427D01*
X460315Y232910D01*
X460238Y232445D01*
X461848D01*
G01X463491Y232807D02*
X463760Y232548D01*
X464066Y232445D01*
X464373Y232548D01*
X464641Y232858D01*
X464833Y233323D01*
X464910Y233788D01*
Y234357D01*
X464833Y234822D01*
X464641Y235235D01*
X464411Y235442D01*
X464143Y235545D01*
X463836Y235442D01*
X463606Y235235D01*
X463453Y234925D01*
X463376Y234512D01*
X463453Y234150D01*
X463645Y233788D01*
X463875Y233582D01*
X464143Y233530D01*
X464450Y233633D01*
X464680Y233892D01*
X464910Y234357D01*
G01X454077Y228407D02*
Y231507D01*
X455036D01*
X455342Y231352D01*
X455534Y231145D01*
X455611Y230732D01*
X455534Y230319D01*
X455304Y230060D01*
X455036Y229905D01*
X454077D01*
G01X455036D02*
X455611Y228407D01*
G01X457216Y230990D02*
X457446Y231300D01*
X457714Y231455D01*
X458021Y231507D01*
X458404Y231404D01*
X458672Y231145D01*
X458749Y230835D01*
X458711Y230525D01*
X458557Y230267D01*
X457791Y229750D01*
X457446Y229389D01*
X457216Y228872D01*
X457139Y228407D01*
X458749D01*
G01X460316Y230990D02*
X460546Y231300D01*
X460814Y231455D01*
X461121Y231507D01*
X461504Y231404D01*
X461772Y231145D01*
X461849Y230835D01*
X461811Y230525D01*
X461657Y230267D01*
X460891Y229750D01*
X460546Y229389D01*
X460316Y228872D01*
X460239Y228407D01*
X461849D01*
G01X463301Y228872D02*
X463531Y228614D01*
X463799Y228459D01*
X464144Y228407D01*
X464489Y228510D01*
X464757Y228717D01*
X464949Y229079D01*
X464987Y229492D01*
X464911Y229905D01*
X464719Y230164D01*
X464451Y230370D01*
X464182Y230422D01*
X463914Y230370D01*
X463569Y230164D01*
X463684Y231507D01*
X464719D01*
G01X455502Y243403D02*
X455272Y243558D01*
X455004Y243661D01*
X454697D01*
X454352Y243506D01*
X454084Y243248D01*
X453892Y242938D01*
X453739Y242421D01*
X453701Y241956D01*
X453777Y241491D01*
X453892Y241181D01*
X454122Y240871D01*
X454391Y240664D01*
X454659Y240561D01*
X454927D01*
X455196Y240664D01*
X455426Y240819D01*
X455617Y241026D01*
G01X457759Y240561D02*
Y243661D01*
X457299Y243041D01*
G01Y240561D02*
X458219D01*
G01X460859D02*
X461127Y240613D01*
X461434Y240768D01*
X461626Y241026D01*
X461702Y241388D01*
X461626Y241749D01*
X461396Y242059D01*
X461051Y242214D01*
X460667D01*
X460437Y242318D01*
X460246Y242576D01*
X460169Y242938D01*
X460284Y243299D01*
X460552Y243558D01*
X460859Y243661D01*
X461166Y243558D01*
X461434Y243299D01*
X461549Y242938D01*
X461472Y242576D01*
X461281Y242318D01*
X461051Y242214D01*
X460667D01*
X460322Y242059D01*
X460092Y241749D01*
X460016Y241388D01*
X460092Y241026D01*
X460284Y240768D01*
X460591Y240613D01*
X460859Y240561D01*
G01X463116Y241181D02*
X463346Y240819D01*
X463652Y240613D01*
X463997Y240561D01*
X464304Y240613D01*
X464611Y240871D01*
X464802Y241181D01*
X464841Y241491D01*
X464764Y241853D01*
X464496Y242111D01*
X464227Y242214D01*
X463882D01*
G01X464227D02*
X464457Y242369D01*
X464649Y242628D01*
X464726Y242938D01*
X464649Y243248D01*
X464457Y243506D01*
X464112Y243661D01*
X463767Y243609D01*
X463422Y243403D01*
G01X449335Y250904D02*
Y247904D01*
G01X452435Y251004D02*
Y247804D01*
G01X462904Y248260D02*
Y251360D01*
X463863D01*
X464169Y251205D01*
X464361Y250998D01*
X464438Y250585D01*
X464361Y250172D01*
X464131Y249913D01*
X463863Y249758D01*
X462904D01*
G01X463863D02*
X464438Y248260D01*
G01X466043Y250843D02*
X466273Y251153D01*
X466541Y251308D01*
X466848Y251360D01*
X467231Y251257D01*
X467499Y250998D01*
X467576Y250688D01*
X467538Y250378D01*
X467384Y250120D01*
X466618Y249603D01*
X466273Y249242D01*
X466043Y248725D01*
X465966Y248260D01*
X467576D01*
G01X469143Y250843D02*
X469373Y251153D01*
X469641Y251308D01*
X469948Y251360D01*
X470331Y251257D01*
X470599Y250998D01*
X470676Y250688D01*
X470638Y250378D01*
X470484Y250120D01*
X469718Y249603D01*
X469373Y249242D01*
X469143Y248725D01*
X469066Y248260D01*
X470676D01*
G01X472128Y248880D02*
X472358Y248518D01*
X472664Y248312D01*
X473009Y248260D01*
X473316Y248312D01*
X473623Y248570D01*
X473814Y248880D01*
X473853Y249190D01*
X473776Y249552D01*
X473508Y249810D01*
X473239Y249913D01*
X472894D01*
G01X473239D02*
X473469Y250068D01*
X473661Y250327D01*
X473738Y250637D01*
X473661Y250947D01*
X473469Y251205D01*
X473124Y251360D01*
X472779Y251308D01*
X472434Y251102D01*
G01X461876Y248096D02*
X455676D01*
G01D02*
Y251296D01*
G01X461876D02*
Y248096D01*
G01X454319Y236445D02*
Y239545D01*
X455278D01*
X455584Y239390D01*
X455776Y239183D01*
X455853Y238770D01*
X455776Y238357D01*
X455546Y238098D01*
X455278Y237943D01*
X454319D01*
G01X455278D02*
X455853Y236445D01*
G01X457458Y239028D02*
X457688Y239338D01*
X457956Y239493D01*
X458263Y239545D01*
X458646Y239442D01*
X458914Y239183D01*
X458991Y238873D01*
X458953Y238563D01*
X458799Y238305D01*
X458033Y237788D01*
X457688Y237427D01*
X457458Y236910D01*
X457381Y236445D01*
X458991D01*
G01X460558Y239028D02*
X460788Y239338D01*
X461056Y239493D01*
X461363Y239545D01*
X461746Y239442D01*
X462014Y239183D01*
X462091Y238873D01*
X462053Y238563D01*
X461899Y238305D01*
X461133Y237788D01*
X460788Y237427D01*
X460558Y236910D01*
X460481Y236445D01*
X462091D01*
G01X464386D02*
X464654Y236497D01*
X464961Y236652D01*
X465153Y236910D01*
X465229Y237272D01*
X465153Y237633D01*
X464923Y237943D01*
X464578Y238098D01*
X464194D01*
X463964Y238202D01*
X463773Y238460D01*
X463696Y238822D01*
X463811Y239183D01*
X464079Y239442D01*
X464386Y239545D01*
X464693Y239442D01*
X464961Y239183D01*
X465076Y238822D01*
X464999Y238460D01*
X464808Y238202D01*
X464578Y238098D01*
X464194D01*
X463849Y237943D01*
X463619Y237633D01*
X463543Y237272D01*
X463619Y236910D01*
X463811Y236652D01*
X464118Y236497D01*
X464386Y236445D01*
G01X452101Y246762D02*
Y243562D01*
G01Y242762D02*
Y239562D01*
G01Y238762D02*
Y235562D01*
G01X460960Y264469D02*
X460730Y264624D01*
X460462Y264727D01*
X460155D01*
X459810Y264572D01*
X459542Y264314D01*
X459350Y264004D01*
X459197Y263487D01*
X459159Y263022D01*
X459235Y262557D01*
X459350Y262247D01*
X459580Y261937D01*
X459849Y261730D01*
X460117Y261627D01*
X460385D01*
X460654Y261730D01*
X460884Y261885D01*
X461075Y262092D01*
G01X463217Y261627D02*
Y264727D01*
X462757Y264107D01*
G01Y261627D02*
X463677D01*
G01X465665Y261989D02*
X465934Y261730D01*
X466240Y261627D01*
X466547Y261730D01*
X466815Y262040D01*
X467007Y262505D01*
X467084Y262970D01*
Y263539D01*
X467007Y264004D01*
X466815Y264417D01*
X466585Y264624D01*
X466317Y264727D01*
X466010Y264624D01*
X465780Y264417D01*
X465627Y264107D01*
X465550Y263694D01*
X465627Y263332D01*
X465819Y262970D01*
X466049Y262764D01*
X466317Y262712D01*
X466624Y262815D01*
X466854Y263074D01*
X467084Y263539D01*
G01X469340Y261627D02*
X469417Y262299D01*
X469532Y262867D01*
X469685Y263384D01*
X469877Y263952D01*
X470184Y264727D01*
X468650D01*
G01X456182Y264591D02*
Y259991D01*
G01X451082Y264591D02*
Y259991D01*
G01X455676Y251296D02*
X461876D01*
G01X459896Y257000D02*
Y260100D01*
X460855D01*
X461161Y259945D01*
X461353Y259738D01*
X461430Y259325D01*
X461353Y258912D01*
X461123Y258653D01*
X460855Y258498D01*
X459896D01*
G01X460855D02*
X461430Y257000D01*
G01X463035Y259583D02*
X463265Y259893D01*
X463533Y260048D01*
X463840Y260100D01*
X464223Y259997D01*
X464491Y259738D01*
X464568Y259428D01*
X464530Y259118D01*
X464376Y258860D01*
X463610Y258343D01*
X463265Y257982D01*
X463035Y257465D01*
X462958Y257000D01*
X464568D01*
G01X466135Y259583D02*
X466365Y259893D01*
X466633Y260048D01*
X466940Y260100D01*
X467323Y259997D01*
X467591Y259738D01*
X467668Y259428D01*
X467630Y259118D01*
X467476Y258860D01*
X466710Y258343D01*
X466365Y257982D01*
X466135Y257465D01*
X466058Y257000D01*
X467668D01*
G01X469963D02*
Y260100D01*
X469503Y259480D01*
G01Y257000D02*
X470423D01*
G01X448659Y259095D02*
X454859D01*
G01D02*
Y255895D01*
G01D02*
X448659D01*
G01D02*
Y259095D01*
G01X551781Y329924D02*
G02I-44292J0D01*
G01X449337Y484739D02*
Y490939D01*
G01X452537D02*
Y484739D01*
G01D02*
X449337D01*
G01X453288Y476723D02*
Y494123D01*
G01X460688Y476723D02*
X453288D01*
G01X460688Y494123D02*
Y476723D01*
G01X453288Y485423D02*
X460688D01*
G01X461555Y476721D02*
Y494121D01*
G01X468955Y476721D02*
X461555D01*
G01Y485421D02*
X468955D01*
G01X452437Y487839D02*
X449437D01*
G01X449337Y490939D02*
X452537D01*
G01X453288Y494123D02*
X460688D01*
G01X461555Y494121D02*
X468955D01*
G01X457883Y499303D02*
X454783D01*
Y500223D01*
X454938Y500530D01*
X455300Y500760D01*
X455713Y500837D01*
X456126Y500760D01*
X456436Y500568D01*
X456591Y500223D01*
Y499303D01*
G01X457883Y502403D02*
X454783D01*
Y503362D01*
X454938Y503668D01*
X455145Y503860D01*
X455558Y503937D01*
X455971Y503860D01*
X456230Y503630D01*
X456385Y503362D01*
Y502403D01*
G01Y503362D02*
X457883Y503937D01*
G01X457418Y505427D02*
X457676Y505657D01*
X457831Y505925D01*
X457883Y506270D01*
X457780Y506615D01*
X457573Y506883D01*
X457211Y507075D01*
X456798Y507113D01*
X456385Y507037D01*
X456126Y506845D01*
X455920Y506577D01*
X455868Y506308D01*
X455920Y506040D01*
X456126Y505695D01*
X454783Y505810D01*
Y506845D01*
G01X457521Y508718D02*
X457780Y508987D01*
X457883Y509293D01*
X457780Y509600D01*
X457470Y509868D01*
X457005Y510060D01*
X456540Y510137D01*
X455971D01*
X455506Y510060D01*
X455093Y509868D01*
X454886Y509638D01*
X454783Y509370D01*
X454886Y509063D01*
X455093Y508833D01*
X455403Y508680D01*
X455816Y508603D01*
X456178Y508680D01*
X456540Y508872D01*
X456746Y509102D01*
X456798Y509370D01*
X456695Y509677D01*
X456436Y509907D01*
X455971Y510137D01*
G01X458644Y496762D02*
Y514162D01*
G01X466044Y496762D02*
X458644D01*
G01X452341Y515821D02*
Y526021D01*
G01X456941Y515821D02*
X452341D01*
G01X456941Y526021D02*
Y515821D01*
G01X465947Y517401D02*
X462847D01*
Y518321D01*
X463002Y518628D01*
X463364Y518858D01*
X463777Y518935D01*
X464190Y518858D01*
X464500Y518666D01*
X464655Y518321D01*
Y517401D01*
G01X465947Y520501D02*
X462847D01*
Y521460D01*
X463002Y521766D01*
X463209Y521958D01*
X463622Y522035D01*
X464035Y521958D01*
X464294Y521728D01*
X464449Y521460D01*
Y520501D01*
G01Y521460D02*
X465947Y522035D01*
G01X465482Y523525D02*
X465740Y523755D01*
X465895Y524023D01*
X465947Y524368D01*
X465844Y524713D01*
X465637Y524981D01*
X465275Y525173D01*
X464862Y525211D01*
X464449Y525135D01*
X464190Y524943D01*
X463984Y524675D01*
X463932Y524406D01*
X463984Y524138D01*
X464190Y523793D01*
X462847Y523908D01*
Y524943D01*
G01X465482Y526625D02*
X465740Y526855D01*
X465895Y527123D01*
X465947Y527468D01*
X465844Y527813D01*
X465637Y528081D01*
X465275Y528273D01*
X464862Y528311D01*
X464449Y528235D01*
X464190Y528043D01*
X463984Y527775D01*
X463932Y527506D01*
X463984Y527238D01*
X464190Y526893D01*
X462847Y527008D01*
Y528043D01*
G01X462006Y517328D02*
X458906D01*
Y518248D01*
X459061Y518555D01*
X459423Y518785D01*
X459836Y518862D01*
X460249Y518785D01*
X460559Y518593D01*
X460714Y518248D01*
Y517328D01*
G01X462006Y520428D02*
X458906D01*
Y521387D01*
X459061Y521693D01*
X459268Y521885D01*
X459681Y521962D01*
X460094Y521885D01*
X460353Y521655D01*
X460508Y521387D01*
Y520428D01*
G01Y521387D02*
X462006Y521962D01*
G01Y524755D02*
X458906D01*
X461128Y523337D01*
Y525253D01*
G01X459423Y526667D02*
X459113Y526897D01*
X458958Y527165D01*
X458906Y527472D01*
X459009Y527855D01*
X459268Y528123D01*
X459578Y528200D01*
X459888Y528162D01*
X460146Y528008D01*
X460663Y527242D01*
X461024Y526897D01*
X461541Y526667D01*
X462006Y526590D01*
Y528200D01*
G01X449358Y522836D02*
Y516636D01*
G01X457570Y515010D02*
Y511810D01*
G01X451370Y515010D02*
X457570D01*
G01X451370Y511810D02*
Y515010D01*
G01X457570Y511810D02*
X451370D01*
G01X458644Y514162D02*
X466044D01*
G01X451400Y530170D02*
X480280D01*
G01X451400Y524150D02*
Y530170D01*
G01X449865Y528118D02*
Y524918D01*
G01X454366Y533959D02*
Y530759D01*
G01X448166D02*
Y533959D01*
G01X454366Y530759D02*
X448166D01*
G01X451266Y533859D02*
Y530859D01*
G01X456941Y520921D02*
X452341D01*
G01Y526021D02*
X456941D01*
G01X462322Y530826D02*
X459122D01*
G01X462322Y537026D02*
Y530826D01*
G01X459122D02*
Y537026D01*
G01X455122Y530826D02*
Y537026D01*
G01X458322Y530826D02*
X455122D01*
G01X458322Y537026D02*
Y530826D01*
G01X448166Y533959D02*
X454366D01*
G01X449190Y548844D02*
Y555044D01*
G01X452390Y548844D02*
X449190D01*
G01X452390Y555044D02*
Y548844D01*
G01X448767Y541761D02*
Y547961D01*
G01X451967Y541761D02*
X448767D01*
G01X451967Y547961D02*
Y541761D01*
G01X448867Y544861D02*
X451867D01*
G01X448767Y547961D02*
X451967D01*
G01X448167Y536485D02*
Y539685D01*
G01X454367Y536485D02*
X448167D01*
G01X454367Y539685D02*
Y536485D01*
G01X448167Y539685D02*
X454367D01*
G01X451267Y536585D02*
Y539585D01*
G01X455162Y541963D02*
Y545163D01*
G01X461362Y541963D02*
X455162D01*
G01X461362Y545163D02*
Y541963D01*
G01X455162Y545163D02*
X461362D01*
G01X458262Y542063D02*
Y545063D01*
G01X448136Y555043D02*
Y548843D01*
G01X459122Y537026D02*
X462322D01*
G01X455122D02*
X458322D01*
G01X463188Y548938D02*
X459988D01*
G01X463188Y555138D02*
Y548938D01*
G01X459988D02*
Y555138D01*
G01X461318Y541043D02*
Y537843D01*
G01X455118Y541043D02*
X461318D01*
G01X455118Y537843D02*
Y541043D01*
G01X461318Y537843D02*
X455118D01*
G01X458174Y557707D02*
X455674D01*
Y558347D01*
X455799Y558560D01*
X456091Y558720D01*
X456424Y558773D01*
X456757Y558720D01*
X457007Y558587D01*
X457132Y558347D01*
Y557707D01*
G01X455882Y561027D02*
X455757Y560867D01*
X455674Y560680D01*
Y560467D01*
X455799Y560227D01*
X456007Y560040D01*
X456257Y559907D01*
X456674Y559800D01*
X457049Y559773D01*
X457424Y559827D01*
X457674Y559907D01*
X457924Y560067D01*
X458091Y560253D01*
X458174Y560440D01*
Y560627D01*
X458091Y560813D01*
X457966Y560973D01*
X457799Y561107D01*
G01X458174Y562640D02*
X455674D01*
X456174Y562320D01*
G01X458174D02*
Y562960D01*
G01X456091Y564333D02*
X455841Y564493D01*
X455716Y564680D01*
X455674Y564893D01*
X455757Y565160D01*
X455966Y565347D01*
X456216Y565400D01*
X456466Y565373D01*
X456674Y565267D01*
X457091Y564733D01*
X457382Y564493D01*
X457799Y564333D01*
X458174Y564280D01*
Y565400D01*
G01X456091Y566533D02*
X455841Y566693D01*
X455716Y566880D01*
X455674Y567093D01*
X455757Y567360D01*
X455966Y567547D01*
X456216Y567600D01*
X456466Y567573D01*
X456674Y567467D01*
X457091Y566933D01*
X457382Y566693D01*
X457799Y566533D01*
X458174Y566480D01*
Y567600D01*
G01X449190Y555044D02*
X452390D01*
G01X449290Y551944D02*
X452290D01*
G01X464624Y557877D02*
X462124D01*
Y558517D01*
X462249Y558730D01*
X462541Y558890D01*
X462874Y558943D01*
X463207Y558890D01*
X463457Y558757D01*
X463582Y558517D01*
Y557877D01*
G01X462332Y561197D02*
X462207Y561037D01*
X462124Y560850D01*
Y560637D01*
X462249Y560397D01*
X462457Y560210D01*
X462707Y560077D01*
X463124Y559970D01*
X463499Y559943D01*
X463874Y559997D01*
X464124Y560077D01*
X464374Y560237D01*
X464541Y560423D01*
X464624Y560610D01*
Y560797D01*
X464541Y560983D01*
X464416Y561143D01*
X464249Y561277D01*
G01X464624Y562810D02*
X462124D01*
X462624Y562490D01*
G01X464624D02*
Y563130D01*
G01X462124Y565010D02*
X462207Y564797D01*
X462416Y564637D01*
X462666Y564530D01*
X462999Y564450D01*
X463374Y564423D01*
X463749Y564450D01*
X464082Y564530D01*
X464332Y564637D01*
X464541Y564797D01*
X464624Y565010D01*
X464541Y565223D01*
X464332Y565383D01*
X464082Y565490D01*
X463749Y565570D01*
X463374Y565597D01*
X462999Y565570D01*
X462666Y565490D01*
X462416Y565383D01*
X462207Y565223D01*
X462124Y565010D01*
G01X464332Y566757D02*
X464541Y566943D01*
X464624Y567157D01*
X464541Y567370D01*
X464291Y567557D01*
X463916Y567690D01*
X463541Y567743D01*
X463082D01*
X462707Y567690D01*
X462374Y567557D01*
X462207Y567397D01*
X462124Y567210D01*
X462207Y566997D01*
X462374Y566837D01*
X462624Y566730D01*
X462957Y566677D01*
X463249Y566730D01*
X463541Y566863D01*
X463707Y567023D01*
X463749Y567210D01*
X463666Y567423D01*
X463457Y567583D01*
X463082Y567743D01*
G01X454974Y557607D02*
X452474D01*
Y558247D01*
X452599Y558460D01*
X452891Y558620D01*
X453224Y558673D01*
X453557Y558620D01*
X453807Y558487D01*
X453932Y558247D01*
Y557607D01*
G01X452682Y560927D02*
X452557Y560767D01*
X452474Y560580D01*
Y560367D01*
X452599Y560127D01*
X452807Y559940D01*
X453057Y559807D01*
X453474Y559700D01*
X453849Y559673D01*
X454224Y559727D01*
X454474Y559807D01*
X454724Y559967D01*
X454891Y560153D01*
X454974Y560340D01*
Y560527D01*
X454891Y560713D01*
X454766Y560873D01*
X454599Y561007D01*
G01X454974Y562540D02*
X454932Y562727D01*
X454807Y562940D01*
X454599Y563073D01*
X454307Y563127D01*
X454016Y563073D01*
X453766Y562913D01*
X453641Y562673D01*
Y562407D01*
X453557Y562247D01*
X453349Y562113D01*
X453057Y562060D01*
X452766Y562140D01*
X452557Y562327D01*
X452474Y562540D01*
X452557Y562753D01*
X452766Y562940D01*
X453057Y563020D01*
X453349Y562967D01*
X453557Y562833D01*
X453641Y562673D01*
Y562407D01*
X453766Y562167D01*
X454016Y562007D01*
X454307Y561953D01*
X454599Y562007D01*
X454807Y562140D01*
X454932Y562353D01*
X454974Y562540D01*
G01Y564687D02*
X454432Y564740D01*
X453974Y564820D01*
X453557Y564927D01*
X453099Y565060D01*
X452474Y565273D01*
Y564207D01*
G01X459988Y555138D02*
X463188D01*
G01X461451Y557781D02*
X458951D01*
Y558421D01*
X459076Y558634D01*
X459368Y558794D01*
X459701Y558847D01*
X460034Y558794D01*
X460284Y558661D01*
X460409Y558421D01*
Y557781D01*
G01X460951Y559981D02*
X461201Y560114D01*
X461368Y560274D01*
X461451Y560461D01*
X461368Y560674D01*
X461201Y560834D01*
X460951Y560994D01*
X460618Y561047D01*
X458951D01*
G01X461451Y562714D02*
X458951D01*
X459451Y562394D01*
G01X461451D02*
Y563034D01*
G01X461076Y564327D02*
X461284Y564487D01*
X461409Y564674D01*
X461451Y564914D01*
X461368Y565154D01*
X461201Y565341D01*
X460909Y565474D01*
X460576Y565501D01*
X460243Y565447D01*
X460034Y565314D01*
X459868Y565127D01*
X459826Y564941D01*
X459868Y564754D01*
X460034Y564514D01*
X458951Y564594D01*
Y565314D01*
G01X458470Y579250D02*
Y574470D01*
G01X475210Y579250D02*
X458470D01*
G01X460229Y580336D02*
X456831D01*
Y579211D01*
G01X465088Y568430D02*
X462588D01*
Y569070D01*
X462713Y569283D01*
X463005Y569443D01*
X463338Y569496D01*
X463671Y569443D01*
X463921Y569310D01*
X464046Y569070D01*
Y568430D01*
G01X462796Y571750D02*
X462671Y571590D01*
X462588Y571403D01*
Y571190D01*
X462713Y570950D01*
X462921Y570763D01*
X463171Y570630D01*
X463588Y570523D01*
X463963Y570496D01*
X464338Y570550D01*
X464588Y570630D01*
X464838Y570790D01*
X465005Y570976D01*
X465088Y571163D01*
Y571350D01*
X465005Y571536D01*
X464880Y571696D01*
X464713Y571830D01*
G01X465088Y573363D02*
X462588D01*
X463088Y573043D01*
G01X465088D02*
Y573683D01*
G01X462588Y575563D02*
X462671Y575350D01*
X462880Y575190D01*
X463130Y575083D01*
X463463Y575003D01*
X463838Y574976D01*
X464213Y575003D01*
X464546Y575083D01*
X464796Y575190D01*
X465005Y575350D01*
X465088Y575563D01*
X465005Y575776D01*
X464796Y575936D01*
X464546Y576043D01*
X464213Y576123D01*
X463838Y576150D01*
X463463Y576123D01*
X463130Y576043D01*
X462880Y575936D01*
X462671Y575776D01*
X462588Y575563D01*
G01X465088Y578083D02*
X462588D01*
X464380Y577096D01*
Y578430D01*
G01X468020Y580079D02*
X461820D01*
G01D02*
Y583279D01*
G01X461824Y568387D02*
X459324D01*
Y569027D01*
X459449Y569240D01*
X459741Y569400D01*
X460074Y569453D01*
X460407Y569400D01*
X460657Y569267D01*
X460782Y569027D01*
Y568387D01*
G01X461824Y570587D02*
X459324D01*
Y571253D01*
X459449Y571467D01*
X459616Y571600D01*
X459949Y571653D01*
X460282Y571600D01*
X460491Y571440D01*
X460616Y571253D01*
Y570587D01*
G01Y571253D02*
X461824Y571653D01*
G01Y573267D02*
X461282Y573320D01*
X460824Y573400D01*
X460407Y573507D01*
X459949Y573640D01*
X459324Y573853D01*
Y572787D01*
G01X461824Y575520D02*
X459324D01*
X459824Y575200D01*
G01X461824D02*
Y575840D01*
G01X449807Y569237D02*
Y571737D01*
X450447D01*
X450660Y571612D01*
X450820Y571320D01*
X450873Y570987D01*
X450820Y570654D01*
X450687Y570404D01*
X450447Y570279D01*
X449807D01*
G01X452007Y569237D02*
Y571737D01*
X452673D01*
X452887Y571612D01*
X453020Y571445D01*
X453073Y571112D01*
X453020Y570779D01*
X452860Y570570D01*
X452673Y570445D01*
X452007D01*
G01X452673D02*
X453073Y569237D01*
G01X454233Y570279D02*
X454420Y570570D01*
X454580Y570737D01*
X454793Y570820D01*
X454980Y570737D01*
X455113Y570570D01*
X455220Y570320D01*
X455247Y570029D01*
X455220Y569779D01*
X455113Y569529D01*
X454953Y569320D01*
X454767Y569237D01*
X454553Y569320D01*
X454367Y569570D01*
X454260Y569945D01*
X454233Y570362D01*
X454287Y570904D01*
X454367Y571195D01*
X454500Y571487D01*
X454687Y571695D01*
X454873Y571737D01*
X455060Y571654D01*
X455193Y571445D01*
G01X456940Y571737D02*
X456727Y571654D01*
X456567Y571445D01*
X456460Y571195D01*
X456380Y570862D01*
X456353Y570487D01*
X456380Y570112D01*
X456460Y569779D01*
X456567Y569529D01*
X456727Y569320D01*
X456940Y569237D01*
X457153Y569320D01*
X457313Y569529D01*
X457420Y569779D01*
X457500Y570112D01*
X457527Y570487D01*
X457500Y570862D01*
X457420Y571195D01*
X457313Y571445D01*
X457153Y571654D01*
X456940Y571737D01*
G01X457791Y597538D02*
X456127D01*
Y594327D01*
X454346D01*
G01X461820Y583279D02*
X468020D01*
G01X467627Y584170D02*
X452627D01*
G01Y590970D02*
X467627D01*
G01X452627Y584170D02*
Y590970D01*
G01X456853Y593516D02*
Y596016D01*
X457387D01*
X457600Y595891D01*
X457760Y595724D01*
X457893Y595474D01*
X458000Y595183D01*
X458027Y594766D01*
X458000Y594349D01*
X457893Y594058D01*
X457760Y593808D01*
X457600Y593641D01*
X457387Y593516D01*
X456853D01*
G01X458665Y592160D02*
Y607160D01*
G01X471665Y592160D02*
X458665D01*
G01X451392Y601334D02*
X451415D01*
Y599435D01*
G01X450875Y606822D02*
Y602222D01*
G01X455975Y606822D02*
Y602222D01*
G01X461723Y608937D02*
Y611437D01*
X462257D01*
X462470Y611312D01*
X462630Y611145D01*
X462763Y610895D01*
X462870Y610604D01*
X462897Y610187D01*
X462870Y609770D01*
X462763Y609479D01*
X462630Y609229D01*
X462470Y609062D01*
X462257Y608937D01*
X461723D01*
G01X464435Y607973D02*
X451435D01*
G01D02*
Y622973D01*
G01X457725Y605327D02*
X457512Y605535D01*
X457272Y605660D01*
X457058D01*
X456845Y605535D01*
X456685Y605327D01*
X456605Y605035D01*
X456658Y604743D01*
X456792Y604493D01*
X457032Y604327D01*
X457352Y604243D01*
X457538Y604077D01*
X457618Y603785D01*
X457565Y603493D01*
X457432Y603285D01*
X457245Y603160D01*
X457058D01*
X456872Y603243D01*
X456712Y603452D01*
G01X458665Y607160D02*
X471665D01*
G01X450635Y622973D02*
Y607973D01*
G01X464447Y626510D02*
X464287Y626635D01*
X464100Y626718D01*
X463887D01*
X463647Y626593D01*
X463460Y626385D01*
X463327Y626135D01*
X463220Y625718D01*
X463193Y625343D01*
X463247Y624968D01*
X463327Y624718D01*
X463487Y624468D01*
X463673Y624301D01*
X463860Y624218D01*
X464047D01*
X464233Y624301D01*
X464393Y624426D01*
X464527Y624593D01*
G01X465607Y624510D02*
X465793Y624301D01*
X466007Y624218D01*
X466220Y624301D01*
X466407Y624551D01*
X466540Y624926D01*
X466593Y625301D01*
Y625760D01*
X466540Y626135D01*
X466407Y626468D01*
X466247Y626635D01*
X466060Y626718D01*
X465847Y626635D01*
X465687Y626468D01*
X465580Y626218D01*
X465527Y625885D01*
X465580Y625593D01*
X465713Y625301D01*
X465873Y625135D01*
X466060Y625093D01*
X466273Y625176D01*
X466433Y625385D01*
X466593Y625760D01*
G01X467673Y624718D02*
X467833Y624426D01*
X468047Y624260D01*
X468287Y624218D01*
X468500Y624260D01*
X468713Y624468D01*
X468847Y624718D01*
X468873Y624968D01*
X468820Y625260D01*
X468633Y625468D01*
X468447Y625551D01*
X468207D01*
G01X468447D02*
X468607Y625676D01*
X468740Y625885D01*
X468793Y626135D01*
X468740Y626385D01*
X468607Y626593D01*
X468367Y626718D01*
X468127Y626676D01*
X467887Y626510D01*
G01X470780Y624218D02*
Y626718D01*
X469793Y624926D01*
X471127D01*
G01X462124Y628227D02*
X459624D01*
Y628893D01*
X459749Y629107D01*
X459916Y629240D01*
X460249Y629293D01*
X460582Y629240D01*
X460791Y629080D01*
X460916Y628893D01*
Y628227D01*
G01Y628893D02*
X462124Y629293D01*
G01X461082Y630453D02*
X460791Y630640D01*
X460624Y630800D01*
X460541Y631013D01*
X460624Y631200D01*
X460791Y631333D01*
X461041Y631440D01*
X461332Y631467D01*
X461582Y631440D01*
X461832Y631333D01*
X462041Y631173D01*
X462124Y630987D01*
X462041Y630773D01*
X461791Y630587D01*
X461416Y630480D01*
X460999Y630453D01*
X460457Y630507D01*
X460166Y630587D01*
X459874Y630720D01*
X459666Y630907D01*
X459624Y631093D01*
X459707Y631280D01*
X459916Y631413D01*
G01X461082Y632653D02*
X460791Y632840D01*
X460624Y633000D01*
X460541Y633213D01*
X460624Y633400D01*
X460791Y633533D01*
X461041Y633640D01*
X461332Y633667D01*
X461582Y633640D01*
X461832Y633533D01*
X462041Y633373D01*
X462124Y633187D01*
X462041Y632973D01*
X461791Y632787D01*
X461416Y632680D01*
X460999Y632653D01*
X460457Y632707D01*
X460166Y632787D01*
X459874Y632920D01*
X459666Y633107D01*
X459624Y633293D01*
X459707Y633480D01*
X459916Y633613D01*
G01X462124Y635360D02*
X462082Y635547D01*
X461957Y635760D01*
X461749Y635893D01*
X461457Y635947D01*
X461166Y635893D01*
X460916Y635733D01*
X460791Y635493D01*
Y635227D01*
X460707Y635067D01*
X460499Y634933D01*
X460207Y634880D01*
X459916Y634960D01*
X459707Y635147D01*
X459624Y635360D01*
X459707Y635573D01*
X459916Y635760D01*
X460207Y635840D01*
X460499Y635787D01*
X460707Y635653D01*
X460791Y635493D01*
Y635227D01*
X460916Y634987D01*
X461166Y634827D01*
X461457Y634773D01*
X461749Y634827D01*
X461957Y634960D01*
X462082Y635173D01*
X462124Y635360D01*
G01X461720Y615296D02*
X462253D01*
Y614546D01*
X462093Y614296D01*
X461907Y614129D01*
X461640Y614046D01*
X461373Y614129D01*
X461187Y614296D01*
X461027Y614546D01*
X460920Y614838D01*
X460867Y615171D01*
Y615463D01*
X460920Y615713D01*
X461027Y616004D01*
X461187Y616254D01*
X461347Y616421D01*
X461560Y616546D01*
X461747D01*
X461960Y616463D01*
X462120Y616296D01*
G01X453320Y614285D02*
X453533Y614077D01*
X453773Y613952D01*
X453987D01*
X454200Y614077D01*
X454360Y614285D01*
X454440Y614577D01*
X454387Y614869D01*
X454253Y615119D01*
X454013Y615285D01*
X453693Y615369D01*
X453507Y615535D01*
X453427Y615827D01*
X453480Y616119D01*
X453613Y616327D01*
X453800Y616452D01*
X453987D01*
X454173Y616369D01*
X454333Y616160D01*
G01X455831Y623469D02*
X457623D01*
X457998Y623576D01*
X458248Y623789D01*
X458331Y624056D01*
X458248Y624323D01*
X457998Y624536D01*
X457623Y624643D01*
X455831D01*
G01X458331Y626256D02*
X455831D01*
X456331Y625936D01*
G01X458331D02*
Y626576D01*
G01Y628456D02*
X455831D01*
X456331Y628136D01*
G01X458331D02*
Y628776D01*
G01X455831Y630656D02*
X455914Y630443D01*
X456123Y630283D01*
X456373Y630176D01*
X456706Y630096D01*
X457081Y630069D01*
X457456Y630096D01*
X457789Y630176D01*
X458039Y630283D01*
X458248Y630443D01*
X458331Y630656D01*
X458248Y630869D01*
X458039Y631029D01*
X457789Y631136D01*
X457456Y631216D01*
X457081Y631243D01*
X456706Y631216D01*
X456373Y631136D01*
X456123Y631029D01*
X455914Y630869D01*
X455831Y630656D01*
G01X451435Y622973D02*
X464435D01*
G01X448787Y615438D02*
X449320D01*
Y614688D01*
X449160Y614438D01*
X448974Y614271D01*
X448707Y614188D01*
X448440Y614271D01*
X448254Y614438D01*
X448094Y614688D01*
X447987Y614980D01*
X447934Y615313D01*
Y615605D01*
X447987Y615855D01*
X448094Y616146D01*
X448254Y616396D01*
X448414Y616563D01*
X448627Y616688D01*
X448814D01*
X449027Y616605D01*
X449187Y616438D01*
G01X449894Y623683D02*
X451686D01*
X452061Y623790D01*
X452311Y624003D01*
X452394Y624270D01*
X452311Y624537D01*
X452061Y624750D01*
X451686Y624857D01*
X449894D01*
G01X452394Y626470D02*
X449894D01*
X450394Y626150D01*
G01X452394D02*
Y626790D01*
G01X449894Y628670D02*
X449977Y628457D01*
X450186Y628297D01*
X450436Y628190D01*
X450769Y628110D01*
X451144Y628083D01*
X451519Y628110D01*
X451852Y628190D01*
X452102Y628297D01*
X452311Y628457D01*
X452394Y628670D01*
X452311Y628883D01*
X452102Y629043D01*
X451852Y629150D01*
X451519Y629230D01*
X451144Y629257D01*
X450769Y629230D01*
X450436Y629150D01*
X450186Y629043D01*
X449977Y628883D01*
X449894Y628670D01*
G01X452394Y630817D02*
X451852Y630870D01*
X451394Y630950D01*
X450977Y631057D01*
X450519Y631190D01*
X449894Y631403D01*
Y630337D01*
G01X448160Y636420D02*
Y663490D01*
G01X478110Y636420D02*
X448160D01*
G01X455440Y638056D02*
Y658256D01*
G01X471240Y638056D02*
X455440D01*
G01X463340Y655956D02*
X465640Y658256D01*
G01X461040D02*
X463340Y655956D01*
G01X455440Y658256D02*
X461040D01*
G01X458340Y656156D02*
G02I-1000J0D01*
G01X448160Y672390D02*
Y666670D01*
G01Y694860D02*
Y674970D01*
G01X455440Y660556D02*
Y680756D01*
G01X471240Y660556D02*
X455440D01*
G01X463340Y678456D02*
X465640Y680756D01*
G01X461040D02*
X463340Y678456D01*
G01X455440Y680756D02*
X461040D01*
G01X458340Y678656D02*
G02I-1000J0D01*
G01X453540Y687556D02*
X450340D01*
G01X453540Y693756D02*
Y687556D01*
G01X450340D02*
Y693756D01*
G01X463040Y687556D02*
X459840D01*
G01X463040Y693756D02*
Y687556D01*
G01X459840D02*
Y693756D01*
G01X458040Y687556D02*
X454840D01*
G01X458040Y693756D02*
Y687556D01*
G01X454840D02*
Y693756D01*
G01X489510Y694860D02*
X448160D01*
G01X450487Y698826D02*
Y697059D01*
G01X457082Y698942D02*
Y697175D01*
G01X449640Y711356D02*
Y700956D01*
G01Y699156D02*
Y700956D01*
G01X451740D02*
Y711356D01*
G01X456140Y700956D02*
X451740D01*
G01X456140Y711356D02*
Y700956D01*
G01Y700356D02*
X451740D01*
G01Y699756D02*
X456140D01*
G01Y699156D02*
X451740D01*
G01D02*
Y700956D01*
G01X456140Y699156D02*
Y700956D01*
G01X458740D02*
Y711356D01*
G01X463140Y700956D02*
X458740D01*
G01X463140Y700356D02*
X458740D01*
G01Y699756D02*
X463140D01*
G01Y699156D02*
X458740D01*
G01D02*
Y700956D01*
G01X463140Y711356D02*
Y700956D01*
G01Y699156D02*
Y700956D01*
G01X450340Y693756D02*
X453540D01*
G01X459840D02*
X463040D01*
G01X454840D02*
X458040D01*
G01X459365Y715623D02*
X459745Y715040D01*
X460251Y714706D01*
X460821Y714623D01*
X461328Y714706D01*
X461835Y715123D01*
X462151Y715623D01*
X462215Y716123D01*
X462088Y716706D01*
X461645Y717123D01*
X461201Y717290D01*
X460631D01*
G01X461201D02*
X461581Y717540D01*
X461898Y717956D01*
X462025Y718456D01*
X461898Y718956D01*
X461581Y719373D01*
X461011Y719623D01*
X460441Y719540D01*
X459871Y719206D01*
G01X453978Y715956D02*
Y720956D01*
X451635Y717373D01*
X454801D01*
G01X460552Y721065D02*
X461059Y720648D01*
X461629Y720398D01*
X462135D01*
X462642Y720648D01*
X463022Y721065D01*
X463212Y721648D01*
X463085Y722231D01*
X462769Y722731D01*
X462199Y723065D01*
X461439Y723231D01*
X460995Y723565D01*
X460805Y724148D01*
X460932Y724731D01*
X461249Y725148D01*
X461692Y725398D01*
X462135D01*
X462579Y725231D01*
X462959Y724815D01*
G01X465082Y725398D02*
X465969Y720398D01*
X466982Y725398D01*
X467995Y720398D01*
X468882Y725398D01*
G01X451740Y711356D02*
X456140D01*
G01X458740D02*
X463140D01*
G01X454540Y737556D02*
X451340D01*
G01X454540Y743756D02*
Y737556D01*
G01X451340D02*
Y743756D01*
G01X458940Y729156D02*
X455940D01*
G01X459040Y726056D02*
X455840D01*
G01X459040Y732256D02*
Y726056D01*
G01X455840Y732256D02*
X459040D01*
G01X455840Y726056D02*
Y732256D01*
G01X463540Y737556D02*
X460340D01*
G01D02*
Y743756D01*
G01X450040Y732256D02*
Y726056D01*
G01X455840Y737556D02*
Y743756D01*
G01X459040Y737556D02*
X455840D01*
G01X459040Y743756D02*
Y737556D01*
G01X450040Y743756D02*
Y737556D01*
G01X454440Y740656D02*
X451440D01*
G01X451340Y743756D02*
X454540D01*
G01X459651Y749921D02*
X459496Y749691D01*
X459393Y749423D01*
Y749116D01*
X459548Y748771D01*
X459806Y748503D01*
X460116Y748311D01*
X460633Y748158D01*
X461098Y748120D01*
X461563Y748196D01*
X461873Y748311D01*
X462183Y748541D01*
X462390Y748810D01*
X462493Y749078D01*
Y749346D01*
X462390Y749615D01*
X462235Y749845D01*
X462028Y750036D01*
G01X462493Y752101D02*
X461821Y752178D01*
X461253Y752293D01*
X460736Y752446D01*
X460168Y752638D01*
X459393Y752945D01*
Y751411D01*
G01X462028Y754435D02*
X462286Y754665D01*
X462441Y754933D01*
X462493Y755278D01*
X462390Y755623D01*
X462183Y755891D01*
X461821Y756083D01*
X461408Y756121D01*
X460995Y756045D01*
X460736Y755853D01*
X460530Y755585D01*
X460478Y755316D01*
X460530Y755048D01*
X460736Y754703D01*
X459393Y754818D01*
Y755853D01*
G01X462493Y758838D02*
X459393D01*
X461615Y757420D01*
Y759336D01*
G01X463440Y740656D02*
X460440D01*
G01X460340Y743756D02*
X463540D01*
G01X455840D02*
X459040D01*
G01X453406Y762932D02*
X453251Y762702D01*
X453148Y762434D01*
Y762127D01*
X453303Y761782D01*
X453561Y761514D01*
X453871Y761322D01*
X454388Y761169D01*
X454853Y761131D01*
X455318Y761207D01*
X455628Y761322D01*
X455938Y761552D01*
X456145Y761821D01*
X456248Y762089D01*
Y762357D01*
X456145Y762626D01*
X455990Y762856D01*
X455783Y763047D01*
G01X456248Y765112D02*
X455576Y765189D01*
X455008Y765304D01*
X454491Y765457D01*
X453923Y765649D01*
X453148Y765956D01*
Y764422D01*
G01X455783Y767446D02*
X456041Y767676D01*
X456196Y767944D01*
X456248Y768289D01*
X456145Y768634D01*
X455938Y768902D01*
X455576Y769094D01*
X455163Y769132D01*
X454750Y769056D01*
X454491Y768864D01*
X454285Y768596D01*
X454233Y768327D01*
X454285Y768059D01*
X454491Y767714D01*
X453148Y767829D01*
Y768864D01*
G01X456248Y771312D02*
X455576Y771389D01*
X455008Y771504D01*
X454491Y771657D01*
X453923Y771849D01*
X453148Y772156D01*
Y770622D01*
G01X461256Y761701D02*
X461101Y761471D01*
X460998Y761203D01*
Y760896D01*
X461153Y760551D01*
X461411Y760283D01*
X461721Y760091D01*
X462238Y759938D01*
X462703Y759900D01*
X463168Y759976D01*
X463478Y760091D01*
X463788Y760321D01*
X463995Y760590D01*
X464098Y760858D01*
Y761126D01*
X463995Y761395D01*
X463840Y761625D01*
X463633Y761816D01*
G01X464098Y763881D02*
X463426Y763958D01*
X462858Y764073D01*
X462341Y764226D01*
X461773Y764418D01*
X460998Y764725D01*
Y763191D01*
G01X463633Y766215D02*
X463891Y766445D01*
X464046Y766713D01*
X464098Y767058D01*
X463995Y767403D01*
X463788Y767671D01*
X463426Y767863D01*
X463013Y767901D01*
X462600Y767825D01*
X462341Y767633D01*
X462135Y767365D01*
X462083Y767096D01*
X462135Y766828D01*
X462341Y766483D01*
X460998Y766598D01*
Y767633D01*
G01X464098Y770158D02*
X460998D01*
X461618Y769698D01*
G01X464098D02*
Y770618D01*
G01X460288Y760272D02*
X457188D01*
Y761231D01*
X457343Y761537D01*
X457550Y761729D01*
X457963Y761806D01*
X458376Y761729D01*
X458635Y761499D01*
X458790Y761231D01*
Y760272D01*
G01Y761231D02*
X460288Y761806D01*
G01X459926Y763487D02*
X460185Y763756D01*
X460288Y764062D01*
X460185Y764369D01*
X459875Y764637D01*
X459410Y764829D01*
X458945Y764906D01*
X458376D01*
X457911Y764829D01*
X457498Y764637D01*
X457291Y764407D01*
X457188Y764139D01*
X457291Y763832D01*
X457498Y763602D01*
X457808Y763449D01*
X458221Y763372D01*
X458583Y763449D01*
X458945Y763641D01*
X459151Y763871D01*
X459203Y764139D01*
X459100Y764446D01*
X458841Y764676D01*
X458376Y764906D01*
G01X459926Y766587D02*
X460185Y766856D01*
X460288Y767162D01*
X460185Y767469D01*
X459875Y767737D01*
X459410Y767929D01*
X458945Y768006D01*
X458376D01*
X457911Y767929D01*
X457498Y767737D01*
X457291Y767507D01*
X457188Y767239D01*
X457291Y766932D01*
X457498Y766702D01*
X457808Y766549D01*
X458221Y766472D01*
X458583Y766549D01*
X458945Y766741D01*
X459151Y766971D01*
X459203Y767239D01*
X459100Y767546D01*
X458841Y767776D01*
X458376Y768006D01*
G01X460288Y770339D02*
X457188D01*
X457808Y769879D01*
G01X460288D02*
Y770799D01*
G01X451748Y761322D02*
X448648D01*
Y762281D01*
X448803Y762587D01*
X449010Y762779D01*
X449423Y762856D01*
X449836Y762779D01*
X450095Y762549D01*
X450250Y762281D01*
Y761322D01*
G01Y762281D02*
X451748Y762856D01*
G01X451386Y764537D02*
X451645Y764806D01*
X451748Y765112D01*
X451645Y765419D01*
X451335Y765687D01*
X450870Y765879D01*
X450405Y765956D01*
X449836D01*
X449371Y765879D01*
X448958Y765687D01*
X448751Y765457D01*
X448648Y765189D01*
X448751Y764882D01*
X448958Y764652D01*
X449268Y764499D01*
X449681Y764422D01*
X450043Y764499D01*
X450405Y764691D01*
X450611Y764921D01*
X450663Y765189D01*
X450560Y765496D01*
X450301Y765726D01*
X449836Y765956D01*
G01X451386Y767637D02*
X451645Y767906D01*
X451748Y768212D01*
X451645Y768519D01*
X451335Y768787D01*
X450870Y768979D01*
X450405Y769056D01*
X449836D01*
X449371Y768979D01*
X448958Y768787D01*
X448751Y768557D01*
X448648Y768289D01*
X448751Y767982D01*
X448958Y767752D01*
X449268Y767599D01*
X449681Y767522D01*
X450043Y767599D01*
X450405Y767791D01*
X450611Y768021D01*
X450663Y768289D01*
X450560Y768596D01*
X450301Y768826D01*
X449836Y769056D01*
G01X451748Y771312D02*
X451076Y771389D01*
X450508Y771504D01*
X449991Y771657D01*
X449423Y771849D01*
X448648Y772156D01*
Y770622D01*
G01X473793Y-244364D02*
Y-236364D01*
X475793D01*
X476593Y-236764D01*
X477193Y-237297D01*
X477693Y-238097D01*
X478093Y-239031D01*
X478193Y-240364D01*
X478093Y-241697D01*
X477693Y-242631D01*
X477193Y-243431D01*
X476593Y-243964D01*
X475793Y-244364D01*
X473793D01*
G01X478545Y51500D02*
Y54600D01*
G01X480155D02*
Y51500D01*
G01Y53050D02*
X478545D01*
G01X482450Y51500D02*
Y54600D01*
X481990Y53980D01*
G01Y51500D02*
X482910D01*
G01X485550Y54600D02*
X485243Y54497D01*
X485013Y54238D01*
X484860Y53928D01*
X484745Y53515D01*
X484707Y53050D01*
X484745Y52585D01*
X484860Y52172D01*
X485013Y51862D01*
X485243Y51603D01*
X485550Y51500D01*
X485857Y51603D01*
X486087Y51862D01*
X486240Y52172D01*
X486355Y52585D01*
X486393Y53050D01*
X486355Y53515D01*
X486240Y53928D01*
X486087Y54238D01*
X485857Y54497D01*
X485550Y54600D01*
G01X466292Y76597D02*
Y73397D01*
G01X471452Y68716D02*
X471297Y68486D01*
X471194Y68218D01*
Y67911D01*
X471349Y67566D01*
X471607Y67298D01*
X471917Y67106D01*
X472434Y66953D01*
X472899Y66915D01*
X473364Y66991D01*
X473674Y67106D01*
X473984Y67336D01*
X474191Y67605D01*
X474294Y67873D01*
Y68141D01*
X474191Y68410D01*
X474036Y68640D01*
X473829Y68831D01*
G01X474294Y70973D02*
X471194D01*
X471814Y70513D01*
G01X474294D02*
Y71433D01*
G01X473932Y73421D02*
X474191Y73690D01*
X474294Y73996D01*
X474191Y74303D01*
X473881Y74571D01*
X473416Y74763D01*
X472951Y74840D01*
X472382D01*
X471917Y74763D01*
X471504Y74571D01*
X471297Y74341D01*
X471194Y74073D01*
X471297Y73766D01*
X471504Y73536D01*
X471814Y73383D01*
X472227Y73306D01*
X472589Y73383D01*
X472951Y73575D01*
X473157Y73805D01*
X473209Y74073D01*
X473106Y74380D01*
X472847Y74610D01*
X472382Y74840D01*
G01X474294Y77173D02*
X474242Y77441D01*
X474087Y77748D01*
X473829Y77940D01*
X473467Y78016D01*
X473106Y77940D01*
X472796Y77710D01*
X472641Y77365D01*
Y76981D01*
X472537Y76751D01*
X472279Y76560D01*
X471917Y76483D01*
X471556Y76598D01*
X471297Y76866D01*
X471194Y77173D01*
X471297Y77480D01*
X471556Y77748D01*
X471917Y77863D01*
X472279Y77786D01*
X472537Y77595D01*
X472641Y77365D01*
Y76981D01*
X472796Y76636D01*
X473106Y76406D01*
X473467Y76330D01*
X473829Y76406D01*
X474087Y76598D01*
X474242Y76905D01*
X474294Y77173D01*
G01X467465Y68716D02*
X467310Y68486D01*
X467207Y68218D01*
Y67911D01*
X467362Y67566D01*
X467620Y67298D01*
X467930Y67106D01*
X468447Y66953D01*
X468912Y66915D01*
X469377Y66991D01*
X469687Y67106D01*
X469997Y67336D01*
X470204Y67605D01*
X470307Y67873D01*
Y68141D01*
X470204Y68410D01*
X470049Y68640D01*
X469842Y68831D01*
G01X470307Y70973D02*
X470255Y71241D01*
X470100Y71548D01*
X469842Y71740D01*
X469480Y71816D01*
X469119Y71740D01*
X468809Y71510D01*
X468654Y71165D01*
Y70781D01*
X468550Y70551D01*
X468292Y70360D01*
X467930Y70283D01*
X467569Y70398D01*
X467310Y70666D01*
X467207Y70973D01*
X467310Y71280D01*
X467569Y71548D01*
X467930Y71663D01*
X468292Y71586D01*
X468550Y71395D01*
X468654Y71165D01*
Y70781D01*
X468809Y70436D01*
X469119Y70206D01*
X469480Y70130D01*
X469842Y70206D01*
X470100Y70398D01*
X470255Y70705D01*
X470307Y70973D01*
G01X469015Y73345D02*
X468654Y73613D01*
X468447Y73843D01*
X468344Y74150D01*
X468447Y74418D01*
X468654Y74610D01*
X468964Y74763D01*
X469325Y74801D01*
X469635Y74763D01*
X469945Y74610D01*
X470204Y74380D01*
X470307Y74111D01*
X470204Y73805D01*
X469894Y73536D01*
X469429Y73383D01*
X468912Y73345D01*
X468240Y73421D01*
X467879Y73536D01*
X467517Y73728D01*
X467259Y73996D01*
X467207Y74265D01*
X467310Y74533D01*
X467569Y74725D01*
G01X467207Y77173D02*
X467310Y76866D01*
X467569Y76636D01*
X467879Y76483D01*
X468292Y76368D01*
X468757Y76330D01*
X469222Y76368D01*
X469635Y76483D01*
X469945Y76636D01*
X470204Y76866D01*
X470307Y77173D01*
X470204Y77480D01*
X469945Y77710D01*
X469635Y77863D01*
X469222Y77978D01*
X468757Y78016D01*
X468292Y77978D01*
X467879Y77863D01*
X467569Y77710D01*
X467310Y77480D01*
X467207Y77173D01*
G01X478359Y67106D02*
X475259D01*
Y68065D01*
X475414Y68371D01*
X475621Y68563D01*
X476034Y68640D01*
X476447Y68563D01*
X476706Y68333D01*
X476861Y68065D01*
Y67106D01*
G01Y68065D02*
X478359Y68640D01*
G01Y70973D02*
X475259D01*
X475879Y70513D01*
G01X478359D02*
Y71433D01*
G01Y74073D02*
X475259D01*
X475879Y73613D01*
G01X478359D02*
Y74533D01*
G01X475776Y76445D02*
X475466Y76675D01*
X475311Y76943D01*
X475259Y77250D01*
X475362Y77633D01*
X475621Y77901D01*
X475931Y77978D01*
X476241Y77940D01*
X476499Y77786D01*
X477016Y77020D01*
X477377Y76675D01*
X477894Y76445D01*
X478359Y76368D01*
Y77978D01*
G01X477067Y79545D02*
X476706Y79813D01*
X476499Y80043D01*
X476396Y80350D01*
X476499Y80618D01*
X476706Y80810D01*
X477016Y80963D01*
X477377Y81001D01*
X477687Y80963D01*
X477997Y80810D01*
X478256Y80580D01*
X478359Y80311D01*
X478256Y80005D01*
X477946Y79736D01*
X477481Y79583D01*
X476964Y79545D01*
X476292Y79621D01*
X475931Y79736D01*
X475569Y79928D01*
X475311Y80196D01*
X475259Y80465D01*
X475362Y80733D01*
X475621Y80925D01*
G01X466328Y92274D02*
X466098Y92429D01*
X465830Y92532D01*
X465523D01*
X465178Y92377D01*
X464910Y92119D01*
X464718Y91809D01*
X464565Y91292D01*
X464527Y90827D01*
X464603Y90362D01*
X464718Y90052D01*
X464948Y89742D01*
X465217Y89535D01*
X465485Y89432D01*
X465753D01*
X466022Y89535D01*
X466252Y89690D01*
X466443Y89897D01*
G01X468585Y89432D02*
X468853Y89484D01*
X469160Y89639D01*
X469352Y89897D01*
X469428Y90259D01*
X469352Y90620D01*
X469122Y90930D01*
X468777Y91085D01*
X468393D01*
X468163Y91189D01*
X467972Y91447D01*
X467895Y91809D01*
X468010Y92170D01*
X468278Y92429D01*
X468585Y92532D01*
X468892Y92429D01*
X469160Y92170D01*
X469275Y91809D01*
X469198Y91447D01*
X469007Y91189D01*
X468777Y91085D01*
X468393D01*
X468048Y90930D01*
X467818Y90620D01*
X467742Y90259D01*
X467818Y89897D01*
X468010Y89639D01*
X468317Y89484D01*
X468585Y89432D01*
G01X470842Y89897D02*
X471072Y89639D01*
X471340Y89484D01*
X471685Y89432D01*
X472030Y89535D01*
X472298Y89742D01*
X472490Y90104D01*
X472528Y90517D01*
X472452Y90930D01*
X472260Y91189D01*
X471992Y91395D01*
X471723Y91447D01*
X471455Y91395D01*
X471110Y91189D01*
X471225Y92532D01*
X472260D01*
G01X473942Y89897D02*
X474172Y89639D01*
X474440Y89484D01*
X474785Y89432D01*
X475130Y89535D01*
X475398Y89742D01*
X475590Y90104D01*
X475628Y90517D01*
X475552Y90930D01*
X475360Y91189D01*
X475092Y91395D01*
X474823Y91447D01*
X474555Y91395D01*
X474210Y91189D01*
X474325Y92532D01*
X475360D01*
G01X464718Y85321D02*
Y88421D01*
X465677D01*
X465983Y88266D01*
X466175Y88059D01*
X466252Y87646D01*
X466175Y87233D01*
X465945Y86974D01*
X465677Y86819D01*
X464718D01*
G01X465677D02*
X466252Y85321D01*
G01X468585D02*
Y88421D01*
X468125Y87801D01*
G01Y85321D02*
X469045D01*
G01X471685D02*
Y88421D01*
X471225Y87801D01*
G01Y85321D02*
X472145D01*
G01X474057Y87904D02*
X474287Y88214D01*
X474555Y88369D01*
X474862Y88421D01*
X475245Y88318D01*
X475513Y88059D01*
X475590Y87749D01*
X475552Y87439D01*
X475398Y87181D01*
X474632Y86664D01*
X474287Y86303D01*
X474057Y85786D01*
X473980Y85321D01*
X475590D01*
G01X477042Y85786D02*
X477272Y85528D01*
X477540Y85373D01*
X477885Y85321D01*
X478230Y85424D01*
X478498Y85631D01*
X478690Y85993D01*
X478728Y86406D01*
X478652Y86819D01*
X478460Y87078D01*
X478192Y87284D01*
X477923Y87336D01*
X477655Y87284D01*
X477310Y87078D01*
X477425Y88421D01*
X478460D01*
G01X469155Y100347D02*
Y97147D01*
G01X466055Y100247D02*
Y97247D01*
G01X474577Y105281D02*
X471477D01*
Y106047D01*
X471632Y106354D01*
X471839Y106584D01*
X472149Y106776D01*
X472510Y106929D01*
X473027Y106967D01*
X473544Y106929D01*
X473905Y106776D01*
X474215Y106584D01*
X474422Y106354D01*
X474577Y106047D01*
Y105281D01*
G01X473285Y108496D02*
X472924Y108764D01*
X472717Y108994D01*
X472614Y109301D01*
X472717Y109569D01*
X472924Y109761D01*
X473234Y109914D01*
X473595Y109952D01*
X473905Y109914D01*
X474215Y109761D01*
X474474Y109531D01*
X474577Y109262D01*
X474474Y108956D01*
X474164Y108687D01*
X473699Y108534D01*
X473182Y108496D01*
X472510Y108572D01*
X472149Y108687D01*
X471787Y108879D01*
X471529Y109147D01*
X471477Y109416D01*
X471580Y109684D01*
X471839Y109876D01*
G01X481070Y100470D02*
X475670D01*
G01X480339Y107589D02*
X476401D01*
G01Y109951D02*
X478370Y107983D01*
G01D02*
X480339Y109951D01*
G01X481070Y102270D02*
X475670D01*
G01D02*
Y115270D01*
G01X481070Y101670D02*
X475670D01*
G01Y101070D02*
X481070D01*
G01X475670Y100470D02*
Y102270D01*
G01X469151Y96343D02*
Y93143D01*
G01X467394Y104156D02*
X464294D01*
Y105115D01*
X464449Y105421D01*
X464656Y105613D01*
X465069Y105690D01*
X465482Y105613D01*
X465741Y105383D01*
X465896Y105115D01*
Y104156D01*
G01Y105115D02*
X467394Y105690D01*
G01Y108023D02*
X464294D01*
X464914Y107563D01*
G01X467394D02*
Y108483D01*
G01Y111123D02*
X464294D01*
X464914Y110663D01*
G01X467394D02*
Y111583D01*
G01X464811Y113495D02*
X464501Y113725D01*
X464346Y113993D01*
X464294Y114300D01*
X464397Y114683D01*
X464656Y114951D01*
X464966Y115028D01*
X465276Y114990D01*
X465534Y114836D01*
X466051Y114070D01*
X466412Y113725D01*
X466929Y113495D01*
X467394Y113418D01*
Y115028D01*
G01Y117783D02*
X464294D01*
X466516Y116365D01*
Y118281D01*
G01X480339Y109951D02*
X476401D01*
G01X475670Y115270D02*
X481070D01*
G01X472734Y129585D02*
X469634D01*
Y130544D01*
X469789Y130850D01*
X469996Y131042D01*
X470409Y131119D01*
X470822Y131042D01*
X471081Y130812D01*
X471236Y130544D01*
Y129585D01*
G01Y130544D02*
X472734Y131119D01*
G01Y133452D02*
X472682Y133720D01*
X472527Y134027D01*
X472269Y134219D01*
X471907Y134295D01*
X471546Y134219D01*
X471236Y133989D01*
X471081Y133644D01*
Y133260D01*
X470977Y133030D01*
X470719Y132839D01*
X470357Y132762D01*
X469996Y132877D01*
X469737Y133145D01*
X469634Y133452D01*
X469737Y133759D01*
X469996Y134027D01*
X470357Y134142D01*
X470719Y134065D01*
X470977Y133874D01*
X471081Y133644D01*
Y133260D01*
X471236Y132915D01*
X471546Y132685D01*
X471907Y132609D01*
X472269Y132685D01*
X472527Y132877D01*
X472682Y133184D01*
X472734Y133452D01*
G01Y136552D02*
X469634D01*
X470254Y136092D01*
G01X472734D02*
Y137012D01*
G01X472269Y138809D02*
X472527Y139039D01*
X472682Y139307D01*
X472734Y139652D01*
X472631Y139997D01*
X472424Y140265D01*
X472062Y140457D01*
X471649Y140495D01*
X471236Y140419D01*
X470977Y140227D01*
X470771Y139959D01*
X470719Y139690D01*
X470771Y139422D01*
X470977Y139077D01*
X469634Y139192D01*
Y140227D01*
G01X464874Y181313D02*
Y152967D01*
G01X478005Y154925D02*
X472005D01*
G01X465361Y146262D02*
Y149362D01*
X466320D01*
X466626Y149207D01*
X466818Y149000D01*
X466895Y148587D01*
X466818Y148174D01*
X466588Y147915D01*
X466320Y147760D01*
X465361D01*
G01X466320D02*
X466895Y146262D01*
G01X468500Y147554D02*
X468768Y147915D01*
X468998Y148122D01*
X469305Y148225D01*
X469573Y148122D01*
X469765Y147915D01*
X469918Y147605D01*
X469956Y147244D01*
X469918Y146934D01*
X469765Y146624D01*
X469535Y146365D01*
X469266Y146262D01*
X468960Y146365D01*
X468691Y146675D01*
X468538Y147140D01*
X468500Y147657D01*
X468576Y148329D01*
X468691Y148690D01*
X468883Y149052D01*
X469151Y149310D01*
X469420Y149362D01*
X469688Y149259D01*
X469880Y149000D01*
G01X471600Y148845D02*
X471830Y149155D01*
X472098Y149310D01*
X472405Y149362D01*
X472788Y149259D01*
X473056Y149000D01*
X473133Y148690D01*
X473095Y148380D01*
X472941Y148122D01*
X472175Y147605D01*
X471830Y147244D01*
X471600Y146727D01*
X471523Y146262D01*
X473133D01*
G01X474585Y146727D02*
X474815Y146469D01*
X475083Y146314D01*
X475428Y146262D01*
X475773Y146365D01*
X476041Y146572D01*
X476233Y146934D01*
X476271Y147347D01*
X476195Y147760D01*
X476003Y148019D01*
X475735Y148225D01*
X475466Y148277D01*
X475198Y148225D01*
X474853Y148019D01*
X474968Y149362D01*
X476003D01*
G01X465361Y142281D02*
Y145381D01*
X466320D01*
X466626Y145226D01*
X466818Y145019D01*
X466895Y144606D01*
X466818Y144193D01*
X466588Y143934D01*
X466320Y143779D01*
X465361D01*
G01X466320D02*
X466895Y142281D01*
G01X468500Y143573D02*
X468768Y143934D01*
X468998Y144141D01*
X469305Y144244D01*
X469573Y144141D01*
X469765Y143934D01*
X469918Y143624D01*
X469956Y143263D01*
X469918Y142953D01*
X469765Y142643D01*
X469535Y142384D01*
X469266Y142281D01*
X468960Y142384D01*
X468691Y142694D01*
X468538Y143159D01*
X468500Y143676D01*
X468576Y144348D01*
X468691Y144709D01*
X468883Y145071D01*
X469151Y145329D01*
X469420Y145381D01*
X469688Y145278D01*
X469880Y145019D01*
G01X472328Y142281D02*
Y145381D01*
X471868Y144761D01*
G01Y142281D02*
X472788D01*
G01X475428D02*
X475696Y142333D01*
X476003Y142488D01*
X476195Y142746D01*
X476271Y143108D01*
X476195Y143469D01*
X475965Y143779D01*
X475620Y143934D01*
X475236D01*
X475006Y144038D01*
X474815Y144296D01*
X474738Y144658D01*
X474853Y145019D01*
X475121Y145278D01*
X475428Y145381D01*
X475735Y145278D01*
X476003Y145019D01*
X476118Y144658D01*
X476041Y144296D01*
X475850Y144038D01*
X475620Y143934D01*
X475236D01*
X474891Y143779D01*
X474661Y143469D01*
X474585Y143108D01*
X474661Y142746D01*
X474853Y142488D01*
X475160Y142333D01*
X475428Y142281D01*
G01X472148Y155635D02*
X465948D01*
G01D02*
Y158835D01*
G01X472148D02*
Y155635D01*
G01X469023Y152560D02*
Y158760D01*
G01X472223D02*
Y152560D01*
G01D02*
X469023D01*
G01X465743Y168209D02*
X465903Y167917D01*
X466117Y167751D01*
X466357Y167709D01*
X466570Y167751D01*
X466783Y167959D01*
X466917Y168209D01*
X466943Y168459D01*
X466890Y168751D01*
X466703Y168959D01*
X466517Y169042D01*
X466277D01*
G01X466517D02*
X466677Y169167D01*
X466810Y169376D01*
X466863Y169626D01*
X466810Y169876D01*
X466677Y170084D01*
X466437Y170209D01*
X466197Y170167D01*
X465957Y170001D01*
G01X478005Y164825D02*
X475005D01*
G01X472095Y161903D02*
X465895D01*
G01D02*
Y165103D01*
G01D02*
X472095D01*
G01D02*
Y161903D01*
G01X465948Y158835D02*
X472148D01*
G01X469023Y158760D02*
X472223D01*
G01X467150Y175766D02*
Y178866D01*
X465732Y176644D01*
X467648D01*
G01X477960Y174675D02*
X471960D01*
G01X465394Y184705D02*
Y189705D01*
G01X470084Y201024D02*
X466984D01*
Y201983D01*
X467139Y202289D01*
X467346Y202481D01*
X467759Y202558D01*
X468172Y202481D01*
X468431Y202251D01*
X468586Y201983D01*
Y201024D01*
G01Y201983D02*
X470084Y202558D01*
G01Y204891D02*
X466984D01*
X467604Y204431D01*
G01X470084D02*
Y205351D01*
G01Y207991D02*
X470032Y208259D01*
X469877Y208566D01*
X469619Y208758D01*
X469257Y208834D01*
X468896Y208758D01*
X468586Y208528D01*
X468431Y208183D01*
Y207799D01*
X468327Y207569D01*
X468069Y207378D01*
X467707Y207301D01*
X467346Y207416D01*
X467087Y207684D01*
X466984Y207991D01*
X467087Y208298D01*
X467346Y208566D01*
X467707Y208681D01*
X468069Y208604D01*
X468327Y208413D01*
X468431Y208183D01*
Y207799D01*
X468586Y207454D01*
X468896Y207224D01*
X469257Y207148D01*
X469619Y207224D01*
X469877Y207416D01*
X470032Y207723D01*
X470084Y207991D01*
G01Y211091D02*
X466984D01*
X467604Y210631D01*
G01X470084D02*
Y211551D01*
G01X472821Y193259D02*
X469621D01*
G01X472821Y199459D02*
Y193259D01*
G01X469621Y199459D02*
X472821D01*
G01X469621Y193259D02*
Y199459D01*
G01X481572Y191360D02*
X478472D01*
Y192319D01*
X478627Y192625D01*
X478834Y192817D01*
X479247Y192894D01*
X479660Y192817D01*
X479919Y192587D01*
X480074Y192319D01*
Y191360D01*
G01Y192319D02*
X481572Y192894D01*
G01X480280Y194499D02*
X479919Y194767D01*
X479712Y194997D01*
X479609Y195304D01*
X479712Y195572D01*
X479919Y195764D01*
X480229Y195917D01*
X480590Y195955D01*
X480900Y195917D01*
X481210Y195764D01*
X481469Y195534D01*
X481572Y195265D01*
X481469Y194959D01*
X481159Y194690D01*
X480694Y194537D01*
X480177Y194499D01*
X479505Y194575D01*
X479144Y194690D01*
X478782Y194882D01*
X478524Y195150D01*
X478472Y195419D01*
X478575Y195687D01*
X478834Y195879D01*
G01X481572Y198327D02*
X478472D01*
X479092Y197867D01*
G01X481572D02*
Y198787D01*
G01Y201350D02*
X480900Y201427D01*
X480332Y201542D01*
X479815Y201695D01*
X479247Y201887D01*
X478472Y202194D01*
Y200660D01*
G01X475619Y206857D02*
Y204635D01*
X475772Y204170D01*
X476079Y203860D01*
X476462Y203757D01*
X476845Y203860D01*
X477152Y204170D01*
X477305Y204635D01*
Y206857D01*
G01X479562Y203757D02*
Y206857D01*
X479102Y206237D01*
G01Y203757D02*
X480022D01*
G01X482662Y206857D02*
X482355Y206754D01*
X482125Y206495D01*
X481972Y206185D01*
X481857Y205772D01*
X481819Y205307D01*
X481857Y204842D01*
X481972Y204429D01*
X482125Y204119D01*
X482355Y203860D01*
X482662Y203757D01*
X482969Y203860D01*
X483199Y204119D01*
X483352Y204429D01*
X483467Y204842D01*
X483505Y205307D01*
X483467Y205772D01*
X483352Y206185D01*
X483199Y206495D01*
X482969Y206754D01*
X482662Y206857D01*
G01X484919Y204377D02*
X485149Y204015D01*
X485455Y203809D01*
X485800Y203757D01*
X486107Y203809D01*
X486414Y204067D01*
X486605Y204377D01*
X486644Y204687D01*
X486567Y205049D01*
X486299Y205307D01*
X486030Y205410D01*
X485685D01*
G01X486030D02*
X486260Y205565D01*
X486452Y205824D01*
X486529Y206134D01*
X486452Y206444D01*
X486260Y206702D01*
X485915Y206857D01*
X485570Y206805D01*
X485225Y206599D01*
G01X478279Y219146D02*
X478812D01*
Y218396D01*
X478652Y218146D01*
X478466Y217979D01*
X478199Y217896D01*
X477932Y217979D01*
X477746Y218146D01*
X477586Y218396D01*
X477479Y218688D01*
X477426Y219021D01*
Y219313D01*
X477479Y219563D01*
X477586Y219854D01*
X477746Y220104D01*
X477906Y220271D01*
X478119Y220396D01*
X478306D01*
X478519Y220313D01*
X478679Y220146D01*
G01X475634Y232735D02*
Y235835D01*
X476593D01*
X476899Y235680D01*
X477091Y235473D01*
X477168Y235060D01*
X477091Y234647D01*
X476861Y234388D01*
X476593Y234233D01*
X475634D01*
G01X476593D02*
X477168Y232735D01*
G01X479501D02*
Y235835D01*
X479041Y235215D01*
G01Y232735D02*
X479961D01*
G01X482601D02*
Y235835D01*
X482141Y235215D01*
G01Y232735D02*
X483061D01*
G01X484973Y234027D02*
X485241Y234388D01*
X485471Y234595D01*
X485778Y234698D01*
X486046Y234595D01*
X486238Y234388D01*
X486391Y234078D01*
X486429Y233717D01*
X486391Y233407D01*
X486238Y233097D01*
X486008Y232838D01*
X485739Y232735D01*
X485433Y232838D01*
X485164Y233148D01*
X485011Y233613D01*
X484973Y234130D01*
X485049Y234802D01*
X485164Y235163D01*
X485356Y235525D01*
X485624Y235783D01*
X485893Y235835D01*
X486161Y235732D01*
X486353Y235473D01*
G01X488073Y235318D02*
X488303Y235628D01*
X488571Y235783D01*
X488878Y235835D01*
X489261Y235732D01*
X489529Y235473D01*
X489606Y235163D01*
X489568Y234853D01*
X489414Y234595D01*
X488648Y234078D01*
X488303Y233717D01*
X488073Y233200D01*
X487996Y232735D01*
X489606D01*
G01X471945Y228493D02*
Y231593D01*
X472904D01*
X473210Y231438D01*
X473402Y231231D01*
X473479Y230818D01*
X473402Y230405D01*
X473172Y230146D01*
X472904Y229991D01*
X471945D01*
G01X472904D02*
X473479Y228493D01*
G01X475812D02*
Y231593D01*
X475352Y230973D01*
G01Y228493D02*
X476272D01*
G01X478184Y231076D02*
X478414Y231386D01*
X478682Y231541D01*
X478989Y231593D01*
X479372Y231490D01*
X479640Y231231D01*
X479717Y230921D01*
X479679Y230611D01*
X479525Y230353D01*
X478759Y229836D01*
X478414Y229475D01*
X478184Y228958D01*
X478107Y228493D01*
X479717D01*
G01X482012D02*
Y231593D01*
X481552Y230973D01*
G01Y228493D02*
X482472D01*
G01X485035D02*
X485112Y229165D01*
X485227Y229733D01*
X485380Y230250D01*
X485572Y230818D01*
X485879Y231593D01*
X484345D01*
G01X472080Y222119D02*
Y225219D01*
X473039D01*
X473345Y225064D01*
X473537Y224857D01*
X473614Y224444D01*
X473537Y224031D01*
X473307Y223772D01*
X473039Y223617D01*
X472080D01*
G01X473039D02*
X473614Y222119D01*
G01X475104Y222584D02*
X475334Y222326D01*
X475602Y222171D01*
X475947Y222119D01*
X476292Y222222D01*
X476560Y222429D01*
X476752Y222791D01*
X476790Y223204D01*
X476714Y223617D01*
X476522Y223876D01*
X476254Y224082D01*
X475985Y224134D01*
X475717Y224082D01*
X475372Y223876D01*
X475487Y225219D01*
X476522D01*
G01X478319Y224702D02*
X478549Y225012D01*
X478817Y225167D01*
X479124Y225219D01*
X479507Y225116D01*
X479775Y224857D01*
X479852Y224547D01*
X479814Y224237D01*
X479660Y223979D01*
X478894Y223462D01*
X478549Y223101D01*
X478319Y222584D01*
X478242Y222119D01*
X479852D01*
G01X482147D02*
Y225219D01*
X481687Y224599D01*
G01Y222119D02*
X482607D01*
G01X477493Y244269D02*
X477263Y244424D01*
X476995Y244527D01*
X476688D01*
X476343Y244372D01*
X476075Y244114D01*
X475883Y243804D01*
X475730Y243287D01*
X475692Y242822D01*
X475768Y242357D01*
X475883Y242047D01*
X476113Y241737D01*
X476382Y241530D01*
X476650Y241427D01*
X476918D01*
X477187Y241530D01*
X477417Y241685D01*
X477608Y241892D01*
G01X478907Y242047D02*
X479137Y241685D01*
X479443Y241479D01*
X479788Y241427D01*
X480095Y241479D01*
X480402Y241737D01*
X480593Y242047D01*
X480632Y242357D01*
X480555Y242719D01*
X480287Y242977D01*
X480018Y243080D01*
X479673D01*
G01X480018D02*
X480248Y243235D01*
X480440Y243494D01*
X480517Y243804D01*
X480440Y244114D01*
X480248Y244372D01*
X479903Y244527D01*
X479558Y244475D01*
X479213Y244269D01*
G01X482007Y242047D02*
X482237Y241685D01*
X482543Y241479D01*
X482888Y241427D01*
X483195Y241479D01*
X483502Y241737D01*
X483693Y242047D01*
X483732Y242357D01*
X483655Y242719D01*
X483387Y242977D01*
X483118Y243080D01*
X482773D01*
G01X483118D02*
X483348Y243235D01*
X483540Y243494D01*
X483617Y243804D01*
X483540Y244114D01*
X483348Y244372D01*
X483003Y244527D01*
X482658Y244475D01*
X482313Y244269D01*
G01X485107Y241892D02*
X485337Y241634D01*
X485605Y241479D01*
X485950Y241427D01*
X486295Y241530D01*
X486563Y241737D01*
X486755Y242099D01*
X486793Y242512D01*
X486717Y242925D01*
X486525Y243184D01*
X486257Y243390D01*
X485988Y243442D01*
X485720Y243390D01*
X485375Y243184D01*
X485490Y244527D01*
X486525D01*
G01X467549Y272792D02*
Y275292D01*
X467229Y274792D01*
G01Y272792D02*
X467869D01*
G01X469295Y269767D02*
Y284767D01*
G01X482295Y269767D02*
X469295D01*
G01X469191Y288835D02*
Y286613D01*
X469344Y286148D01*
X469651Y285838D01*
X470034Y285735D01*
X470417Y285838D01*
X470724Y286148D01*
X470877Y286613D01*
Y288835D01*
G01X472291Y286355D02*
X472521Y285993D01*
X472827Y285787D01*
X473172Y285735D01*
X473479Y285787D01*
X473786Y286045D01*
X473977Y286355D01*
X474016Y286665D01*
X473939Y287027D01*
X473671Y287285D01*
X473402Y287388D01*
X473057D01*
G01X473402D02*
X473632Y287543D01*
X473824Y287802D01*
X473901Y288112D01*
X473824Y288422D01*
X473632Y288680D01*
X473287Y288835D01*
X472942Y288783D01*
X472597Y288577D01*
G01X469295Y284767D02*
X482295D01*
G01X476702Y350947D02*
G02I-3544J0D01*
G01X471813Y414376D02*
Y417476D01*
X472733D01*
X473040Y417321D01*
X473270Y416959D01*
X473347Y416546D01*
X473270Y416133D01*
X473078Y415823D01*
X472733Y415668D01*
X471813D01*
G01X476523Y417218D02*
X476293Y417373D01*
X476025Y417476D01*
X475718D01*
X475373Y417321D01*
X475105Y417063D01*
X474913Y416753D01*
X474760Y416236D01*
X474722Y415771D01*
X474798Y415306D01*
X474913Y414996D01*
X475143Y414686D01*
X475412Y414479D01*
X475680Y414376D01*
X475948D01*
X476217Y414479D01*
X476447Y414634D01*
X476638Y414841D01*
G01X478780Y414376D02*
Y417476D01*
X478320Y416856D01*
G01Y414376D02*
X479240D01*
G01X481880Y417476D02*
X481573Y417373D01*
X481343Y417114D01*
X481190Y416804D01*
X481075Y416391D01*
X481037Y415926D01*
X481075Y415461D01*
X481190Y415048D01*
X481343Y414738D01*
X481573Y414479D01*
X481880Y414376D01*
X482187Y414479D01*
X482417Y414738D01*
X482570Y415048D01*
X482685Y415461D01*
X482723Y415926D01*
X482685Y416391D01*
X482570Y416804D01*
X482417Y417114D01*
X482187Y417373D01*
X481880Y417476D01*
G01X484980D02*
X484673Y417373D01*
X484443Y417114D01*
X484290Y416804D01*
X484175Y416391D01*
X484137Y415926D01*
X484175Y415461D01*
X484290Y415048D01*
X484443Y414738D01*
X484673Y414479D01*
X484980Y414376D01*
X485287Y414479D01*
X485517Y414738D01*
X485670Y415048D01*
X485785Y415461D01*
X485823Y415926D01*
X485785Y416391D01*
X485670Y416804D01*
X485517Y417114D01*
X485287Y417373D01*
X484980Y417476D01*
G01X470012Y427563D02*
Y409847D01*
G01X470973Y432217D02*
Y435317D01*
X471893D01*
X472200Y435162D01*
X472430Y434800D01*
X472507Y434387D01*
X472430Y433974D01*
X472238Y433664D01*
X471893Y433509D01*
X470973D01*
G01X475683Y435059D02*
X475453Y435214D01*
X475185Y435317D01*
X474878D01*
X474533Y435162D01*
X474265Y434904D01*
X474073Y434594D01*
X473920Y434077D01*
X473882Y433612D01*
X473958Y433147D01*
X474073Y432837D01*
X474303Y432527D01*
X474572Y432320D01*
X474840Y432217D01*
X475108D01*
X475377Y432320D01*
X475607Y432475D01*
X475798Y432682D01*
G01X477288Y432579D02*
X477557Y432320D01*
X477863Y432217D01*
X478170Y432320D01*
X478438Y432630D01*
X478630Y433095D01*
X478707Y433560D01*
Y434129D01*
X478630Y434594D01*
X478438Y435007D01*
X478208Y435214D01*
X477940Y435317D01*
X477633Y435214D01*
X477403Y435007D01*
X477250Y434697D01*
X477173Y434284D01*
X477250Y433922D01*
X477442Y433560D01*
X477672Y433354D01*
X477940Y433302D01*
X478247Y433405D01*
X478477Y433664D01*
X478707Y434129D01*
G01X480388Y432579D02*
X480657Y432320D01*
X480963Y432217D01*
X481270Y432320D01*
X481538Y432630D01*
X481730Y433095D01*
X481807Y433560D01*
Y434129D01*
X481730Y434594D01*
X481538Y435007D01*
X481308Y435214D01*
X481040Y435317D01*
X480733Y435214D01*
X480503Y435007D01*
X480350Y434697D01*
X480273Y434284D01*
X480350Y433922D01*
X480542Y433560D01*
X480772Y433354D01*
X481040Y433302D01*
X481347Y433405D01*
X481577Y433664D01*
X481807Y434129D01*
G01X470012Y447563D02*
Y429847D01*
G01X473338Y483718D02*
X470238D01*
Y484638D01*
X470393Y484945D01*
X470755Y485175D01*
X471168Y485252D01*
X471581Y485175D01*
X471891Y484983D01*
X472046Y484638D01*
Y483718D01*
G01X470496Y488428D02*
X470341Y488198D01*
X470238Y487930D01*
Y487623D01*
X470393Y487278D01*
X470651Y487010D01*
X470961Y486818D01*
X471478Y486665D01*
X471943Y486627D01*
X472408Y486703D01*
X472718Y486818D01*
X473028Y487048D01*
X473235Y487317D01*
X473338Y487585D01*
Y487853D01*
X473235Y488122D01*
X473080Y488352D01*
X472873Y488543D01*
G01X473338Y490685D02*
X473286Y490953D01*
X473131Y491260D01*
X472873Y491452D01*
X472511Y491528D01*
X472150Y491452D01*
X471840Y491222D01*
X471685Y490877D01*
Y490493D01*
X471581Y490263D01*
X471323Y490072D01*
X470961Y489995D01*
X470600Y490110D01*
X470341Y490378D01*
X470238Y490685D01*
X470341Y490992D01*
X470600Y491260D01*
X470961Y491375D01*
X471323Y491298D01*
X471581Y491107D01*
X471685Y490877D01*
Y490493D01*
X471840Y490148D01*
X472150Y489918D01*
X472511Y489842D01*
X472873Y489918D01*
X473131Y490110D01*
X473286Y490417D01*
X473338Y490685D01*
G01X472976Y493133D02*
X473235Y493402D01*
X473338Y493708D01*
X473235Y494015D01*
X472925Y494283D01*
X472460Y494475D01*
X471995Y494552D01*
X471426D01*
X470961Y494475D01*
X470548Y494283D01*
X470341Y494053D01*
X470238Y493785D01*
X470341Y493478D01*
X470548Y493248D01*
X470858Y493095D01*
X471271Y493018D01*
X471633Y493095D01*
X471995Y493287D01*
X472201Y493517D01*
X472253Y493785D01*
X472150Y494092D01*
X471891Y494322D01*
X471426Y494552D01*
G01X477338Y483718D02*
X474238D01*
Y484638D01*
X474393Y484945D01*
X474755Y485175D01*
X475168Y485252D01*
X475581Y485175D01*
X475891Y484983D01*
X476046Y484638D01*
Y483718D01*
G01X474496Y488428D02*
X474341Y488198D01*
X474238Y487930D01*
Y487623D01*
X474393Y487278D01*
X474651Y487010D01*
X474961Y486818D01*
X475478Y486665D01*
X475943Y486627D01*
X476408Y486703D01*
X476718Y486818D01*
X477028Y487048D01*
X477235Y487317D01*
X477338Y487585D01*
Y487853D01*
X477235Y488122D01*
X477080Y488352D01*
X476873Y488543D01*
G01X476976Y490033D02*
X477235Y490302D01*
X477338Y490608D01*
X477235Y490915D01*
X476925Y491183D01*
X476460Y491375D01*
X475995Y491452D01*
X475426D01*
X474961Y491375D01*
X474548Y491183D01*
X474341Y490953D01*
X474238Y490685D01*
X474341Y490378D01*
X474548Y490148D01*
X474858Y489995D01*
X475271Y489918D01*
X475633Y489995D01*
X475995Y490187D01*
X476201Y490417D01*
X476253Y490685D01*
X476150Y490992D01*
X475891Y491222D01*
X475426Y491452D01*
G01X477338Y494245D02*
X474238D01*
X476460Y492827D01*
Y494743D01*
G01X481338Y483718D02*
X478238D01*
Y484638D01*
X478393Y484945D01*
X478755Y485175D01*
X479168Y485252D01*
X479581Y485175D01*
X479891Y484983D01*
X480046Y484638D01*
Y483718D01*
G01X478496Y488428D02*
X478341Y488198D01*
X478238Y487930D01*
Y487623D01*
X478393Y487278D01*
X478651Y487010D01*
X478961Y486818D01*
X479478Y486665D01*
X479943Y486627D01*
X480408Y486703D01*
X480718Y486818D01*
X481028Y487048D01*
X481235Y487317D01*
X481338Y487585D01*
Y487853D01*
X481235Y488122D01*
X481080Y488352D01*
X480873Y488543D01*
G01X480976Y490033D02*
X481235Y490302D01*
X481338Y490608D01*
X481235Y490915D01*
X480925Y491183D01*
X480460Y491375D01*
X479995Y491452D01*
X479426D01*
X478961Y491375D01*
X478548Y491183D01*
X478341Y490953D01*
X478238Y490685D01*
X478341Y490378D01*
X478548Y490148D01*
X478858Y489995D01*
X479271Y489918D01*
X479633Y489995D01*
X479995Y490187D01*
X480201Y490417D01*
X480253Y490685D01*
X480150Y490992D01*
X479891Y491222D01*
X479426Y491452D01*
G01X481338Y493785D02*
X478238D01*
X478858Y493325D01*
G01X481338D02*
Y494245D01*
G01X468955Y494121D02*
Y476721D01*
G01X471690Y498297D02*
X468590D01*
Y499217D01*
X468745Y499524D01*
X469107Y499754D01*
X469520Y499831D01*
X469933Y499754D01*
X470243Y499562D01*
X470398Y499217D01*
Y498297D01*
G01X471690Y501397D02*
X468590D01*
Y502356D01*
X468745Y502662D01*
X468952Y502854D01*
X469365Y502931D01*
X469778Y502854D01*
X470037Y502624D01*
X470192Y502356D01*
Y501397D01*
G01Y502356D02*
X471690Y502931D01*
G01Y505724D02*
X468590D01*
X470812Y504306D01*
Y506222D01*
G01X471328Y507712D02*
X471587Y507981D01*
X471690Y508287D01*
X471587Y508594D01*
X471277Y508862D01*
X470812Y509054D01*
X470347Y509131D01*
X469778D01*
X469313Y509054D01*
X468900Y508862D01*
X468693Y508632D01*
X468590Y508364D01*
X468693Y508057D01*
X468900Y507827D01*
X469210Y507674D01*
X469623Y507597D01*
X469985Y507674D01*
X470347Y507866D01*
X470553Y508096D01*
X470605Y508364D01*
X470502Y508671D01*
X470243Y508901D01*
X469778Y509131D01*
G01X466044Y514162D02*
Y496762D01*
G01X474164Y517401D02*
X471064D01*
Y518321D01*
X471219Y518628D01*
X471581Y518858D01*
X471994Y518935D01*
X472407Y518858D01*
X472717Y518666D01*
X472872Y518321D01*
Y517401D01*
G01X471322Y522111D02*
X471167Y521881D01*
X471064Y521613D01*
Y521306D01*
X471219Y520961D01*
X471477Y520693D01*
X471787Y520501D01*
X472304Y520348D01*
X472769Y520310D01*
X473234Y520386D01*
X473544Y520501D01*
X473854Y520731D01*
X474061Y521000D01*
X474164Y521268D01*
Y521536D01*
X474061Y521805D01*
X473906Y522035D01*
X473699Y522226D01*
G01X473802Y523716D02*
X474061Y523985D01*
X474164Y524291D01*
X474061Y524598D01*
X473751Y524866D01*
X473286Y525058D01*
X472821Y525135D01*
X472252D01*
X471787Y525058D01*
X471374Y524866D01*
X471167Y524636D01*
X471064Y524368D01*
X471167Y524061D01*
X471374Y523831D01*
X471684Y523678D01*
X472097Y523601D01*
X472459Y523678D01*
X472821Y523870D01*
X473027Y524100D01*
X473079Y524368D01*
X472976Y524675D01*
X472717Y524905D01*
X472252Y525135D01*
G01X474164Y527468D02*
X474112Y527736D01*
X473957Y528043D01*
X473699Y528235D01*
X473337Y528311D01*
X472976Y528235D01*
X472666Y528005D01*
X472511Y527660D01*
Y527276D01*
X472407Y527046D01*
X472149Y526855D01*
X471787Y526778D01*
X471426Y526893D01*
X471167Y527161D01*
X471064Y527468D01*
X471167Y527775D01*
X471426Y528043D01*
X471787Y528158D01*
X472149Y528081D01*
X472407Y527890D01*
X472511Y527660D01*
Y527276D01*
X472666Y526931D01*
X472976Y526701D01*
X473337Y526625D01*
X473699Y526701D01*
X473957Y526893D01*
X474112Y527200D01*
X474164Y527468D01*
G01X469947Y517401D02*
X466847D01*
Y518321D01*
X467002Y518628D01*
X467364Y518858D01*
X467777Y518935D01*
X468190Y518858D01*
X468500Y518666D01*
X468655Y518321D01*
Y517401D01*
G01X469947Y520501D02*
X466847D01*
Y521460D01*
X467002Y521766D01*
X467209Y521958D01*
X467622Y522035D01*
X468035Y521958D01*
X468294Y521728D01*
X468449Y521460D01*
Y520501D01*
G01Y521460D02*
X469947Y522035D01*
G01X469482Y523525D02*
X469740Y523755D01*
X469895Y524023D01*
X469947Y524368D01*
X469844Y524713D01*
X469637Y524981D01*
X469275Y525173D01*
X468862Y525211D01*
X468449Y525135D01*
X468190Y524943D01*
X467984Y524675D01*
X467932Y524406D01*
X467984Y524138D01*
X468190Y523793D01*
X466847Y523908D01*
Y524943D01*
G01X469947Y527468D02*
X469895Y527736D01*
X469740Y528043D01*
X469482Y528235D01*
X469120Y528311D01*
X468759Y528235D01*
X468449Y528005D01*
X468294Y527660D01*
Y527276D01*
X468190Y527046D01*
X467932Y526855D01*
X467570Y526778D01*
X467209Y526893D01*
X466950Y527161D01*
X466847Y527468D01*
X466950Y527775D01*
X467209Y528043D01*
X467570Y528158D01*
X467932Y528081D01*
X468190Y527890D01*
X468294Y527660D01*
Y527276D01*
X468449Y526931D01*
X468759Y526701D01*
X469120Y526625D01*
X469482Y526701D01*
X469740Y526893D01*
X469895Y527200D01*
X469947Y527468D01*
G01X463691Y533310D02*
Y539510D01*
G01X466891Y533310D02*
X463691D01*
G01X466891Y539510D02*
Y533310D01*
G01X469966Y540726D02*
X467466D01*
Y541366D01*
X467591Y541579D01*
X467883Y541739D01*
X468216Y541792D01*
X468549Y541739D01*
X468799Y541606D01*
X468924Y541366D01*
Y540726D01*
G01X467674Y544046D02*
X467549Y543886D01*
X467466Y543699D01*
Y543486D01*
X467591Y543246D01*
X467799Y543059D01*
X468049Y542926D01*
X468466Y542819D01*
X468841Y542792D01*
X469216Y542846D01*
X469466Y542926D01*
X469716Y543086D01*
X469883Y543272D01*
X469966Y543459D01*
Y543646D01*
X469883Y543832D01*
X469758Y543992D01*
X469591Y544126D01*
G01X469966Y545659D02*
X467466D01*
X467966Y545339D01*
G01X469966D02*
Y545979D01*
G01X467466Y547859D02*
X467549Y547646D01*
X467758Y547486D01*
X468008Y547379D01*
X468341Y547299D01*
X468716Y547272D01*
X469091Y547299D01*
X469424Y547379D01*
X469674Y547486D01*
X469883Y547646D01*
X469966Y547859D01*
X469883Y548072D01*
X469674Y548232D01*
X469424Y548339D01*
X469091Y548419D01*
X468716Y548446D01*
X468341Y548419D01*
X468008Y548339D01*
X467758Y548232D01*
X467549Y548072D01*
X467466Y547859D01*
G01X469966Y550059D02*
X469924Y550246D01*
X469799Y550459D01*
X469591Y550592D01*
X469299Y550646D01*
X469008Y550592D01*
X468758Y550432D01*
X468633Y550192D01*
Y549926D01*
X468549Y549766D01*
X468341Y549632D01*
X468049Y549579D01*
X467758Y549659D01*
X467549Y549846D01*
X467466Y550059D01*
X467549Y550272D01*
X467758Y550459D01*
X468049Y550539D01*
X468341Y550486D01*
X468549Y550352D01*
X468633Y550192D01*
Y549926D01*
X468758Y549686D01*
X469008Y549526D01*
X469299Y549472D01*
X469591Y549526D01*
X469799Y549659D01*
X469924Y549872D01*
X469966Y550059D01*
G01X468097Y536787D02*
Y539287D01*
X468737D01*
X468950Y539162D01*
X469110Y538870D01*
X469163Y538537D01*
X469110Y538204D01*
X468977Y537954D01*
X468737Y537829D01*
X468097D01*
G01X471417Y539079D02*
X471257Y539204D01*
X471070Y539287D01*
X470857D01*
X470617Y539162D01*
X470430Y538954D01*
X470297Y538704D01*
X470190Y538287D01*
X470163Y537912D01*
X470217Y537537D01*
X470297Y537287D01*
X470457Y537037D01*
X470643Y536870D01*
X470830Y536787D01*
X471017D01*
X471203Y536870D01*
X471363Y536995D01*
X471497Y537162D01*
G01X473030Y536787D02*
Y539287D01*
X472710Y538787D01*
G01Y536787D02*
X473350D01*
G01X475230Y539287D02*
X475017Y539204D01*
X474857Y538995D01*
X474750Y538745D01*
X474670Y538412D01*
X474643Y538037D01*
X474670Y537662D01*
X474750Y537329D01*
X474857Y537079D01*
X475017Y536870D01*
X475230Y536787D01*
X475443Y536870D01*
X475603Y537079D01*
X475710Y537329D01*
X475790Y537662D01*
X475817Y538037D01*
X475790Y538412D01*
X475710Y538745D01*
X475603Y538995D01*
X475443Y539204D01*
X475230Y539287D01*
G01X477430Y536787D02*
Y539287D01*
X477110Y538787D01*
G01Y536787D02*
X477750D01*
G01X473863Y540887D02*
X471363D01*
Y541527D01*
X471488Y541740D01*
X471780Y541900D01*
X472113Y541953D01*
X472446Y541900D01*
X472696Y541767D01*
X472821Y541527D01*
Y540887D01*
G01X471571Y544207D02*
X471446Y544047D01*
X471363Y543860D01*
Y543647D01*
X471488Y543407D01*
X471696Y543220D01*
X471946Y543087D01*
X472363Y542980D01*
X472738Y542953D01*
X473113Y543007D01*
X473363Y543087D01*
X473613Y543247D01*
X473780Y543433D01*
X473863Y543620D01*
Y543807D01*
X473780Y543993D01*
X473655Y544153D01*
X473488Y544287D01*
G01X473863Y545820D02*
X471363D01*
X471863Y545500D01*
G01X473863D02*
Y546140D01*
G01X471363Y548020D02*
X471446Y547807D01*
X471655Y547647D01*
X471905Y547540D01*
X472238Y547460D01*
X472613Y547433D01*
X472988Y547460D01*
X473321Y547540D01*
X473571Y547647D01*
X473780Y547807D01*
X473863Y548020D01*
X473780Y548233D01*
X473571Y548393D01*
X473321Y548500D01*
X472988Y548580D01*
X472613Y548607D01*
X472238Y548580D01*
X471905Y548500D01*
X471655Y548393D01*
X471446Y548233D01*
X471363Y548020D01*
G01X471780Y549713D02*
X471530Y549873D01*
X471405Y550060D01*
X471363Y550273D01*
X471446Y550540D01*
X471655Y550727D01*
X471905Y550780D01*
X472155Y550753D01*
X472363Y550647D01*
X472780Y550113D01*
X473071Y549873D01*
X473488Y549713D01*
X473863Y549660D01*
Y550780D01*
G01X466564Y540667D02*
X464064D01*
Y541307D01*
X464189Y541520D01*
X464481Y541680D01*
X464814Y541733D01*
X465147Y541680D01*
X465397Y541547D01*
X465522Y541307D01*
Y540667D01*
G01X466564Y542867D02*
X464064D01*
Y543533D01*
X464189Y543747D01*
X464356Y543880D01*
X464689Y543933D01*
X465022Y543880D01*
X465231Y543720D01*
X465356Y543533D01*
Y542867D01*
G01Y543533D02*
X466564Y543933D01*
G01X465522Y545093D02*
X465231Y545280D01*
X465064Y545440D01*
X464981Y545653D01*
X465064Y545840D01*
X465231Y545973D01*
X465481Y546080D01*
X465772Y546107D01*
X466022Y546080D01*
X466272Y545973D01*
X466481Y545813D01*
X466564Y545627D01*
X466481Y545413D01*
X466231Y545227D01*
X465856Y545120D01*
X465439Y545093D01*
X464897Y545147D01*
X464606Y545227D01*
X464314Y545360D01*
X464106Y545547D01*
X464064Y545733D01*
X464147Y545920D01*
X464356Y546053D01*
G01X466564Y547800D02*
X466522Y547987D01*
X466397Y548200D01*
X466189Y548333D01*
X465897Y548387D01*
X465606Y548333D01*
X465356Y548173D01*
X465231Y547933D01*
Y547667D01*
X465147Y547507D01*
X464939Y547373D01*
X464647Y547320D01*
X464356Y547400D01*
X464147Y547587D01*
X464064Y547800D01*
X464147Y548013D01*
X464356Y548200D01*
X464647Y548280D01*
X464939Y548227D01*
X465147Y548093D01*
X465231Y547933D01*
Y547667D01*
X465356Y547427D01*
X465606Y547267D01*
X465897Y547213D01*
X466189Y547267D01*
X466397Y547400D01*
X466522Y547613D01*
X466564Y547800D01*
G01X478484Y544547D02*
X475984D01*
Y545187D01*
X476109Y545400D01*
X476401Y545560D01*
X476734Y545613D01*
X477067Y545560D01*
X477317Y545427D01*
X477442Y545187D01*
Y544547D01*
G01X478484Y546747D02*
X475984D01*
Y547413D01*
X476109Y547627D01*
X476276Y547760D01*
X476609Y547813D01*
X476942Y547760D01*
X477151Y547600D01*
X477276Y547413D01*
Y546747D01*
G01Y547413D02*
X478484Y547813D01*
G01X477442Y548973D02*
X477151Y549160D01*
X476984Y549320D01*
X476901Y549533D01*
X476984Y549720D01*
X477151Y549853D01*
X477401Y549960D01*
X477692Y549987D01*
X477942Y549960D01*
X478192Y549853D01*
X478401Y549693D01*
X478484Y549507D01*
X478401Y549293D01*
X478151Y549107D01*
X477776Y549000D01*
X477359Y548973D01*
X476817Y549027D01*
X476526Y549107D01*
X476234Y549240D01*
X476026Y549427D01*
X475984Y549613D01*
X476067Y549800D01*
X476276Y549933D01*
G01X477442Y551173D02*
X477151Y551360D01*
X476984Y551520D01*
X476901Y551733D01*
X476984Y551920D01*
X477151Y552053D01*
X477401Y552160D01*
X477692Y552187D01*
X477942Y552160D01*
X478192Y552053D01*
X478401Y551893D01*
X478484Y551707D01*
X478401Y551493D01*
X478151Y551307D01*
X477776Y551200D01*
X477359Y551173D01*
X476817Y551227D01*
X476526Y551307D01*
X476234Y551440D01*
X476026Y551627D01*
X475984Y551813D01*
X476067Y552000D01*
X476276Y552133D01*
G01X463691Y539510D02*
X466891D01*
G01X475210Y565130D02*
Y579250D01*
G01X488140Y565130D02*
X475210D01*
G01X463997Y554597D02*
Y557097D01*
X464637D01*
X464850Y556972D01*
X465010Y556680D01*
X465063Y556347D01*
X465010Y556014D01*
X464877Y555764D01*
X464637Y555639D01*
X463997D01*
G01X467317Y556889D02*
X467157Y557014D01*
X466970Y557097D01*
X466757D01*
X466517Y556972D01*
X466330Y556764D01*
X466197Y556514D01*
X466090Y556097D01*
X466063Y555722D01*
X466117Y555347D01*
X466197Y555097D01*
X466357Y554847D01*
X466543Y554680D01*
X466730Y554597D01*
X466917D01*
X467103Y554680D01*
X467263Y554805D01*
X467397Y554972D01*
G01X468930Y554597D02*
Y557097D01*
X468610Y556597D01*
G01Y554597D02*
X469250D01*
G01X471130D02*
Y557097D01*
X470810Y556597D01*
G01Y554597D02*
X471450D01*
G01X473330Y557097D02*
X473117Y557014D01*
X472957Y556805D01*
X472850Y556555D01*
X472770Y556222D01*
X472743Y555847D01*
X472770Y555472D01*
X472850Y555139D01*
X472957Y554889D01*
X473117Y554680D01*
X473330Y554597D01*
X473543Y554680D01*
X473703Y554889D01*
X473810Y555139D01*
X473890Y555472D01*
X473917Y555847D01*
X473890Y556222D01*
X473810Y556555D01*
X473703Y556805D01*
X473543Y557014D01*
X473330Y557097D01*
G01X466753Y559907D02*
Y563007D01*
X467673D01*
X467980Y562852D01*
X468210Y562490D01*
X468287Y562077D01*
X468210Y561664D01*
X468018Y561354D01*
X467673Y561199D01*
X466753D01*
G01X471463Y562749D02*
X471233Y562904D01*
X470965Y563007D01*
X470658D01*
X470313Y562852D01*
X470045Y562594D01*
X469853Y562284D01*
X469700Y561767D01*
X469662Y561302D01*
X469738Y560837D01*
X469853Y560527D01*
X470083Y560217D01*
X470352Y560010D01*
X470620Y559907D01*
X470888D01*
X471157Y560010D01*
X471387Y560165D01*
X471578Y560372D01*
G01X473720Y559907D02*
Y563007D01*
X473260Y562387D01*
G01Y559907D02*
X474180D01*
G01X476820Y563007D02*
X476513Y562904D01*
X476283Y562645D01*
X476130Y562335D01*
X476015Y561922D01*
X475977Y561457D01*
X476015Y560992D01*
X476130Y560579D01*
X476283Y560269D01*
X476513Y560010D01*
X476820Y559907D01*
X477127Y560010D01*
X477357Y560269D01*
X477510Y560579D01*
X477625Y560992D01*
X477663Y561457D01*
X477625Y561922D01*
X477510Y562335D01*
X477357Y562645D01*
X477127Y562904D01*
X476820Y563007D01*
G01X479077Y560527D02*
X479307Y560165D01*
X479613Y559959D01*
X479958Y559907D01*
X480265Y559959D01*
X480572Y560217D01*
X480763Y560527D01*
X480802Y560837D01*
X480725Y561199D01*
X480457Y561457D01*
X480188Y561560D01*
X479843D01*
G01X480188D02*
X480418Y561715D01*
X480610Y561974D01*
X480687Y562284D01*
X480610Y562594D01*
X480418Y562852D01*
X480073Y563007D01*
X479728Y562955D01*
X479383Y562749D01*
G01X475357Y555337D02*
Y557837D01*
X475997D01*
X476210Y557712D01*
X476370Y557420D01*
X476423Y557087D01*
X476370Y556754D01*
X476237Y556504D01*
X475997Y556379D01*
X475357D01*
G01X477557Y555337D02*
Y557837D01*
X478223D01*
X478437Y557712D01*
X478570Y557545D01*
X478623Y557212D01*
X478570Y556879D01*
X478410Y556670D01*
X478223Y556545D01*
X477557D01*
G01X478223D02*
X478623Y555337D01*
G01X479783Y556379D02*
X479970Y556670D01*
X480130Y556837D01*
X480343Y556920D01*
X480530Y556837D01*
X480663Y556670D01*
X480770Y556420D01*
X480797Y556129D01*
X480770Y555879D01*
X480663Y555629D01*
X480503Y555420D01*
X480317Y555337D01*
X480103Y555420D01*
X479917Y555670D01*
X479810Y556045D01*
X479783Y556462D01*
X479837Y557004D01*
X479917Y557295D01*
X480050Y557587D01*
X480237Y557795D01*
X480423Y557837D01*
X480610Y557754D01*
X480743Y557545D01*
G01X482437Y555337D02*
X482490Y555879D01*
X482570Y556337D01*
X482677Y556754D01*
X482810Y557212D01*
X483023Y557837D01*
X481957D01*
G01X468020Y583279D02*
Y580079D01*
G01X473934Y566753D02*
X470834D01*
Y567673D01*
X470989Y567980D01*
X471351Y568210D01*
X471764Y568287D01*
X472177Y568210D01*
X472487Y568018D01*
X472642Y567673D01*
Y566753D01*
G01X473934Y569853D02*
X470834D01*
Y570812D01*
X470989Y571118D01*
X471196Y571310D01*
X471609Y571387D01*
X472022Y571310D01*
X472281Y571080D01*
X472436Y570812D01*
Y569853D01*
G01Y570812D02*
X473934Y571387D01*
G01X472642Y572992D02*
X472281Y573260D01*
X472074Y573490D01*
X471971Y573797D01*
X472074Y574065D01*
X472281Y574257D01*
X472591Y574410D01*
X472952Y574448D01*
X473262Y574410D01*
X473572Y574257D01*
X473831Y574027D01*
X473934Y573758D01*
X473831Y573452D01*
X473521Y573183D01*
X473056Y573030D01*
X472539Y572992D01*
X471867Y573068D01*
X471506Y573183D01*
X471144Y573375D01*
X470886Y573643D01*
X470834Y573912D01*
X470937Y574180D01*
X471196Y574372D01*
G01X473314Y575977D02*
X473676Y576207D01*
X473882Y576513D01*
X473934Y576858D01*
X473882Y577165D01*
X473624Y577472D01*
X473314Y577663D01*
X473004Y577702D01*
X472642Y577625D01*
X472384Y577357D01*
X472281Y577088D01*
Y576743D01*
G01Y577088D02*
X472126Y577318D01*
X471867Y577510D01*
X471557Y577587D01*
X471247Y577510D01*
X470989Y577318D01*
X470834Y576973D01*
X470886Y576628D01*
X471092Y576283D01*
G01X479649Y570518D02*
X479597Y570211D01*
X479391Y569943D01*
X479081Y569713D01*
X478719Y569560D01*
X478306Y569483D01*
X477892D01*
X477479Y569560D01*
X477117Y569713D01*
X476807Y569943D01*
X476601Y570211D01*
X476549Y570518D01*
X476601Y570825D01*
X476807Y571093D01*
X477117Y571323D01*
X477479Y571476D01*
X477892Y571553D01*
X478306D01*
X478719Y571476D01*
X479081Y571323D01*
X479391Y571093D01*
X479597Y570825D01*
X479649Y570518D01*
G01X478822Y570825D02*
X479649Y571285D01*
G01Y574078D02*
X476549D01*
X478771Y572660D01*
Y574576D01*
G01X478357Y575990D02*
X477996Y576258D01*
X477789Y576488D01*
X477686Y576795D01*
X477789Y577063D01*
X477996Y577255D01*
X478306Y577408D01*
X478667Y577446D01*
X478977Y577408D01*
X479287Y577255D01*
X479546Y577025D01*
X479649Y576756D01*
X479546Y576450D01*
X479236Y576181D01*
X478771Y576028D01*
X478254Y575990D01*
X477582Y576066D01*
X477221Y576181D01*
X476859Y576373D01*
X476601Y576641D01*
X476549Y576910D01*
X476652Y577178D01*
X476911Y577370D01*
G01X468954Y579476D02*
Y591194D01*
G01X480766Y579476D02*
X468954D01*
G01X470094Y566503D02*
X466994D01*
Y567423D01*
X467149Y567730D01*
X467511Y567960D01*
X467924Y568037D01*
X468337Y567960D01*
X468647Y567768D01*
X468802Y567423D01*
Y566503D01*
G01X469474Y569603D02*
X469784Y569795D01*
X469991Y570025D01*
X470094Y570293D01*
X469991Y570600D01*
X469784Y570830D01*
X469474Y571060D01*
X469061Y571137D01*
X466994D01*
G01X470094Y573470D02*
X466994D01*
X467614Y573010D01*
G01X470094D02*
Y573930D01*
G01Y577030D02*
X466994D01*
X469216Y575612D01*
Y577528D01*
G01X476811Y592439D02*
Y598639D01*
G01X480011Y592439D02*
X476811D01*
G01X472797D02*
Y598639D01*
G01X475997D02*
Y592439D01*
G01D02*
X472797D01*
G01X467627Y590970D02*
Y584170D01*
G01X468003Y591616D02*
X468163Y591866D01*
X468350Y591991D01*
X468563Y592033D01*
X468830Y591950D01*
X469017Y591741D01*
X469070Y591491D01*
X469043Y591241D01*
X468937Y591033D01*
X468403Y590616D01*
X468163Y590325D01*
X468003Y589908D01*
X467950Y589533D01*
X469070D01*
G01X468954Y591194D02*
X480766D01*
G01X471665Y607160D02*
Y592160D01*
G01X472540Y608310D02*
Y600060D01*
G01D02*
X508630D01*
G01X476590Y610010D02*
X474370D01*
G01X476590Y632610D02*
Y610010D01*
G01X473285Y609001D02*
X476483D01*
G01X473285Y602801D02*
Y609001D01*
G01X476483D02*
Y602801D01*
G01D02*
X473285D01*
G01X476811Y598639D02*
X480011D01*
G01X472797D02*
X475997D01*
G01X471517Y614807D02*
Y611607D01*
G01D02*
X465317D01*
G01D02*
Y614807D01*
G01X474431Y612295D02*
X474644Y612087D01*
X474884Y611962D01*
X475098D01*
X475311Y612087D01*
X475471Y612295D01*
X475551Y612587D01*
X475498Y612879D01*
X475364Y613129D01*
X475124Y613295D01*
X474804Y613379D01*
X474618Y613545D01*
X474538Y613837D01*
X474591Y614129D01*
X474724Y614337D01*
X474911Y614462D01*
X475098D01*
X475284Y614379D01*
X475444Y614170D01*
G01X477148Y600932D02*
Y615932D01*
G01X490148Y600932D02*
X477148D01*
G01X464435Y622973D02*
Y607973D01*
G01X465305Y604099D02*
X464772D01*
Y604849D01*
X464932Y605099D01*
X465118Y605266D01*
X465385Y605349D01*
X465652Y605266D01*
X465838Y605099D01*
X465998Y604849D01*
X466105Y604557D01*
X466158Y604224D01*
Y603932D01*
X466105Y603682D01*
X465998Y603391D01*
X465838Y603141D01*
X465678Y602974D01*
X465465Y602849D01*
X465278D01*
X465065Y602932D01*
X464905Y603099D01*
G01X475353Y615580D02*
X465153D01*
G01X475353Y620180D02*
Y615580D01*
G01X465153Y620180D02*
X475353D01*
G01X465153Y615580D02*
Y620180D01*
G01X470253D02*
Y615580D01*
G01X467164Y628017D02*
X464664D01*
Y628683D01*
X464789Y628897D01*
X464956Y629030D01*
X465289Y629083D01*
X465622Y629030D01*
X465831Y628870D01*
X465956Y628683D01*
Y628017D01*
G01Y628683D02*
X467164Y629083D01*
G01X466122Y630243D02*
X465831Y630430D01*
X465664Y630590D01*
X465581Y630803D01*
X465664Y630990D01*
X465831Y631123D01*
X466081Y631230D01*
X466372Y631257D01*
X466622Y631230D01*
X466872Y631123D01*
X467081Y630963D01*
X467164Y630777D01*
X467081Y630563D01*
X466831Y630377D01*
X466456Y630270D01*
X466039Y630243D01*
X465497Y630297D01*
X465206Y630377D01*
X464914Y630510D01*
X464706Y630697D01*
X464664Y630883D01*
X464747Y631070D01*
X464956Y631203D01*
G01X467164Y633270D02*
X464664D01*
X466456Y632283D01*
Y633617D01*
G01X466789Y634563D02*
X466997Y634723D01*
X467122Y634910D01*
X467164Y635150D01*
X467081Y635390D01*
X466914Y635577D01*
X466622Y635710D01*
X466289Y635737D01*
X465956Y635683D01*
X465747Y635550D01*
X465581Y635363D01*
X465539Y635177D01*
X465581Y634990D01*
X465747Y634750D01*
X464664Y634830D01*
Y635550D01*
G01X471836Y624854D02*
Y631054D01*
G01X475036D02*
Y624854D01*
G01D02*
X471836D01*
G01X465087Y620891D02*
Y623391D01*
X465753D01*
X465967Y623266D01*
X466100Y623099D01*
X466153Y622766D01*
X466100Y622433D01*
X465940Y622224D01*
X465753Y622099D01*
X465087D01*
G01X465753D02*
X466153Y620891D01*
G01X467820D02*
Y623391D01*
X467500Y622891D01*
G01Y620891D02*
X468140D01*
G01X470020Y623391D02*
X469807Y623308D01*
X469647Y623099D01*
X469540Y622849D01*
X469460Y622516D01*
X469433Y622141D01*
X469460Y621766D01*
X469540Y621433D01*
X469647Y621183D01*
X469807Y620974D01*
X470020Y620891D01*
X470233Y620974D01*
X470393Y621183D01*
X470500Y621433D01*
X470580Y621766D01*
X470607Y622141D01*
X470580Y622516D01*
X470500Y622849D01*
X470393Y623099D01*
X470233Y623308D01*
X470020Y623391D01*
G01X471633Y621266D02*
X471793Y621058D01*
X471980Y620933D01*
X472220Y620891D01*
X472460Y620974D01*
X472647Y621141D01*
X472780Y621433D01*
X472807Y621766D01*
X472753Y622099D01*
X472620Y622308D01*
X472433Y622474D01*
X472247Y622516D01*
X472060Y622474D01*
X471820Y622308D01*
X471900Y623391D01*
X472620D01*
G01X473967Y621183D02*
X474153Y620974D01*
X474367Y620891D01*
X474580Y620974D01*
X474767Y621224D01*
X474900Y621599D01*
X474953Y621974D01*
Y622433D01*
X474900Y622808D01*
X474767Y623141D01*
X474607Y623308D01*
X474420Y623391D01*
X474207Y623308D01*
X474047Y623141D01*
X473940Y622891D01*
X473887Y622558D01*
X473940Y622266D01*
X474073Y621974D01*
X474233Y621808D01*
X474420Y621766D01*
X474633Y621849D01*
X474793Y622058D01*
X474953Y622433D01*
G01X465317Y614807D02*
X471517D01*
G01X477148Y615932D02*
X490148D01*
G01X475640Y628833D02*
X475853Y628625D01*
X476093Y628500D01*
X476307D01*
X476520Y628625D01*
X476680Y628833D01*
X476760Y629125D01*
X476707Y629417D01*
X476573Y629667D01*
X476333Y629833D01*
X476013Y629917D01*
X475827Y630083D01*
X475747Y630375D01*
X475800Y630667D01*
X475933Y630875D01*
X476120Y631000D01*
X476307D01*
X476493Y630917D01*
X476653Y630708D01*
G01X477332Y616941D02*
Y631941D01*
G01X490332Y616941D02*
X477332D01*
G01X478110Y634290D02*
Y636420D01*
G01X481020Y634290D02*
X478110D01*
G01X499810Y632610D02*
X476590D01*
G01X471240Y658256D02*
Y638056D01*
G01X471836Y631054D02*
X475036D01*
G01X471044Y634615D02*
Y628415D01*
G01X467844Y634615D02*
X471044D01*
G01X467844Y628415D02*
Y634615D01*
G01X471044Y628415D02*
X467844D01*
G01X477332Y631941D02*
X490332D01*
G01X465640Y658256D02*
X471240D01*
G01Y680756D02*
Y660556D01*
G01X465640Y680756D02*
X471240D01*
G01X467540Y687556D02*
X464340D01*
G01X467540Y693756D02*
Y687556D01*
G01X464340D02*
Y693756D01*
G01X472040Y687556D02*
X468840D01*
G01X472040Y693756D02*
Y687556D01*
G01X468840D02*
Y693756D01*
G01X476540Y687556D02*
X473340D01*
G01X476540Y693756D02*
Y687556D01*
G01X473340D02*
Y693756D01*
G01X464240Y699367D02*
Y697600D01*
G01X470590Y700578D02*
Y698811D01*
G01X477039Y701163D02*
Y699396D01*
G01X465240Y700956D02*
Y711356D01*
G01X469640Y700956D02*
X465240D01*
G01X469640Y711356D02*
Y700956D01*
G01Y700356D02*
X465240D01*
G01Y699756D02*
X469640D01*
G01Y699156D02*
X465240D01*
G01D02*
Y700956D01*
G01X469640Y699156D02*
Y700956D01*
G01X471740D02*
Y711356D01*
G01X476140Y700956D02*
X471740D01*
G01X476140Y711356D02*
Y700956D01*
G01Y700356D02*
X471740D01*
G01Y699756D02*
X476140D01*
G01Y699156D02*
X471740D01*
G01D02*
Y700956D01*
G01X476140Y699156D02*
Y700956D01*
G01X478240D02*
Y711356D01*
G01X482640Y700956D02*
X478240D01*
G01X482640Y700356D02*
X478240D01*
G01Y699756D02*
X482640D01*
G01Y699156D02*
X478240D01*
G01D02*
Y700956D01*
G01X464340Y693756D02*
X467540D01*
G01X468840D02*
X472040D01*
G01X473340D02*
X476540D01*
G01X466791Y717692D02*
X467171Y718192D01*
X467614Y718442D01*
X468121Y718525D01*
X468754Y718358D01*
X469197Y717942D01*
X469324Y717442D01*
X469261Y716942D01*
X469007Y716525D01*
X467741Y715692D01*
X467171Y715108D01*
X466791Y714275D01*
X466664Y713525D01*
X469324D01*
G01X473828Y716010D02*
Y721010D01*
X473068Y720010D01*
G01Y716010D02*
X474588D01*
G01X479984Y717623D02*
X479477Y717456D01*
X479097Y717040D01*
X478844Y716540D01*
X478654Y715873D01*
X478591Y715123D01*
X478654Y714373D01*
X478844Y713706D01*
X479097Y713206D01*
X479477Y712790D01*
X479984Y712623D01*
X480491Y712790D01*
X480871Y713206D01*
X481124Y713706D01*
X481314Y714373D01*
X481377Y715123D01*
X481314Y715873D01*
X481124Y716540D01*
X480871Y717040D01*
X480491Y717456D01*
X479984Y717623D01*
G01X481030Y718697D02*
X478530D01*
Y719231D01*
X478655Y719444D01*
X478822Y719604D01*
X479072Y719737D01*
X479363Y719844D01*
X479780Y719871D01*
X480197Y719844D01*
X480488Y719737D01*
X480738Y719604D01*
X480905Y719444D01*
X481030Y719231D01*
Y718697D01*
G01X478947Y720977D02*
X478697Y721137D01*
X478572Y721324D01*
X478530Y721537D01*
X478613Y721804D01*
X478822Y721991D01*
X479072Y722044D01*
X479322Y722017D01*
X479530Y721911D01*
X479947Y721377D01*
X480238Y721137D01*
X480655Y720977D01*
X481030Y720924D01*
Y722044D01*
G01Y724004D02*
X478530D01*
X480322Y723017D01*
Y724351D01*
G01X465240Y711356D02*
X469640D01*
G01X471740D02*
X476140D01*
G01X478240D02*
X482640D01*
G01X472540Y737556D02*
X469340D01*
G01X472540Y743756D02*
Y737556D01*
G01X469340D02*
Y743756D01*
G01X473340Y737556D02*
Y743756D01*
G01X476540Y737556D02*
X473340D01*
G01X476540Y743756D02*
Y737556D01*
G01X468040Y726056D02*
X464840D01*
G01X468040Y732256D02*
Y726056D01*
G01X464840Y732256D02*
X468040D01*
G01X464840Y726056D02*
Y732256D01*
G01X467940Y729156D02*
X464940D01*
G01X463540Y743756D02*
Y737556D01*
G01X468830Y732273D02*
X472030D01*
G01X468830Y726073D02*
Y732273D01*
G01X472030D02*
Y726073D01*
G01X468930Y729173D02*
X471930D01*
G01X472030Y726073D02*
X468830D01*
G01X473330Y732273D02*
X476530D01*
G01X473330Y726073D02*
Y732273D01*
G01X476530Y726073D02*
X473330D01*
G01X476530Y732273D02*
Y726073D01*
G01X477830Y732273D02*
X481030D01*
G01X477830Y726073D02*
Y732273D01*
G01X481030Y726073D02*
X477830D01*
G01X464840Y737556D02*
Y743756D01*
G01X468040Y737556D02*
X464840D01*
G01X468040Y743756D02*
Y737556D01*
G01X477340D02*
Y743756D01*
G01X480540Y737556D02*
X477340D01*
G01X469340Y743756D02*
X472540D01*
G01X472440Y740656D02*
X469440D01*
G01X473340Y743756D02*
X476540D01*
G01X473440Y740656D02*
X476440D01*
G01X466541Y749921D02*
X466386Y749691D01*
X466283Y749423D01*
Y749116D01*
X466438Y748771D01*
X466696Y748503D01*
X467006Y748311D01*
X467523Y748158D01*
X467988Y748120D01*
X468453Y748196D01*
X468763Y748311D01*
X469073Y748541D01*
X469280Y748810D01*
X469383Y749078D01*
Y749346D01*
X469280Y749615D01*
X469125Y749845D01*
X468918Y750036D01*
G01X469383Y752101D02*
X468711Y752178D01*
X468143Y752293D01*
X467626Y752446D01*
X467058Y752638D01*
X466283Y752945D01*
Y751411D01*
G01X469383Y755738D02*
X466283D01*
X468505Y754320D01*
Y756236D01*
G01X469383Y758378D02*
X469331Y758646D01*
X469176Y758953D01*
X468918Y759145D01*
X468556Y759221D01*
X468195Y759145D01*
X467885Y758915D01*
X467730Y758570D01*
Y758186D01*
X467626Y757956D01*
X467368Y757765D01*
X467006Y757688D01*
X466645Y757803D01*
X466386Y758071D01*
X466283Y758378D01*
X466386Y758685D01*
X466645Y758953D01*
X467006Y759068D01*
X467368Y758991D01*
X467626Y758800D01*
X467730Y758570D01*
Y758186D01*
X467885Y757841D01*
X468195Y757611D01*
X468556Y757535D01*
X468918Y757611D01*
X469176Y757803D01*
X469331Y758110D01*
X469383Y758378D01*
G01X470373Y749964D02*
X470218Y749734D01*
X470115Y749466D01*
Y749159D01*
X470270Y748814D01*
X470528Y748546D01*
X470838Y748354D01*
X471355Y748201D01*
X471820Y748163D01*
X472285Y748239D01*
X472595Y748354D01*
X472905Y748584D01*
X473112Y748853D01*
X473215Y749121D01*
Y749389D01*
X473112Y749658D01*
X472957Y749888D01*
X472750Y750079D01*
G01X471923Y751493D02*
X471562Y751761D01*
X471355Y751991D01*
X471252Y752298D01*
X471355Y752566D01*
X471562Y752758D01*
X471872Y752911D01*
X472233Y752949D01*
X472543Y752911D01*
X472853Y752758D01*
X473112Y752528D01*
X473215Y752259D01*
X473112Y751953D01*
X472802Y751684D01*
X472337Y751531D01*
X471820Y751493D01*
X471148Y751569D01*
X470787Y751684D01*
X470425Y751876D01*
X470167Y752144D01*
X470115Y752413D01*
X470218Y752681D01*
X470477Y752873D01*
G01X472595Y754478D02*
X472957Y754708D01*
X473163Y755014D01*
X473215Y755359D01*
X473163Y755666D01*
X472905Y755973D01*
X472595Y756164D01*
X472285Y756203D01*
X471923Y756126D01*
X471665Y755858D01*
X471562Y755589D01*
Y755244D01*
G01Y755589D02*
X471407Y755819D01*
X471148Y756011D01*
X470838Y756088D01*
X470528Y756011D01*
X470270Y755819D01*
X470115Y755474D01*
X470167Y755129D01*
X470373Y754784D01*
G01X472750Y757578D02*
X473008Y757808D01*
X473163Y758076D01*
X473215Y758421D01*
X473112Y758766D01*
X472905Y759034D01*
X472543Y759226D01*
X472130Y759264D01*
X471717Y759188D01*
X471458Y758996D01*
X471252Y758728D01*
X471200Y758459D01*
X471252Y758191D01*
X471458Y757846D01*
X470115Y757961D01*
Y758996D01*
G01X476927Y748328D02*
X473827D01*
Y749287D01*
X473982Y749593D01*
X474189Y749785D01*
X474602Y749862D01*
X475015Y749785D01*
X475274Y749555D01*
X475429Y749287D01*
Y748328D01*
G01Y749287D02*
X476927Y749862D01*
G01Y752195D02*
X476875Y752463D01*
X476720Y752770D01*
X476462Y752962D01*
X476100Y753038D01*
X475739Y752962D01*
X475429Y752732D01*
X475274Y752387D01*
Y752003D01*
X475170Y751773D01*
X474912Y751582D01*
X474550Y751505D01*
X474189Y751620D01*
X473930Y751888D01*
X473827Y752195D01*
X473930Y752502D01*
X474189Y752770D01*
X474550Y752885D01*
X474912Y752808D01*
X475170Y752617D01*
X475274Y752387D01*
Y752003D01*
X475429Y751658D01*
X475739Y751428D01*
X476100Y751352D01*
X476462Y751428D01*
X476720Y751620D01*
X476875Y751927D01*
X476927Y752195D01*
G01X475635Y754567D02*
X475274Y754835D01*
X475067Y755065D01*
X474964Y755372D01*
X475067Y755640D01*
X475274Y755832D01*
X475584Y755985D01*
X475945Y756023D01*
X476255Y755985D01*
X476565Y755832D01*
X476824Y755602D01*
X476927Y755333D01*
X476824Y755027D01*
X476514Y754758D01*
X476049Y754605D01*
X475532Y754567D01*
X474860Y754643D01*
X474499Y754758D01*
X474137Y754950D01*
X473879Y755218D01*
X473827Y755487D01*
X473930Y755755D01*
X474189Y755947D01*
G01X476565Y757743D02*
X476824Y758012D01*
X476927Y758318D01*
X476824Y758625D01*
X476514Y758893D01*
X476049Y759085D01*
X475584Y759162D01*
X475015D01*
X474550Y759085D01*
X474137Y758893D01*
X473930Y758663D01*
X473827Y758395D01*
X473930Y758088D01*
X474137Y757858D01*
X474447Y757705D01*
X474860Y757628D01*
X475222Y757705D01*
X475584Y757897D01*
X475790Y758127D01*
X475842Y758395D01*
X475739Y758702D01*
X475480Y758932D01*
X475015Y759162D01*
G01X481427Y748328D02*
X478327D01*
Y749287D01*
X478482Y749593D01*
X478689Y749785D01*
X479102Y749862D01*
X479515Y749785D01*
X479774Y749555D01*
X479929Y749287D01*
Y748328D01*
G01Y749287D02*
X481427Y749862D01*
G01Y752195D02*
X481375Y752463D01*
X481220Y752770D01*
X480962Y752962D01*
X480600Y753038D01*
X480239Y752962D01*
X479929Y752732D01*
X479774Y752387D01*
Y752003D01*
X479670Y751773D01*
X479412Y751582D01*
X479050Y751505D01*
X478689Y751620D01*
X478430Y751888D01*
X478327Y752195D01*
X478430Y752502D01*
X478689Y752770D01*
X479050Y752885D01*
X479412Y752808D01*
X479670Y752617D01*
X479774Y752387D01*
Y752003D01*
X479929Y751658D01*
X480239Y751428D01*
X480600Y751352D01*
X480962Y751428D01*
X481220Y751620D01*
X481375Y751927D01*
X481427Y752195D01*
G01X480135Y754567D02*
X479774Y754835D01*
X479567Y755065D01*
X479464Y755372D01*
X479567Y755640D01*
X479774Y755832D01*
X480084Y755985D01*
X480445Y756023D01*
X480755Y755985D01*
X481065Y755832D01*
X481324Y755602D01*
X481427Y755333D01*
X481324Y755027D01*
X481014Y754758D01*
X480549Y754605D01*
X480032Y754567D01*
X479360Y754643D01*
X478999Y754758D01*
X478637Y754950D01*
X478379Y755218D01*
X478327Y755487D01*
X478430Y755755D01*
X478689Y755947D01*
G01X480135Y757667D02*
X479774Y757935D01*
X479567Y758165D01*
X479464Y758472D01*
X479567Y758740D01*
X479774Y758932D01*
X480084Y759085D01*
X480445Y759123D01*
X480755Y759085D01*
X481065Y758932D01*
X481324Y758702D01*
X481427Y758433D01*
X481324Y758127D01*
X481014Y757858D01*
X480549Y757705D01*
X480032Y757667D01*
X479360Y757743D01*
X478999Y757858D01*
X478637Y758050D01*
X478379Y758318D01*
X478327Y758587D01*
X478430Y758855D01*
X478689Y759047D01*
G01X464840Y743756D02*
X468040D01*
G01X477340D02*
X480540D01*
G01X469056Y761629D02*
X468901Y761399D01*
X468798Y761131D01*
Y760824D01*
X468953Y760479D01*
X469211Y760211D01*
X469521Y760019D01*
X470038Y759866D01*
X470503Y759828D01*
X470968Y759904D01*
X471278Y760019D01*
X471588Y760249D01*
X471795Y760518D01*
X471898Y760786D01*
Y761054D01*
X471795Y761323D01*
X471640Y761553D01*
X471433Y761744D01*
G01X471898Y763809D02*
X471226Y763886D01*
X470658Y764001D01*
X470141Y764154D01*
X469573Y764346D01*
X468798Y764653D01*
Y763119D01*
G01X471898Y767446D02*
X468798D01*
X471020Y766028D01*
Y767944D01*
G01X471433Y769243D02*
X471691Y769473D01*
X471846Y769741D01*
X471898Y770086D01*
X471795Y770431D01*
X471588Y770699D01*
X471226Y770891D01*
X470813Y770929D01*
X470400Y770853D01*
X470141Y770661D01*
X469935Y770393D01*
X469883Y770124D01*
X469935Y769856D01*
X470141Y769511D01*
X468798Y769626D01*
Y770661D01*
G01X472801Y761945D02*
X472646Y761715D01*
X472543Y761447D01*
Y761140D01*
X472698Y760795D01*
X472956Y760527D01*
X473266Y760335D01*
X473783Y760182D01*
X474248Y760144D01*
X474713Y760220D01*
X475023Y760335D01*
X475333Y760565D01*
X475540Y760834D01*
X475643Y761102D01*
Y761370D01*
X475540Y761639D01*
X475385Y761869D01*
X475178Y762060D01*
G01X475643Y764125D02*
X474971Y764202D01*
X474403Y764317D01*
X473886Y764470D01*
X473318Y764662D01*
X472543Y764969D01*
Y763435D01*
G01X475643Y767762D02*
X472543D01*
X474765Y766344D01*
Y768260D01*
G01X473060Y769674D02*
X472750Y769904D01*
X472595Y770172D01*
X472543Y770479D01*
X472646Y770862D01*
X472905Y771130D01*
X473215Y771207D01*
X473525Y771169D01*
X473783Y771015D01*
X474300Y770249D01*
X474661Y769904D01*
X475178Y769674D01*
X475643Y769597D01*
Y771207D01*
G01X467898Y760381D02*
X464798D01*
Y761340D01*
X464953Y761646D01*
X465160Y761838D01*
X465573Y761915D01*
X465986Y761838D01*
X466245Y761608D01*
X466400Y761340D01*
Y760381D01*
G01Y761340D02*
X467898Y761915D01*
G01X467536Y763596D02*
X467795Y763865D01*
X467898Y764171D01*
X467795Y764478D01*
X467485Y764746D01*
X467020Y764938D01*
X466555Y765015D01*
X465986D01*
X465521Y764938D01*
X465108Y764746D01*
X464901Y764516D01*
X464798Y764248D01*
X464901Y763941D01*
X465108Y763711D01*
X465418Y763558D01*
X465831Y763481D01*
X466193Y763558D01*
X466555Y763750D01*
X466761Y763980D01*
X466813Y764248D01*
X466710Y764555D01*
X466451Y764785D01*
X465986Y765015D01*
G01X467898Y767348D02*
X467846Y767616D01*
X467691Y767923D01*
X467433Y768115D01*
X467071Y768191D01*
X466710Y768115D01*
X466400Y767885D01*
X466245Y767540D01*
Y767156D01*
X466141Y766926D01*
X465883Y766735D01*
X465521Y766658D01*
X465160Y766773D01*
X464901Y767041D01*
X464798Y767348D01*
X464901Y767655D01*
X465160Y767923D01*
X465521Y768038D01*
X465883Y767961D01*
X466141Y767770D01*
X466245Y767540D01*
Y767156D01*
X466400Y766811D01*
X466710Y766581D01*
X467071Y766505D01*
X467433Y766581D01*
X467691Y766773D01*
X467846Y767080D01*
X467898Y767348D01*
G01X467433Y769605D02*
X467691Y769835D01*
X467846Y770103D01*
X467898Y770448D01*
X467795Y770793D01*
X467588Y771061D01*
X467226Y771253D01*
X466813Y771291D01*
X466400Y771215D01*
X466141Y771023D01*
X465935Y770755D01*
X465883Y770486D01*
X465935Y770218D01*
X466141Y769873D01*
X464798Y769988D01*
Y771023D01*
G01X479398Y760598D02*
X476298D01*
Y761557D01*
X476453Y761863D01*
X476660Y762055D01*
X477073Y762132D01*
X477486Y762055D01*
X477745Y761825D01*
X477900Y761557D01*
Y760598D01*
G01Y761557D02*
X479398Y762132D01*
G01X479036Y763813D02*
X479295Y764082D01*
X479398Y764388D01*
X479295Y764695D01*
X478985Y764963D01*
X478520Y765155D01*
X478055Y765232D01*
X477486D01*
X477021Y765155D01*
X476608Y764963D01*
X476401Y764733D01*
X476298Y764465D01*
X476401Y764158D01*
X476608Y763928D01*
X476918Y763775D01*
X477331Y763698D01*
X477693Y763775D01*
X478055Y763967D01*
X478261Y764197D01*
X478313Y764465D01*
X478210Y764772D01*
X477951Y765002D01*
X477486Y765232D01*
G01X479398Y767488D02*
X478726Y767565D01*
X478158Y767680D01*
X477641Y767833D01*
X477073Y768025D01*
X476298Y768332D01*
Y766798D01*
G01X479036Y770013D02*
X479295Y770282D01*
X479398Y770588D01*
X479295Y770895D01*
X478985Y771163D01*
X478520Y771355D01*
X478055Y771432D01*
X477486D01*
X477021Y771355D01*
X476608Y771163D01*
X476401Y770933D01*
X476298Y770665D01*
X476401Y770358D01*
X476608Y770128D01*
X476918Y769975D01*
X477331Y769898D01*
X477693Y769975D01*
X478055Y770167D01*
X478261Y770397D01*
X478313Y770665D01*
X478210Y770972D01*
X477951Y771202D01*
X477486Y771432D01*
G01X479776Y68716D02*
X479621Y68486D01*
X479518Y68218D01*
Y67911D01*
X479673Y67566D01*
X479931Y67298D01*
X480241Y67106D01*
X480758Y66953D01*
X481223Y66915D01*
X481688Y66991D01*
X481998Y67106D01*
X482308Y67336D01*
X482515Y67605D01*
X482618Y67873D01*
Y68141D01*
X482515Y68410D01*
X482360Y68640D01*
X482153Y68831D01*
G01X482618Y70973D02*
X482566Y71241D01*
X482411Y71548D01*
X482153Y71740D01*
X481791Y71816D01*
X481430Y71740D01*
X481120Y71510D01*
X480965Y71165D01*
Y70781D01*
X480861Y70551D01*
X480603Y70360D01*
X480241Y70283D01*
X479880Y70398D01*
X479621Y70666D01*
X479518Y70973D01*
X479621Y71280D01*
X479880Y71548D01*
X480241Y71663D01*
X480603Y71586D01*
X480861Y71395D01*
X480965Y71165D01*
Y70781D01*
X481120Y70436D01*
X481430Y70206D01*
X481791Y70130D01*
X482153Y70206D01*
X482411Y70398D01*
X482566Y70705D01*
X482618Y70973D01*
G01X482153Y73230D02*
X482411Y73460D01*
X482566Y73728D01*
X482618Y74073D01*
X482515Y74418D01*
X482308Y74686D01*
X481946Y74878D01*
X481533Y74916D01*
X481120Y74840D01*
X480861Y74648D01*
X480655Y74380D01*
X480603Y74111D01*
X480655Y73843D01*
X480861Y73498D01*
X479518Y73613D01*
Y74648D01*
G01X481326Y76445D02*
X480965Y76713D01*
X480758Y76943D01*
X480655Y77250D01*
X480758Y77518D01*
X480965Y77710D01*
X481275Y77863D01*
X481636Y77901D01*
X481946Y77863D01*
X482256Y77710D01*
X482515Y77480D01*
X482618Y77211D01*
X482515Y76905D01*
X482205Y76636D01*
X481740Y76483D01*
X481223Y76445D01*
X480551Y76521D01*
X480190Y76636D01*
X479828Y76828D01*
X479570Y77096D01*
X479518Y77365D01*
X479621Y77633D01*
X479880Y77825D01*
G01X487646Y85630D02*
X487491Y85400D01*
X487388Y85132D01*
Y84825D01*
X487543Y84480D01*
X487801Y84212D01*
X488111Y84020D01*
X488628Y83867D01*
X489093Y83829D01*
X489558Y83905D01*
X489868Y84020D01*
X490178Y84250D01*
X490385Y84519D01*
X490488Y84787D01*
Y85055D01*
X490385Y85324D01*
X490230Y85554D01*
X490023Y85745D01*
G01X490488Y88347D02*
X487388D01*
X489610Y86929D01*
Y88845D01*
G01X490488Y90987D02*
X490436Y91255D01*
X490281Y91562D01*
X490023Y91754D01*
X489661Y91830D01*
X489300Y91754D01*
X488990Y91524D01*
X488835Y91179D01*
Y90795D01*
X488731Y90565D01*
X488473Y90374D01*
X488111Y90297D01*
X487750Y90412D01*
X487491Y90680D01*
X487388Y90987D01*
X487491Y91294D01*
X487750Y91562D01*
X488111Y91677D01*
X488473Y91600D01*
X488731Y91409D01*
X488835Y91179D01*
Y90795D01*
X488990Y90450D01*
X489300Y90220D01*
X489661Y90144D01*
X490023Y90220D01*
X490281Y90412D01*
X490436Y90719D01*
X490488Y90987D01*
G01X489196Y93359D02*
X488835Y93627D01*
X488628Y93857D01*
X488525Y94164D01*
X488628Y94432D01*
X488835Y94624D01*
X489145Y94777D01*
X489506Y94815D01*
X489816Y94777D01*
X490126Y94624D01*
X490385Y94394D01*
X490488Y94125D01*
X490385Y93819D01*
X490075Y93550D01*
X489610Y93397D01*
X489093Y93359D01*
X488421Y93435D01*
X488060Y93550D01*
X487698Y93742D01*
X487440Y94010D01*
X487388Y94279D01*
X487491Y94547D01*
X487750Y94739D01*
G01X486338Y84020D02*
X483238D01*
Y84979D01*
X483393Y85285D01*
X483600Y85477D01*
X484013Y85554D01*
X484426Y85477D01*
X484685Y85247D01*
X484840Y84979D01*
Y84020D01*
G01Y84979D02*
X486338Y85554D01*
G01X485046Y87159D02*
X484685Y87427D01*
X484478Y87657D01*
X484375Y87964D01*
X484478Y88232D01*
X484685Y88424D01*
X484995Y88577D01*
X485356Y88615D01*
X485666Y88577D01*
X485976Y88424D01*
X486235Y88194D01*
X486338Y87925D01*
X486235Y87619D01*
X485925Y87350D01*
X485460Y87197D01*
X484943Y87159D01*
X484271Y87235D01*
X483910Y87350D01*
X483548Y87542D01*
X483290Y87810D01*
X483238Y88079D01*
X483341Y88347D01*
X483600Y88539D01*
G01X483755Y90259D02*
X483445Y90489D01*
X483290Y90757D01*
X483238Y91064D01*
X483341Y91447D01*
X483600Y91715D01*
X483910Y91792D01*
X484220Y91754D01*
X484478Y91600D01*
X484995Y90834D01*
X485356Y90489D01*
X485873Y90259D01*
X486338Y90182D01*
Y91792D01*
G01Y94547D02*
X483238D01*
X485460Y93129D01*
Y95045D01*
G01X494462Y84020D02*
X491362D01*
Y84979D01*
X491517Y85285D01*
X491724Y85477D01*
X492137Y85554D01*
X492550Y85477D01*
X492809Y85247D01*
X492964Y84979D01*
Y84020D01*
G01Y84979D02*
X494462Y85554D01*
G01Y87887D02*
X491362D01*
X491982Y87427D01*
G01X494462D02*
Y88347D01*
G01Y90987D02*
X491362D01*
X491982Y90527D01*
G01X494462D02*
Y91447D01*
G01X493997Y93244D02*
X494255Y93474D01*
X494410Y93742D01*
X494462Y94087D01*
X494359Y94432D01*
X494152Y94700D01*
X493790Y94892D01*
X493377Y94930D01*
X492964Y94854D01*
X492705Y94662D01*
X492499Y94394D01*
X492447Y94125D01*
X492499Y93857D01*
X492705Y93512D01*
X491362Y93627D01*
Y94662D01*
G01Y97187D02*
X491465Y96880D01*
X491724Y96650D01*
X492034Y96497D01*
X492447Y96382D01*
X492912Y96344D01*
X493377Y96382D01*
X493790Y96497D01*
X494100Y96650D01*
X494359Y96880D01*
X494462Y97187D01*
X494359Y97494D01*
X494100Y97724D01*
X493790Y97877D01*
X493377Y97992D01*
X492912Y98030D01*
X492447Y97992D01*
X492034Y97877D01*
X491724Y97724D01*
X491465Y97494D01*
X491362Y97187D01*
G01X486838Y107723D02*
X490038D01*
G01X486838Y101523D02*
Y107723D01*
G01X490038D02*
Y101523D01*
G01D02*
X486838D01*
G01X489938Y104623D02*
X486938D01*
G01X481070Y115270D02*
Y102270D01*
G01Y100470D02*
Y102270D01*
G01X481938Y107723D02*
X485138D01*
G01X481938Y101523D02*
Y107723D01*
G01X485138D02*
Y101523D01*
G01D02*
X481938D01*
G01X494555Y107704D02*
Y101504D01*
G01X491355Y107704D02*
X494555D01*
G01Y101504D02*
X491355D01*
G01D02*
Y107704D01*
G01X482972Y124567D02*
X483159Y124858D01*
X483319Y125025D01*
X483532Y125108D01*
X483719Y125025D01*
X483852Y124858D01*
X483959Y124608D01*
X483986Y124317D01*
X483959Y124067D01*
X483852Y123817D01*
X483692Y123608D01*
X483506Y123525D01*
X483292Y123608D01*
X483106Y123858D01*
X482999Y124233D01*
X482972Y124650D01*
X483026Y125192D01*
X483106Y125483D01*
X483239Y125775D01*
X483426Y125983D01*
X483612Y126025D01*
X483799Y125942D01*
X483932Y125733D01*
G01X485999Y123525D02*
Y126025D01*
X485012Y124233D01*
X486346D01*
G01X486055Y117929D02*
X486242Y118220D01*
X486402Y118387D01*
X486615Y118470D01*
X486802Y118387D01*
X486935Y118220D01*
X487042Y117970D01*
X487069Y117679D01*
X487042Y117429D01*
X486935Y117179D01*
X486775Y116970D01*
X486589Y116887D01*
X486375Y116970D01*
X486189Y117220D01*
X486082Y117595D01*
X486055Y118012D01*
X486109Y118554D01*
X486189Y118845D01*
X486322Y119137D01*
X486509Y119345D01*
X486695Y119387D01*
X486882Y119304D01*
X487015Y119095D01*
G01X488175Y117262D02*
X488335Y117054D01*
X488522Y116929D01*
X488762Y116887D01*
X489002Y116970D01*
X489189Y117137D01*
X489322Y117429D01*
X489349Y117762D01*
X489295Y118095D01*
X489162Y118304D01*
X488975Y118470D01*
X488789Y118512D01*
X488602Y118470D01*
X488362Y118304D01*
X488442Y119387D01*
X489162D01*
G01X491010Y114325D02*
Y111325D01*
G01X567172Y124369D02*
X488038D01*
G01D02*
Y179881D01*
G01X486360Y186505D02*
X486520Y186213D01*
X486734Y186047D01*
X486974Y186005D01*
X487187Y186047D01*
X487400Y186255D01*
X487534Y186505D01*
X487560Y186755D01*
X487507Y187047D01*
X487320Y187255D01*
X487134Y187338D01*
X486894D01*
G01X487134D02*
X487294Y187463D01*
X487427Y187672D01*
X487480Y187922D01*
X487427Y188172D01*
X487294Y188380D01*
X487054Y188505D01*
X486814Y188463D01*
X486574Y188297D01*
G01X489147Y186005D02*
X489334Y186047D01*
X489547Y186172D01*
X489680Y186380D01*
X489734Y186672D01*
X489680Y186963D01*
X489520Y187213D01*
X489280Y187338D01*
X489014D01*
X488854Y187422D01*
X488720Y187630D01*
X488667Y187922D01*
X488747Y188213D01*
X488934Y188422D01*
X489147Y188505D01*
X489360Y188422D01*
X489547Y188213D01*
X489627Y187922D01*
X489574Y187630D01*
X489440Y187422D01*
X489280Y187338D01*
X489014D01*
X488774Y187213D01*
X488614Y186963D01*
X488560Y186672D01*
X488614Y186380D01*
X488747Y186172D01*
X488960Y186047D01*
X489147Y186005D01*
G01X483640Y178815D02*
X483800Y178523D01*
X484014Y178357D01*
X484254Y178315D01*
X484467Y178357D01*
X484680Y178565D01*
X484814Y178815D01*
X484840Y179065D01*
X484787Y179357D01*
X484600Y179565D01*
X484414Y179648D01*
X484174D01*
G01X484414D02*
X484574Y179773D01*
X484707Y179982D01*
X484760Y180232D01*
X484707Y180482D01*
X484574Y180690D01*
X484334Y180815D01*
X484094Y180773D01*
X483854Y180607D01*
G01X485974Y178607D02*
X486160Y178398D01*
X486374Y178315D01*
X486587Y178398D01*
X486774Y178648D01*
X486907Y179023D01*
X486960Y179398D01*
Y179857D01*
X486907Y180232D01*
X486774Y180565D01*
X486614Y180732D01*
X486427Y180815D01*
X486214Y180732D01*
X486054Y180565D01*
X485947Y180315D01*
X485894Y179982D01*
X485947Y179690D01*
X486080Y179398D01*
X486240Y179232D01*
X486427Y179190D01*
X486640Y179273D01*
X486800Y179482D01*
X486960Y179857D01*
G01X488038Y179881D02*
X567172D01*
G01X488240Y196010D02*
Y201160D01*
G01X495640Y192920D02*
X488240D01*
G01Y201160D02*
X497880D01*
G01X493776Y197128D02*
X496776D01*
G01X496876Y194028D02*
X493676D01*
G01D02*
Y200228D01*
G01D02*
X496876D01*
G01X489571Y194049D02*
Y200249D01*
G01D02*
X492771D01*
G01D02*
Y194049D01*
G01D02*
X489571D01*
G01X482680Y193891D02*
Y200091D01*
G01D02*
X485880D01*
G01D02*
Y193891D01*
G01D02*
X482680D01*
G01X489700Y203632D02*
X489913Y203424D01*
X490153Y203299D01*
X490367D01*
X490580Y203424D01*
X490740Y203632D01*
X490820Y203924D01*
X490767Y204216D01*
X490633Y204466D01*
X490393Y204632D01*
X490073Y204716D01*
X489887Y204882D01*
X489807Y205174D01*
X489860Y205466D01*
X489993Y205674D01*
X490180Y205799D01*
X490367D01*
X490553Y205716D01*
X490713Y205507D01*
G01X493458Y204429D02*
Y206929D01*
X493992D01*
X494205Y206804D01*
X494365Y206637D01*
X494498Y206387D01*
X494605Y206096D01*
X494632Y205679D01*
X494605Y205262D01*
X494498Y204971D01*
X494365Y204721D01*
X494205Y204554D01*
X493992Y204429D01*
X493458D01*
G01X494513Y220934D02*
Y207934D01*
G01D02*
X479513D01*
G01D02*
Y220934D01*
G01X494598Y229220D02*
Y232420D01*
G01X500798Y229220D02*
X494598D01*
G01Y232420D02*
X500798D01*
G01X492829Y226353D02*
X486629D01*
G01D02*
Y229553D01*
G01D02*
X492829D01*
G01D02*
Y226353D01*
G01X483467Y225346D02*
X489667D01*
G01D02*
Y222146D01*
G01D02*
X483467D01*
G01D02*
Y225346D01*
G01X479513Y220934D02*
X494513D01*
G01X490632Y244477D02*
X496832D01*
G01Y241277D02*
X490632D01*
G01D02*
Y244477D01*
G01X493732Y241377D02*
Y244377D01*
G01X489388Y262926D02*
X486288D01*
Y263885D01*
X486443Y264191D01*
X486650Y264383D01*
X487063Y264460D01*
X487476Y264383D01*
X487735Y264153D01*
X487890Y263885D01*
Y262926D01*
G01Y263885D02*
X489388Y264460D01*
G01Y266793D02*
X486288D01*
X486908Y266333D01*
G01X489388D02*
Y267253D01*
G01Y270353D02*
X486288D01*
X488510Y268935D01*
Y270851D01*
G01X489388Y272916D02*
X488716Y272993D01*
X488148Y273108D01*
X487631Y273261D01*
X487063Y273453D01*
X486288Y273760D01*
Y272226D01*
G01X492135Y277089D02*
X522843D01*
G01X492135Y288428D02*
Y277089D01*
G01X483681Y269549D02*
X483841Y269799D01*
X484028Y269924D01*
X484241Y269966D01*
X484508Y269883D01*
X484695Y269674D01*
X484748Y269424D01*
X484721Y269174D01*
X484615Y268966D01*
X484081Y268549D01*
X483841Y268258D01*
X483681Y267841D01*
X483628Y267466D01*
X484748D01*
G01X482295Y284767D02*
Y269767D01*
G01X484119Y280946D02*
X487319D01*
G01X484119Y274746D02*
Y280946D01*
G01X487319D02*
Y274746D01*
G01D02*
X484119D01*
G01X479468Y285941D02*
X479628Y285649D01*
X479842Y285483D01*
X480082Y285441D01*
X480295Y285483D01*
X480508Y285691D01*
X480642Y285941D01*
X480668Y286191D01*
X480615Y286483D01*
X480428Y286691D01*
X480242Y286774D01*
X480002D01*
G01X480242D02*
X480402Y286899D01*
X480535Y287108D01*
X480588Y287358D01*
X480535Y287608D01*
X480402Y287816D01*
X480162Y287941D01*
X479922Y287899D01*
X479682Y287733D01*
G01X485834Y438300D02*
X485604Y438455D01*
X485336Y438558D01*
X485029D01*
X484684Y438403D01*
X484416Y438145D01*
X484224Y437835D01*
X484071Y437318D01*
X484033Y436853D01*
X484109Y436388D01*
X484224Y436078D01*
X484454Y435768D01*
X484723Y435561D01*
X484991Y435458D01*
X485259D01*
X485528Y435561D01*
X485758Y435716D01*
X485949Y435923D01*
G01X488091Y435458D02*
Y438558D01*
X487631Y437938D01*
G01Y435458D02*
X488551D01*
G01X490348Y436078D02*
X490578Y435716D01*
X490884Y435510D01*
X491229Y435458D01*
X491536Y435510D01*
X491843Y435768D01*
X492034Y436078D01*
X492073Y436388D01*
X491996Y436750D01*
X491728Y437008D01*
X491459Y437111D01*
X491114D01*
G01X491459D02*
X491689Y437266D01*
X491881Y437525D01*
X491958Y437835D01*
X491881Y438145D01*
X491689Y438403D01*
X491344Y438558D01*
X490999Y438506D01*
X490654Y438300D01*
G01X495409Y438264D02*
X495179Y438419D01*
X494911Y438522D01*
X494604D01*
X494259Y438367D01*
X493991Y438109D01*
X493799Y437799D01*
X493646Y437282D01*
X493608Y436817D01*
X493684Y436352D01*
X493799Y436042D01*
X494029Y435732D01*
X494298Y435525D01*
X494566Y435422D01*
X494834D01*
X495103Y435525D01*
X495333Y435680D01*
X495524Y435887D01*
G01X497666Y435422D02*
Y438522D01*
X497206Y437902D01*
G01Y435422D02*
X498126D01*
G01X500038Y438005D02*
X500268Y438315D01*
X500536Y438470D01*
X500843Y438522D01*
X501226Y438419D01*
X501494Y438160D01*
X501571Y437850D01*
X501533Y437540D01*
X501379Y437282D01*
X500613Y436765D01*
X500268Y436404D01*
X500038Y435887D01*
X499961Y435422D01*
X501571D01*
G01X480280Y530170D02*
Y541620D01*
G01X482013Y532540D02*
Y535640D01*
X482972D01*
X483278Y535485D01*
X483470Y535278D01*
X483547Y534865D01*
X483470Y534452D01*
X483240Y534193D01*
X482972Y534038D01*
X482013D01*
G01X482972D02*
X483547Y532540D01*
G01X485152Y535123D02*
X485382Y535433D01*
X485650Y535588D01*
X485957Y535640D01*
X486340Y535537D01*
X486608Y535278D01*
X486685Y534968D01*
X486647Y534658D01*
X486493Y534400D01*
X485727Y533883D01*
X485382Y533522D01*
X485152Y533005D01*
X485075Y532540D01*
X486685D01*
G01X488980D02*
X489248Y532592D01*
X489555Y532747D01*
X489747Y533005D01*
X489823Y533367D01*
X489747Y533728D01*
X489517Y534038D01*
X489172Y534193D01*
X488788D01*
X488558Y534297D01*
X488367Y534555D01*
X488290Y534917D01*
X488405Y535278D01*
X488673Y535537D01*
X488980Y535640D01*
X489287Y535537D01*
X489555Y535278D01*
X489670Y534917D01*
X489593Y534555D01*
X489402Y534297D01*
X489172Y534193D01*
X488788D01*
X488443Y534038D01*
X488213Y533728D01*
X488137Y533367D01*
X488213Y533005D01*
X488405Y532747D01*
X488712Y532592D01*
X488980Y532540D01*
G01X492080D02*
Y535640D01*
X491620Y535020D01*
G01Y532540D02*
X492540D01*
G01X488140Y541620D02*
Y565130D01*
G01X480280Y541620D02*
X488140D01*
G01X494054Y535647D02*
X494240Y535438D01*
X494454Y535355D01*
X494667Y535438D01*
X494854Y535688D01*
X494987Y536063D01*
X495040Y536438D01*
Y536897D01*
X494987Y537272D01*
X494854Y537605D01*
X494694Y537772D01*
X494507Y537855D01*
X494294Y537772D01*
X494134Y537605D01*
X494027Y537355D01*
X493974Y537022D01*
X494027Y536730D01*
X494160Y536438D01*
X494320Y536272D01*
X494507Y536230D01*
X494720Y536313D01*
X494880Y536522D01*
X495040Y536897D01*
G01X496200Y536397D02*
X496387Y536688D01*
X496547Y536855D01*
X496760Y536938D01*
X496947Y536855D01*
X497080Y536688D01*
X497187Y536438D01*
X497214Y536147D01*
X497187Y535897D01*
X497080Y535647D01*
X496920Y535438D01*
X496734Y535355D01*
X496520Y535438D01*
X496334Y535688D01*
X496227Y536063D01*
X496200Y536480D01*
X496254Y537022D01*
X496334Y537313D01*
X496467Y537605D01*
X496654Y537813D01*
X496840Y537855D01*
X497027Y537772D01*
X497160Y537563D01*
G01X488538Y541125D02*
Y537925D01*
G01X482338Y541125D02*
X488538D01*
G01X482338Y537925D02*
Y541125D01*
G01X488538Y537925D02*
X482338D01*
G01X481894Y544297D02*
X479394D01*
Y544937D01*
X479519Y545150D01*
X479811Y545310D01*
X480144Y545363D01*
X480477Y545310D01*
X480727Y545177D01*
X480852Y544937D01*
Y544297D01*
G01X481894Y546497D02*
X479394D01*
Y547163D01*
X479519Y547377D01*
X479686Y547510D01*
X480019Y547563D01*
X480352Y547510D01*
X480561Y547350D01*
X480686Y547163D01*
Y546497D01*
G01Y547163D02*
X481894Y547563D01*
G01X480852Y548723D02*
X480561Y548910D01*
X480394Y549070D01*
X480311Y549283D01*
X480394Y549470D01*
X480561Y549603D01*
X480811Y549710D01*
X481102Y549737D01*
X481352Y549710D01*
X481602Y549603D01*
X481811Y549443D01*
X481894Y549257D01*
X481811Y549043D01*
X481561Y548857D01*
X481186Y548750D01*
X480769Y548723D01*
X480227Y548777D01*
X479936Y548857D01*
X479644Y548990D01*
X479436Y549177D01*
X479394Y549363D01*
X479477Y549550D01*
X479686Y549683D01*
G01X481602Y550977D02*
X481811Y551163D01*
X481894Y551377D01*
X481811Y551590D01*
X481561Y551777D01*
X481186Y551910D01*
X480811Y551963D01*
X480352D01*
X479977Y551910D01*
X479644Y551777D01*
X479477Y551617D01*
X479394Y551430D01*
X479477Y551217D01*
X479644Y551057D01*
X479894Y550950D01*
X480227Y550897D01*
X480519Y550950D01*
X480811Y551083D01*
X480977Y551243D01*
X481019Y551430D01*
X480936Y551643D01*
X480727Y551803D01*
X480352Y551963D01*
G01X487154Y545837D02*
X484654D01*
Y546477D01*
X484779Y546690D01*
X485071Y546850D01*
X485404Y546903D01*
X485737Y546850D01*
X485987Y546717D01*
X486112Y546477D01*
Y545837D01*
G01X487154Y548037D02*
X484654D01*
Y548703D01*
X484779Y548917D01*
X484946Y549050D01*
X485279Y549103D01*
X485612Y549050D01*
X485821Y548890D01*
X485946Y548703D01*
Y548037D01*
G01Y548703D02*
X487154Y549103D01*
G01Y550717D02*
X486612Y550770D01*
X486154Y550850D01*
X485737Y550957D01*
X485279Y551090D01*
X484654Y551303D01*
Y550237D01*
G01Y552970D02*
X484737Y552757D01*
X484946Y552597D01*
X485196Y552490D01*
X485529Y552410D01*
X485904Y552383D01*
X486279Y552410D01*
X486612Y552490D01*
X486862Y552597D01*
X487071Y552757D01*
X487154Y552970D01*
X487071Y553183D01*
X486862Y553343D01*
X486612Y553450D01*
X486279Y553530D01*
X485904Y553557D01*
X485529Y553530D01*
X485196Y553450D01*
X484946Y553343D01*
X484737Y553183D01*
X484654Y552970D01*
G01X481787Y579864D02*
X481947Y579572D01*
X482161Y579406D01*
X482401Y579364D01*
X482614Y579406D01*
X482827Y579614D01*
X482961Y579864D01*
X482987Y580114D01*
X482934Y580406D01*
X482747Y580614D01*
X482561Y580697D01*
X482321D01*
G01X482561D02*
X482721Y580822D01*
X482854Y581031D01*
X482907Y581281D01*
X482854Y581531D01*
X482721Y581739D01*
X482481Y581864D01*
X482241Y581822D01*
X482001Y581656D01*
G01X480766Y591194D02*
Y579476D01*
G01X492658Y592751D02*
X492845Y593042D01*
X493005Y593209D01*
X493218Y593292D01*
X493405Y593209D01*
X493538Y593042D01*
X493645Y592792D01*
X493672Y592501D01*
X493645Y592251D01*
X493538Y592001D01*
X493378Y591792D01*
X493192Y591709D01*
X492978Y591792D01*
X492792Y592042D01*
X492685Y592417D01*
X492658Y592834D01*
X492712Y593376D01*
X492792Y593667D01*
X492925Y593959D01*
X493112Y594167D01*
X493298Y594209D01*
X493485Y594126D01*
X493618Y593917D01*
G01X494778Y592084D02*
X494938Y591876D01*
X495125Y591751D01*
X495365Y591709D01*
X495605Y591792D01*
X495792Y591959D01*
X495925Y592251D01*
X495952Y592584D01*
X495898Y592917D01*
X495765Y593126D01*
X495578Y593292D01*
X495392Y593334D01*
X495205Y593292D01*
X494965Y593126D01*
X495045Y594209D01*
X495765D01*
G01X488932Y588891D02*
X486432D01*
Y589557D01*
X486557Y589771D01*
X486724Y589904D01*
X487057Y589957D01*
X487390Y589904D01*
X487599Y589744D01*
X487724Y589557D01*
Y588891D01*
G01Y589557D02*
X488932Y589957D01*
G01Y591624D02*
X486432D01*
X486932Y591304D01*
G01X488932D02*
Y591944D01*
G01X486849Y593317D02*
X486599Y593477D01*
X486474Y593664D01*
X486432Y593877D01*
X486515Y594144D01*
X486724Y594331D01*
X486974Y594384D01*
X487224Y594357D01*
X487432Y594251D01*
X487849Y593717D01*
X488140Y593477D01*
X488557Y593317D01*
X488932Y593264D01*
Y594384D01*
G01X488557Y595437D02*
X488765Y595597D01*
X488890Y595784D01*
X488932Y596024D01*
X488849Y596264D01*
X488682Y596451D01*
X488390Y596584D01*
X488057Y596611D01*
X487724Y596557D01*
X487515Y596424D01*
X487349Y596237D01*
X487307Y596051D01*
X487349Y595864D01*
X487515Y595624D01*
X486432Y595704D01*
Y596424D01*
G01Y598224D02*
X486515Y598011D01*
X486724Y597851D01*
X486974Y597744D01*
X487307Y597664D01*
X487682Y597637D01*
X488057Y597664D01*
X488390Y597744D01*
X488640Y597851D01*
X488849Y598011D01*
X488932Y598224D01*
X488849Y598437D01*
X488640Y598597D01*
X488390Y598704D01*
X488057Y598784D01*
X487682Y598811D01*
X487307Y598784D01*
X486974Y598704D01*
X486724Y598597D01*
X486515Y598437D01*
X486432Y598224D01*
G01X480011Y598639D02*
Y592439D01*
G01X485045Y589104D02*
X482545D01*
Y589770D01*
X482670Y589984D01*
X482837Y590117D01*
X483170Y590170D01*
X483503Y590117D01*
X483712Y589957D01*
X483837Y589770D01*
Y589104D01*
G01Y589770D02*
X485045Y590170D01*
G01Y591837D02*
X482545D01*
X483045Y591517D01*
G01X485045D02*
Y592157D01*
G01X482545Y594037D02*
X482628Y593824D01*
X482837Y593664D01*
X483087Y593557D01*
X483420Y593477D01*
X483795Y593450D01*
X484170Y593477D01*
X484503Y593557D01*
X484753Y593664D01*
X484962Y593824D01*
X485045Y594037D01*
X484962Y594250D01*
X484753Y594410D01*
X484503Y594517D01*
X484170Y594597D01*
X483795Y594624D01*
X483420Y594597D01*
X483087Y594517D01*
X482837Y594410D01*
X482628Y594250D01*
X482545Y594037D01*
G01X484545Y595650D02*
X484837Y595810D01*
X485003Y596024D01*
X485045Y596264D01*
X485003Y596477D01*
X484795Y596690D01*
X484545Y596824D01*
X484295Y596850D01*
X484003Y596797D01*
X483795Y596610D01*
X483712Y596424D01*
Y596184D01*
G01Y596424D02*
X483587Y596584D01*
X483378Y596717D01*
X483128Y596770D01*
X482878Y596717D01*
X482670Y596584D01*
X482545Y596344D01*
X482587Y596104D01*
X482753Y595864D01*
G01X484753Y597984D02*
X484962Y598170D01*
X485045Y598384D01*
X484962Y598597D01*
X484712Y598784D01*
X484337Y598917D01*
X483962Y598970D01*
X483503D01*
X483128Y598917D01*
X482795Y598784D01*
X482628Y598624D01*
X482545Y598437D01*
X482628Y598224D01*
X482795Y598064D01*
X483045Y597957D01*
X483378Y597904D01*
X483670Y597957D01*
X483962Y598090D01*
X484128Y598250D01*
X484170Y598437D01*
X484087Y598650D01*
X483878Y598810D01*
X483503Y598970D01*
G01X481562Y585387D02*
Y587887D01*
X481242Y587387D01*
G01Y585387D02*
X481882D01*
G01X495838Y601925D02*
X492638D01*
G01Y608125D02*
X495838D01*
G01X492638Y601925D02*
Y608125D01*
G01X491073Y601627D02*
Y604127D01*
X491607D01*
X491820Y604002D01*
X491980Y603835D01*
X492113Y603585D01*
X492220Y603294D01*
X492247Y602877D01*
X492220Y602460D01*
X492113Y602169D01*
X491980Y601919D01*
X491820Y601752D01*
X491607Y601627D01*
X491073D01*
G01X492566Y613586D02*
X493099D01*
Y612836D01*
X492939Y612586D01*
X492753Y612419D01*
X492486Y612336D01*
X492219Y612419D01*
X492033Y612586D01*
X491873Y612836D01*
X491766Y613128D01*
X491713Y613461D01*
Y613753D01*
X491766Y614003D01*
X491873Y614294D01*
X492033Y614544D01*
X492193Y614711D01*
X492406Y614836D01*
X492593D01*
X492806Y614753D01*
X492966Y614586D01*
G01X490148Y615932D02*
Y600932D01*
G01X491782Y616936D02*
Y631936D01*
G01X504782Y616936D02*
X491782D01*
G01X484360Y629250D02*
X484893D01*
Y628500D01*
X484733Y628250D01*
X484547Y628083D01*
X484280Y628000D01*
X484013Y628083D01*
X483827Y628250D01*
X483667Y628500D01*
X483560Y628792D01*
X483507Y629125D01*
Y629417D01*
X483560Y629667D01*
X483667Y629958D01*
X483827Y630208D01*
X483987Y630375D01*
X484200Y630500D01*
X484387D01*
X484600Y630417D01*
X484760Y630250D01*
G01X487660Y617975D02*
Y620475D01*
X488194D01*
X488407Y620350D01*
X488567Y620183D01*
X488700Y619933D01*
X488807Y619642D01*
X488834Y619225D01*
X488807Y618808D01*
X488700Y618517D01*
X488567Y618267D01*
X488407Y618100D01*
X488194Y617975D01*
X487660D01*
G01X490332Y631941D02*
Y616941D01*
G01X492580Y638470D02*
X496990D01*
G01X492580Y643560D02*
Y638470D01*
G01X483940Y642004D02*
Y645204D01*
G01X490140Y642004D02*
X483940D01*
G01X490140Y645204D02*
Y642004D01*
G01X487040Y642104D02*
Y645104D01*
G01X488331Y636396D02*
Y633196D01*
G01X482131Y636396D02*
X488331D01*
G01X482131Y633196D02*
Y636396D01*
G01X488331Y633196D02*
X482131D01*
G01X483838Y638023D02*
Y641223D01*
G01X490038Y638023D02*
X483838D01*
G01X490038Y641223D02*
Y638023D01*
G01X483838Y641223D02*
X490038D01*
G01X495298Y633003D02*
X489098D01*
G01Y636203D02*
X495298D01*
G01X489098Y633003D02*
Y636203D01*
G01X491782Y631936D02*
X504782D01*
G01X492580Y647370D02*
Y680740D01*
G01X483940Y645204D02*
X490140D01*
G01X493688Y653113D02*
Y657713D01*
G01X503888Y653113D02*
X493688D01*
G01Y657713D02*
X503888D01*
G01X483940Y654004D02*
Y657204D01*
G01X490140Y654004D02*
X483940D01*
G01X490140Y657204D02*
Y654004D01*
G01X483940Y657204D02*
X490140D01*
G01X483940Y650004D02*
Y653204D01*
G01X490140Y650004D02*
X483940D01*
G01X490140Y653204D02*
Y650004D01*
G01X483940Y653204D02*
X490140D01*
G01Y649204D02*
Y646004D01*
G01X483940Y649204D02*
X490140D01*
G01X483940Y646004D02*
Y649204D01*
G01X490140Y646004D02*
X483940D01*
G01X495261Y678255D02*
X495031Y678410D01*
X494763Y678513D01*
X494456D01*
X494111Y678358D01*
X493843Y678100D01*
X493651Y677790D01*
X493498Y677273D01*
X493460Y676808D01*
X493536Y676343D01*
X493651Y676033D01*
X493881Y675723D01*
X494150Y675516D01*
X494418Y675413D01*
X494686D01*
X494955Y675516D01*
X495185Y675671D01*
X495376Y675878D01*
G01X496866Y675775D02*
X497135Y675516D01*
X497441Y675413D01*
X497748Y675516D01*
X498016Y675826D01*
X498208Y676291D01*
X498285Y676756D01*
Y677325D01*
X498208Y677790D01*
X498016Y678203D01*
X497786Y678410D01*
X497518Y678513D01*
X497211Y678410D01*
X496981Y678203D01*
X496828Y677893D01*
X496751Y677480D01*
X496828Y677118D01*
X497020Y676756D01*
X497250Y676550D01*
X497518Y676498D01*
X497825Y676601D01*
X498055Y676860D01*
X498285Y677325D01*
G01X500618Y678513D02*
X500311Y678410D01*
X500081Y678151D01*
X499928Y677841D01*
X499813Y677428D01*
X499775Y676963D01*
X499813Y676498D01*
X499928Y676085D01*
X500081Y675775D01*
X500311Y675516D01*
X500618Y675413D01*
X500925Y675516D01*
X501155Y675775D01*
X501308Y676085D01*
X501423Y676498D01*
X501461Y676963D01*
X501423Y677428D01*
X501308Y677841D01*
X501155Y678151D01*
X500925Y678410D01*
X500618Y678513D01*
G01X502990Y677996D02*
X503220Y678306D01*
X503488Y678461D01*
X503795Y678513D01*
X504178Y678410D01*
X504446Y678151D01*
X504523Y677841D01*
X504485Y677531D01*
X504331Y677273D01*
X503565Y676756D01*
X503220Y676395D01*
X502990Y675878D01*
X502913Y675413D01*
X504523D01*
G01X495261Y674242D02*
X495031Y674397D01*
X494763Y674500D01*
X494456D01*
X494111Y674345D01*
X493843Y674087D01*
X493651Y673777D01*
X493498Y673260D01*
X493460Y672795D01*
X493536Y672330D01*
X493651Y672020D01*
X493881Y671710D01*
X494150Y671503D01*
X494418Y671400D01*
X494686D01*
X494955Y671503D01*
X495185Y671658D01*
X495376Y671865D01*
G01X496866Y671762D02*
X497135Y671503D01*
X497441Y671400D01*
X497748Y671503D01*
X498016Y671813D01*
X498208Y672278D01*
X498285Y672743D01*
Y673312D01*
X498208Y673777D01*
X498016Y674190D01*
X497786Y674397D01*
X497518Y674500D01*
X497211Y674397D01*
X496981Y674190D01*
X496828Y673880D01*
X496751Y673467D01*
X496828Y673105D01*
X497020Y672743D01*
X497250Y672537D01*
X497518Y672485D01*
X497825Y672588D01*
X498055Y672847D01*
X498285Y673312D01*
G01X500618Y674500D02*
X500311Y674397D01*
X500081Y674138D01*
X499928Y673828D01*
X499813Y673415D01*
X499775Y672950D01*
X499813Y672485D01*
X499928Y672072D01*
X500081Y671762D01*
X500311Y671503D01*
X500618Y671400D01*
X500925Y671503D01*
X501155Y671762D01*
X501308Y672072D01*
X501423Y672485D01*
X501461Y672950D01*
X501423Y673415D01*
X501308Y673828D01*
X501155Y674138D01*
X500925Y674397D01*
X500618Y674500D01*
G01X503718Y671400D02*
X503986Y671452D01*
X504293Y671607D01*
X504485Y671865D01*
X504561Y672227D01*
X504485Y672588D01*
X504255Y672898D01*
X503910Y673053D01*
X503526D01*
X503296Y673157D01*
X503105Y673415D01*
X503028Y673777D01*
X503143Y674138D01*
X503411Y674397D01*
X503718Y674500D01*
X504025Y674397D01*
X504293Y674138D01*
X504408Y673777D01*
X504331Y673415D01*
X504140Y673157D01*
X503910Y673053D01*
X503526D01*
X503181Y672898D01*
X502951Y672588D01*
X502875Y672227D01*
X502951Y671865D01*
X503143Y671607D01*
X503450Y671452D01*
X503718Y671400D01*
G01X483940Y674004D02*
Y677204D01*
G01X490140Y674004D02*
X483940D01*
G01X490140Y677204D02*
Y674004D01*
G01X483940Y670004D02*
Y673204D01*
G01X490140Y670004D02*
X483940D01*
G01X490140Y673204D02*
Y670004D01*
G01X483940Y673204D02*
X490140D01*
G01X483940Y666004D02*
Y669204D01*
G01X490140Y666004D02*
X483940D01*
G01X490140Y669204D02*
Y666004D01*
G01X483940Y669204D02*
X490140D01*
G01X493651Y667179D02*
Y670279D01*
X494610D01*
X494916Y670124D01*
X495108Y669917D01*
X495185Y669504D01*
X495108Y669091D01*
X494878Y668832D01*
X494610Y668677D01*
X493651D01*
G01X494610D02*
X495185Y667179D01*
G01X496790Y668471D02*
X497058Y668832D01*
X497288Y669039D01*
X497595Y669142D01*
X497863Y669039D01*
X498055Y668832D01*
X498208Y668522D01*
X498246Y668161D01*
X498208Y667851D01*
X498055Y667541D01*
X497825Y667282D01*
X497556Y667179D01*
X497250Y667282D01*
X496981Y667592D01*
X496828Y668057D01*
X496790Y668574D01*
X496866Y669246D01*
X496981Y669607D01*
X497173Y669969D01*
X497441Y670227D01*
X497710Y670279D01*
X497978Y670176D01*
X498170Y669917D01*
G01X500541Y667179D02*
X500618Y667851D01*
X500733Y668419D01*
X500886Y668936D01*
X501078Y669504D01*
X501385Y670279D01*
X499851D01*
G01X503066Y667541D02*
X503335Y667282D01*
X503641Y667179D01*
X503948Y667282D01*
X504216Y667592D01*
X504408Y668057D01*
X504485Y668522D01*
Y669091D01*
X504408Y669556D01*
X504216Y669969D01*
X503986Y670176D01*
X503718Y670279D01*
X503411Y670176D01*
X503181Y669969D01*
X503028Y669659D01*
X502951Y669246D01*
X503028Y668884D01*
X503220Y668522D01*
X503450Y668316D01*
X503718Y668264D01*
X504025Y668367D01*
X504255Y668626D01*
X504485Y669091D01*
G01X489353Y693596D02*
X488973Y693846D01*
X488530Y694013D01*
X488023D01*
X487453Y693763D01*
X487010Y693346D01*
X486693Y692846D01*
X486440Y692013D01*
X486377Y691263D01*
X486503Y690513D01*
X486693Y690013D01*
X487073Y689513D01*
X487517Y689180D01*
X487960Y689013D01*
X488403D01*
X488847Y689180D01*
X489227Y689430D01*
X489543Y689763D01*
G01X492580Y684250D02*
Y694860D01*
G01X484270Y685980D02*
Y694910D01*
G01X492550Y685980D02*
X484270D01*
G01X506540Y689556D02*
X494340D01*
G01X483940Y678028D02*
Y681228D01*
G01X490140Y678028D02*
X483940D01*
G01X490140Y681228D02*
Y678028D01*
G01X483940Y681228D02*
X490140D01*
G01X487040Y678128D02*
Y681128D01*
G01X483940Y677204D02*
X490140D01*
G01X484174Y700999D02*
Y699232D01*
G01X494475Y701182D02*
Y698960D01*
X494628Y698495D01*
X494935Y698185D01*
X495318Y698082D01*
X495701Y698185D01*
X496008Y698495D01*
X496161Y698960D01*
Y701182D01*
G01X498418Y698082D02*
Y701182D01*
X497958Y700562D01*
G01Y698082D02*
X498878D01*
G01X500790Y700665D02*
X501020Y700975D01*
X501288Y701130D01*
X501595Y701182D01*
X501978Y701079D01*
X502246Y700820D01*
X502323Y700510D01*
X502285Y700200D01*
X502131Y699942D01*
X501365Y699425D01*
X501020Y699064D01*
X500790Y698547D01*
X500713Y698082D01*
X502323D01*
G01X503966Y698444D02*
X504235Y698185D01*
X504541Y698082D01*
X504848Y698185D01*
X505116Y698495D01*
X505308Y698960D01*
X505385Y699425D01*
Y699994D01*
X505308Y700459D01*
X505116Y700872D01*
X504886Y701079D01*
X504618Y701182D01*
X504311Y701079D01*
X504081Y700872D01*
X503928Y700562D01*
X503851Y700149D01*
X503928Y699787D01*
X504120Y699425D01*
X504350Y699219D01*
X504618Y699167D01*
X504925Y699270D01*
X505155Y699529D01*
X505385Y699994D01*
G01X482640Y711356D02*
Y700956D01*
G01Y699156D02*
Y700956D01*
G01X491922Y704982D02*
Y708182D01*
G01X498122Y704982D02*
X491922D01*
G01X484845Y718644D02*
X482345D01*
Y719178D01*
X482470Y719391D01*
X482637Y719551D01*
X482887Y719684D01*
X483178Y719791D01*
X483595Y719818D01*
X484012Y719791D01*
X484303Y719684D01*
X484553Y719551D01*
X484720Y719391D01*
X484845Y719178D01*
Y718644D01*
G01X482762Y720924D02*
X482512Y721084D01*
X482387Y721271D01*
X482345Y721484D01*
X482428Y721751D01*
X482637Y721938D01*
X482887Y721991D01*
X483137Y721964D01*
X483345Y721858D01*
X483762Y721324D01*
X484053Y721084D01*
X484470Y720924D01*
X484845Y720871D01*
Y721991D01*
G01X482762Y723124D02*
X482512Y723284D01*
X482387Y723471D01*
X482345Y723684D01*
X482428Y723951D01*
X482637Y724138D01*
X482887Y724191D01*
X483137Y724164D01*
X483345Y724058D01*
X483762Y723524D01*
X484053Y723284D01*
X484470Y723124D01*
X484845Y723071D01*
Y724191D01*
G01X491230Y719338D02*
X488730D01*
Y719872D01*
X488855Y720085D01*
X489022Y720245D01*
X489272Y720378D01*
X489563Y720485D01*
X489980Y720512D01*
X490397Y720485D01*
X490688Y720378D01*
X490938Y720245D01*
X491105Y720085D01*
X491230Y719872D01*
Y719338D01*
G01Y722125D02*
X488730D01*
X489230Y721805D01*
G01X491230D02*
Y722445D01*
G01Y724272D02*
X490688Y724325D01*
X490230Y724405D01*
X489813Y724512D01*
X489355Y724645D01*
X488730Y724858D01*
Y723792D01*
G01X488133Y718675D02*
X485633D01*
Y719209D01*
X485758Y719422D01*
X485925Y719582D01*
X486175Y719715D01*
X486466Y719822D01*
X486883Y719849D01*
X487300Y719822D01*
X487591Y719715D01*
X487841Y719582D01*
X488008Y719422D01*
X488133Y719209D01*
Y718675D01*
G01X486050Y720955D02*
X485800Y721115D01*
X485675Y721302D01*
X485633Y721515D01*
X485716Y721782D01*
X485925Y721969D01*
X486175Y722022D01*
X486425Y721995D01*
X486633Y721889D01*
X487050Y721355D01*
X487341Y721115D01*
X487758Y720955D01*
X488133Y720902D01*
Y722022D01*
G01X487633Y723075D02*
X487925Y723235D01*
X488091Y723449D01*
X488133Y723689D01*
X488091Y723902D01*
X487883Y724115D01*
X487633Y724249D01*
X487383Y724275D01*
X487091Y724222D01*
X486883Y724035D01*
X486800Y723849D01*
Y723609D01*
G01Y723849D02*
X486675Y724009D01*
X486466Y724142D01*
X486216Y724195D01*
X485966Y724142D01*
X485758Y724009D01*
X485633Y723769D01*
X485675Y723529D01*
X485841Y723289D01*
G01X491922Y716182D02*
X498122D01*
G01X491922Y712982D02*
Y716182D01*
G01X498122Y712982D02*
X491922D01*
G01Y720182D02*
X498122D01*
G01X491922Y716982D02*
Y720182D01*
G01X498122Y716982D02*
X491922D01*
G01Y708182D02*
X498122D01*
G01X491922Y712182D02*
X498122D01*
G01X491922Y708982D02*
Y712182D01*
G01X498122Y708982D02*
X491922D01*
G01X488840Y737556D02*
X485640D01*
G01X488840Y743756D02*
Y737556D01*
G01X485640D02*
Y743756D01*
G01X493140Y737556D02*
X489940D01*
G01X493140Y743756D02*
Y737556D01*
G01X489940D02*
Y743756D01*
G01X484540Y737556D02*
X481340D01*
G01X484540Y743756D02*
Y737556D01*
G01X481340D02*
Y743756D01*
G01X490940Y729156D02*
X493940D01*
G01X490840Y732256D02*
X494040D01*
G01X490840Y726056D02*
Y732256D01*
G01X494040Y726056D02*
X490840D01*
G01X494040Y732256D02*
Y726056D01*
G01X497440Y737556D02*
X494240D01*
G01D02*
Y743756D01*
G01X486340Y732256D02*
X489540D01*
G01X486340Y726056D02*
Y732256D01*
G01X489540Y726056D02*
X486340D01*
G01X489540Y732256D02*
Y726056D01*
G01X481030Y732273D02*
Y726073D01*
G01X481840Y732256D02*
X485040D01*
G01X481840Y726056D02*
Y732256D01*
G01X485040Y726056D02*
X481840D01*
G01X485040Y732256D02*
Y726056D01*
G01X480540Y743756D02*
Y737556D01*
G01X485640Y743756D02*
X488840D01*
G01X488740Y740656D02*
X485740D01*
G01X489940Y743756D02*
X493140D01*
G01X493040Y740656D02*
X490040D01*
G01X481340Y743756D02*
X484540D01*
G01X484440Y740656D02*
X481440D01*
G01X491281Y749753D02*
X491126Y749523D01*
X491023Y749255D01*
Y748948D01*
X491178Y748603D01*
X491436Y748335D01*
X491746Y748143D01*
X492263Y747990D01*
X492728Y747952D01*
X493193Y748028D01*
X493503Y748143D01*
X493813Y748373D01*
X494020Y748642D01*
X494123Y748910D01*
Y749178D01*
X494020Y749447D01*
X493865Y749677D01*
X493658Y749868D01*
G01X494123Y751933D02*
X493451Y752010D01*
X492883Y752125D01*
X492366Y752278D01*
X491798Y752470D01*
X491023Y752777D01*
Y751243D01*
G01X493503Y754267D02*
X493865Y754497D01*
X494071Y754803D01*
X494123Y755148D01*
X494071Y755455D01*
X493813Y755762D01*
X493503Y755953D01*
X493193Y755992D01*
X492831Y755915D01*
X492573Y755647D01*
X492470Y755378D01*
Y755033D01*
G01Y755378D02*
X492315Y755608D01*
X492056Y755800D01*
X491746Y755877D01*
X491436Y755800D01*
X491178Y755608D01*
X491023Y755263D01*
X491075Y754918D01*
X491281Y754573D01*
G01X494123Y758133D02*
X493451Y758210D01*
X492883Y758325D01*
X492366Y758478D01*
X491798Y758670D01*
X491023Y758977D01*
Y757443D01*
G01X494240Y743756D02*
X497440D01*
G01X497340Y740656D02*
X494340D01*
G01X489937Y748311D02*
X486837D01*
Y749270D01*
X486992Y749576D01*
X487199Y749768D01*
X487612Y749845D01*
X488025Y749768D01*
X488284Y749538D01*
X488439Y749270D01*
Y748311D01*
G01Y749270D02*
X489937Y749845D01*
G01Y752178D02*
X489885Y752446D01*
X489730Y752753D01*
X489472Y752945D01*
X489110Y753021D01*
X488749Y752945D01*
X488439Y752715D01*
X488284Y752370D01*
Y751986D01*
X488180Y751756D01*
X487922Y751565D01*
X487560Y751488D01*
X487199Y751603D01*
X486940Y751871D01*
X486837Y752178D01*
X486940Y752485D01*
X487199Y752753D01*
X487560Y752868D01*
X487922Y752791D01*
X488180Y752600D01*
X488284Y752370D01*
Y751986D01*
X488439Y751641D01*
X488749Y751411D01*
X489110Y751335D01*
X489472Y751411D01*
X489730Y751603D01*
X489885Y751910D01*
X489937Y752178D01*
G01X488645Y754550D02*
X488284Y754818D01*
X488077Y755048D01*
X487974Y755355D01*
X488077Y755623D01*
X488284Y755815D01*
X488594Y755968D01*
X488955Y756006D01*
X489265Y755968D01*
X489575Y755815D01*
X489834Y755585D01*
X489937Y755316D01*
X489834Y755010D01*
X489524Y754741D01*
X489059Y754588D01*
X488542Y754550D01*
X487870Y754626D01*
X487509Y754741D01*
X487147Y754933D01*
X486889Y755201D01*
X486837Y755470D01*
X486940Y755738D01*
X487199Y755930D01*
G01X486837Y758378D02*
X486940Y758071D01*
X487199Y757841D01*
X487509Y757688D01*
X487922Y757573D01*
X488387Y757535D01*
X488852Y757573D01*
X489265Y757688D01*
X489575Y757841D01*
X489834Y758071D01*
X489937Y758378D01*
X489834Y758685D01*
X489575Y758915D01*
X489265Y759068D01*
X488852Y759183D01*
X488387Y759221D01*
X487922Y759183D01*
X487509Y759068D01*
X487199Y758915D01*
X486940Y758685D01*
X486837Y758378D01*
G01X485437Y748311D02*
X482337D01*
Y749270D01*
X482492Y749576D01*
X482699Y749768D01*
X483112Y749845D01*
X483525Y749768D01*
X483784Y749538D01*
X483939Y749270D01*
Y748311D01*
G01Y749270D02*
X485437Y749845D01*
G01Y752178D02*
X485385Y752446D01*
X485230Y752753D01*
X484972Y752945D01*
X484610Y753021D01*
X484249Y752945D01*
X483939Y752715D01*
X483784Y752370D01*
Y751986D01*
X483680Y751756D01*
X483422Y751565D01*
X483060Y751488D01*
X482699Y751603D01*
X482440Y751871D01*
X482337Y752178D01*
X482440Y752485D01*
X482699Y752753D01*
X483060Y752868D01*
X483422Y752791D01*
X483680Y752600D01*
X483784Y752370D01*
Y751986D01*
X483939Y751641D01*
X484249Y751411D01*
X484610Y751335D01*
X484972Y751411D01*
X485230Y751603D01*
X485385Y751910D01*
X485437Y752178D01*
G01X484145Y754550D02*
X483784Y754818D01*
X483577Y755048D01*
X483474Y755355D01*
X483577Y755623D01*
X483784Y755815D01*
X484094Y755968D01*
X484455Y756006D01*
X484765Y755968D01*
X485075Y755815D01*
X485334Y755585D01*
X485437Y755316D01*
X485334Y755010D01*
X485024Y754741D01*
X484559Y754588D01*
X484042Y754550D01*
X483370Y754626D01*
X483009Y754741D01*
X482647Y754933D01*
X482389Y755201D01*
X482337Y755470D01*
X482440Y755738D01*
X482699Y755930D01*
G01X484817Y757535D02*
X485179Y757765D01*
X485385Y758071D01*
X485437Y758416D01*
X485385Y758723D01*
X485127Y759030D01*
X484817Y759221D01*
X484507Y759260D01*
X484145Y759183D01*
X483887Y758915D01*
X483784Y758646D01*
Y758301D01*
G01Y758646D02*
X483629Y758876D01*
X483370Y759068D01*
X483060Y759145D01*
X482750Y759068D01*
X482492Y758876D01*
X482337Y758531D01*
X482389Y758186D01*
X482595Y757841D01*
G01X497653Y747947D02*
X494553D01*
Y748906D01*
X494708Y749212D01*
X494915Y749404D01*
X495328Y749481D01*
X495741Y749404D01*
X496000Y749174D01*
X496155Y748906D01*
Y747947D01*
G01Y748906D02*
X497653Y749481D01*
G01X497291Y751162D02*
X497550Y751431D01*
X497653Y751737D01*
X497550Y752044D01*
X497240Y752312D01*
X496775Y752504D01*
X496310Y752581D01*
X495741D01*
X495276Y752504D01*
X494863Y752312D01*
X494656Y752082D01*
X494553Y751814D01*
X494656Y751507D01*
X494863Y751277D01*
X495173Y751124D01*
X495586Y751047D01*
X495948Y751124D01*
X496310Y751316D01*
X496516Y751546D01*
X496568Y751814D01*
X496465Y752121D01*
X496206Y752351D01*
X495741Y752581D01*
G01X497653Y754837D02*
X496981Y754914D01*
X496413Y755029D01*
X495896Y755182D01*
X495328Y755374D01*
X494553Y755681D01*
Y754147D01*
G01X497653Y758474D02*
X494553D01*
X496775Y757056D01*
Y758972D01*
G01X484231Y762135D02*
X484076Y761905D01*
X483973Y761637D01*
Y761330D01*
X484128Y760985D01*
X484386Y760717D01*
X484696Y760525D01*
X485213Y760372D01*
X485678Y760334D01*
X486143Y760410D01*
X486453Y760525D01*
X486763Y760755D01*
X486970Y761024D01*
X487073Y761292D01*
Y761560D01*
X486970Y761829D01*
X486815Y762059D01*
X486608Y762250D01*
G01X485781Y763664D02*
X485420Y763932D01*
X485213Y764162D01*
X485110Y764469D01*
X485213Y764737D01*
X485420Y764929D01*
X485730Y765082D01*
X486091Y765120D01*
X486401Y765082D01*
X486711Y764929D01*
X486970Y764699D01*
X487073Y764430D01*
X486970Y764124D01*
X486660Y763855D01*
X486195Y763702D01*
X485678Y763664D01*
X485006Y763740D01*
X484645Y763855D01*
X484283Y764047D01*
X484025Y764315D01*
X483973Y764584D01*
X484076Y764852D01*
X484335Y765044D01*
G01X484490Y766764D02*
X484180Y766994D01*
X484025Y767262D01*
X483973Y767569D01*
X484076Y767952D01*
X484335Y768220D01*
X484645Y768297D01*
X484955Y768259D01*
X485213Y768105D01*
X485730Y767339D01*
X486091Y766994D01*
X486608Y766764D01*
X487073Y766687D01*
Y768297D01*
G01X486711Y769940D02*
X486970Y770209D01*
X487073Y770515D01*
X486970Y770822D01*
X486660Y771090D01*
X486195Y771282D01*
X485730Y771359D01*
X485161D01*
X484696Y771282D01*
X484283Y771090D01*
X484076Y770860D01*
X483973Y770592D01*
X484076Y770285D01*
X484283Y770055D01*
X484593Y769902D01*
X485006Y769825D01*
X485368Y769902D01*
X485730Y770094D01*
X485936Y770324D01*
X485988Y770592D01*
X485885Y770899D01*
X485626Y771129D01*
X485161Y771359D01*
G01X488531Y762135D02*
X488376Y761905D01*
X488273Y761637D01*
Y761330D01*
X488428Y760985D01*
X488686Y760717D01*
X488996Y760525D01*
X489513Y760372D01*
X489978Y760334D01*
X490443Y760410D01*
X490753Y760525D01*
X491063Y760755D01*
X491270Y761024D01*
X491373Y761292D01*
Y761560D01*
X491270Y761829D01*
X491115Y762059D01*
X490908Y762250D01*
G01X490081Y763664D02*
X489720Y763932D01*
X489513Y764162D01*
X489410Y764469D01*
X489513Y764737D01*
X489720Y764929D01*
X490030Y765082D01*
X490391Y765120D01*
X490701Y765082D01*
X491011Y764929D01*
X491270Y764699D01*
X491373Y764430D01*
X491270Y764124D01*
X490960Y763855D01*
X490495Y763702D01*
X489978Y763664D01*
X489306Y763740D01*
X488945Y763855D01*
X488583Y764047D01*
X488325Y764315D01*
X488273Y764584D01*
X488376Y764852D01*
X488635Y765044D01*
G01X488790Y766764D02*
X488480Y766994D01*
X488325Y767262D01*
X488273Y767569D01*
X488376Y767952D01*
X488635Y768220D01*
X488945Y768297D01*
X489255Y768259D01*
X489513Y768105D01*
X490030Y767339D01*
X490391Y766994D01*
X490908Y766764D01*
X491373Y766687D01*
Y768297D01*
G01X490081Y769864D02*
X489720Y770132D01*
X489513Y770362D01*
X489410Y770669D01*
X489513Y770937D01*
X489720Y771129D01*
X490030Y771282D01*
X490391Y771320D01*
X490701Y771282D01*
X491011Y771129D01*
X491270Y770899D01*
X491373Y770630D01*
X491270Y770324D01*
X490960Y770055D01*
X490495Y769902D01*
X489978Y769864D01*
X489306Y769940D01*
X488945Y770055D01*
X488583Y770247D01*
X488325Y770515D01*
X488273Y770784D01*
X488376Y771052D01*
X488635Y771244D01*
G01X480371Y761991D02*
X480216Y761761D01*
X480113Y761493D01*
Y761186D01*
X480268Y760841D01*
X480526Y760573D01*
X480836Y760381D01*
X481353Y760228D01*
X481818Y760190D01*
X482283Y760266D01*
X482593Y760381D01*
X482903Y760611D01*
X483110Y760880D01*
X483213Y761148D01*
Y761416D01*
X483110Y761685D01*
X482955Y761915D01*
X482748Y762106D01*
G01X481921Y763520D02*
X481560Y763788D01*
X481353Y764018D01*
X481250Y764325D01*
X481353Y764593D01*
X481560Y764785D01*
X481870Y764938D01*
X482231Y764976D01*
X482541Y764938D01*
X482851Y764785D01*
X483110Y764555D01*
X483213Y764286D01*
X483110Y763980D01*
X482800Y763711D01*
X482335Y763558D01*
X481818Y763520D01*
X481146Y763596D01*
X480785Y763711D01*
X480423Y763903D01*
X480165Y764171D01*
X480113Y764440D01*
X480216Y764708D01*
X480475Y764900D01*
G01X482593Y766505D02*
X482955Y766735D01*
X483161Y767041D01*
X483213Y767386D01*
X483161Y767693D01*
X482903Y768000D01*
X482593Y768191D01*
X482283Y768230D01*
X481921Y768153D01*
X481663Y767885D01*
X481560Y767616D01*
Y767271D01*
G01Y767616D02*
X481405Y767846D01*
X481146Y768038D01*
X480836Y768115D01*
X480526Y768038D01*
X480268Y767846D01*
X480113Y767501D01*
X480165Y767156D01*
X480371Y766811D01*
G01X480630Y769720D02*
X480320Y769950D01*
X480165Y770218D01*
X480113Y770525D01*
X480216Y770908D01*
X480475Y771176D01*
X480785Y771253D01*
X481095Y771215D01*
X481353Y771061D01*
X481870Y770295D01*
X482231Y769950D01*
X482748Y769720D01*
X483213Y769643D01*
Y771253D01*
G01X492831Y762135D02*
X492676Y761905D01*
X492573Y761637D01*
Y761330D01*
X492728Y760985D01*
X492986Y760717D01*
X493296Y760525D01*
X493813Y760372D01*
X494278Y760334D01*
X494743Y760410D01*
X495053Y760525D01*
X495363Y760755D01*
X495570Y761024D01*
X495673Y761292D01*
Y761560D01*
X495570Y761829D01*
X495415Y762059D01*
X495208Y762250D01*
G01X494381Y763664D02*
X494020Y763932D01*
X493813Y764162D01*
X493710Y764469D01*
X493813Y764737D01*
X494020Y764929D01*
X494330Y765082D01*
X494691Y765120D01*
X495001Y765082D01*
X495311Y764929D01*
X495570Y764699D01*
X495673Y764430D01*
X495570Y764124D01*
X495260Y763855D01*
X494795Y763702D01*
X494278Y763664D01*
X493606Y763740D01*
X493245Y763855D01*
X492883Y764047D01*
X492625Y764315D01*
X492573Y764584D01*
X492676Y764852D01*
X492935Y765044D01*
G01X493090Y766764D02*
X492780Y766994D01*
X492625Y767262D01*
X492573Y767569D01*
X492676Y767952D01*
X492935Y768220D01*
X493245Y768297D01*
X493555Y768259D01*
X493813Y768105D01*
X494330Y767339D01*
X494691Y766994D01*
X495208Y766764D01*
X495673Y766687D01*
Y768297D01*
G01X495053Y769749D02*
X495415Y769979D01*
X495621Y770285D01*
X495673Y770630D01*
X495621Y770937D01*
X495363Y771244D01*
X495053Y771435D01*
X494743Y771474D01*
X494381Y771397D01*
X494123Y771129D01*
X494020Y770860D01*
Y770515D01*
G01Y770860D02*
X493865Y771090D01*
X493606Y771282D01*
X493296Y771359D01*
X492986Y771282D01*
X492728Y771090D01*
X492573Y770745D01*
X492625Y770400D01*
X492831Y770055D01*
G01X503493Y-244364D02*
Y-236364D01*
X502293Y-237964D01*
G01Y-244364D02*
X504693D01*
G01X509593Y-241031D02*
X510293Y-240097D01*
X510893Y-239564D01*
X511693Y-239297D01*
X512393Y-239564D01*
X512893Y-240097D01*
X513293Y-240897D01*
X513393Y-241831D01*
X513293Y-242631D01*
X512893Y-243431D01*
X512293Y-244097D01*
X511593Y-244364D01*
X510793Y-244097D01*
X510093Y-243298D01*
X509693Y-242097D01*
X509593Y-240764D01*
X509793Y-239031D01*
X510093Y-238097D01*
X510593Y-237164D01*
X511293Y-236497D01*
X511993Y-236364D01*
X512693Y-236631D01*
X513193Y-237297D01*
G01X513779Y12973D02*
X513399Y13223D01*
X512956Y13390D01*
X512449D01*
X511879Y13140D01*
X511436Y12723D01*
X511119Y12223D01*
X510866Y11390D01*
X510803Y10640D01*
X510929Y9890D01*
X511119Y9390D01*
X511499Y8890D01*
X511943Y8557D01*
X512386Y8390D01*
X512829D01*
X513273Y8557D01*
X513653Y8807D01*
X513969Y9140D01*
G01X516219Y8390D02*
Y13390D01*
X517739D01*
X518246Y13140D01*
X518626Y12557D01*
X518753Y11890D01*
X518626Y11223D01*
X518309Y10723D01*
X517739Y10473D01*
X516219D01*
G01X521319Y13390D02*
Y8390D01*
X523853D01*
G01X526293D02*
Y13390D01*
X527559D01*
X528066Y13140D01*
X528446Y12807D01*
X528763Y12307D01*
X529016Y11723D01*
X529079Y10890D01*
X529016Y10057D01*
X528763Y9473D01*
X528446Y8973D01*
X528066Y8640D01*
X527559Y8390D01*
X526293D01*
G01X532786D02*
Y13390D01*
X532026Y12390D01*
G01Y8390D02*
X533546D01*
G01X541719Y9390D02*
X542036Y8890D01*
X542416Y8557D01*
X542859Y8390D01*
X543366Y8557D01*
X543746Y8890D01*
X544126Y9390D01*
X544253Y10057D01*
Y13390D01*
G01X548086D02*
Y8390D01*
G01X546629Y13390D02*
X549543D01*
G01X551603Y8390D02*
X553186Y13390D01*
X554769Y8390D01*
G01X554199Y10140D02*
X552173D01*
G01X558666Y10890D02*
X559933D01*
Y9390D01*
X559553Y8890D01*
X559109Y8557D01*
X558476Y8390D01*
X557843Y8557D01*
X557399Y8890D01*
X557019Y9390D01*
X556766Y9973D01*
X556639Y10640D01*
Y11223D01*
X556766Y11723D01*
X557019Y12307D01*
X557399Y12807D01*
X557779Y13140D01*
X558286Y13390D01*
X558729D01*
X559236Y13223D01*
X559616Y12890D01*
G01X511103Y14831D02*
X561835D01*
Y6092D01*
X509918D01*
Y14831D01*
X511103D01*
G01X503721Y26355D02*
Y29455D01*
X503261Y28835D01*
G01Y26355D02*
X504181D01*
G01X506821Y29455D02*
X506514Y29352D01*
X506284Y29093D01*
X506131Y28783D01*
X506016Y28370D01*
X505978Y27905D01*
X506016Y27440D01*
X506131Y27027D01*
X506284Y26717D01*
X506514Y26458D01*
X506821Y26355D01*
X507128Y26458D01*
X507358Y26717D01*
X507511Y27027D01*
X507626Y27440D01*
X507664Y27905D01*
X507626Y28370D01*
X507511Y28783D01*
X507358Y29093D01*
X507128Y29352D01*
X506821Y29455D01*
G01X510483Y18120D02*
X510675Y17810D01*
X510905Y17603D01*
X511173Y17500D01*
X511480Y17603D01*
X511710Y17810D01*
X511940Y18120D01*
X512017Y18533D01*
Y20600D01*
G01X513622Y20083D02*
X513852Y20393D01*
X514120Y20548D01*
X514427Y20600D01*
X514810Y20497D01*
X515078Y20238D01*
X515155Y19928D01*
X515117Y19618D01*
X514963Y19360D01*
X514197Y18843D01*
X513852Y18482D01*
X513622Y17965D01*
X513545Y17500D01*
X515155D01*
G01X517450Y20600D02*
X517143Y20497D01*
X516913Y20238D01*
X516760Y19928D01*
X516645Y19515D01*
X516607Y19050D01*
X516645Y18585D01*
X516760Y18172D01*
X516913Y17862D01*
X517143Y17603D01*
X517450Y17500D01*
X517757Y17603D01*
X517987Y17862D01*
X518140Y18172D01*
X518255Y18585D01*
X518293Y19050D01*
X518255Y19515D01*
X518140Y19928D01*
X517987Y20238D01*
X517757Y20497D01*
X517450Y20600D01*
G01X508796Y23409D02*
Y44197D01*
G01X560764Y23409D02*
X508796D01*
G01X506294Y37486D02*
X506563Y37227D01*
X506869Y37124D01*
X507176Y37227D01*
X507444Y37537D01*
X507636Y38002D01*
X507713Y38467D01*
Y39036D01*
X507636Y39501D01*
X507444Y39914D01*
X507214Y40121D01*
X506946Y40224D01*
X506639Y40121D01*
X506409Y39914D01*
X506256Y39604D01*
X506179Y39191D01*
X506256Y38829D01*
X506448Y38467D01*
X506678Y38261D01*
X506946Y38209D01*
X507253Y38312D01*
X507483Y38571D01*
X507713Y39036D01*
G01X508796Y44197D02*
X560764D01*
G01X496829Y59875D02*
X497336Y59458D01*
X497906Y59208D01*
X498412D01*
X498919Y59458D01*
X499299Y59875D01*
X499489Y60458D01*
X499362Y61041D01*
X499046Y61541D01*
X498476Y61875D01*
X497716Y62041D01*
X497272Y62375D01*
X497082Y62958D01*
X497209Y63541D01*
X497526Y63958D01*
X497969Y64208D01*
X498412D01*
X498856Y64041D01*
X499236Y63625D01*
G01X501676Y59208D02*
X503259Y64208D01*
X504842Y59208D01*
G01X504272Y60958D02*
X502246D01*
G01X508359Y64208D02*
Y59208D01*
G01X506902Y64208D02*
X509816D01*
G01X511876Y59208D02*
X513459Y64208D01*
X515042Y59208D01*
G01X514472Y60958D02*
X512446D01*
G01X522266Y59208D02*
Y64208D01*
X523532D01*
X524039Y63958D01*
X524419Y63625D01*
X524736Y63125D01*
X524989Y62541D01*
X525052Y61708D01*
X524989Y60875D01*
X524736Y60291D01*
X524419Y59791D01*
X524039Y59458D01*
X523532Y59208D01*
X522266D01*
G01X528759D02*
X528252Y59291D01*
X527809Y59625D01*
X527429Y60125D01*
X527176Y60708D01*
X527049Y61375D01*
Y62041D01*
X527176Y62708D01*
X527429Y63291D01*
X527809Y63791D01*
X528252Y64125D01*
X528759Y64208D01*
X529266Y64125D01*
X529709Y63791D01*
X530089Y63291D01*
X530342Y62708D01*
X530469Y62041D01*
Y61375D01*
X530342Y60708D01*
X530089Y60125D01*
X529709Y59625D01*
X529266Y59291D01*
X528759Y59208D01*
G01X532212D02*
Y64208D01*
X533859Y60041D01*
X535506Y64208D01*
Y59208D01*
G01X542792D02*
Y64208D01*
X544312D01*
X544819Y63958D01*
X545199Y63375D01*
X545326Y62708D01*
X545199Y62041D01*
X544882Y61541D01*
X544312Y61291D01*
X542792D01*
G01X547259Y64208D02*
X548146Y59208D01*
X549159Y64208D01*
X550172Y59208D01*
X551059Y64208D01*
G01X552992Y59208D02*
Y64208D01*
X554576D01*
X555082Y63958D01*
X555399Y63625D01*
X555526Y62958D01*
X555399Y62291D01*
X555019Y61875D01*
X554576Y61625D01*
X552992D01*
G01X554576D02*
X555526Y59208D01*
G01X496542Y65281D02*
X556464D01*
Y58011D01*
X496102D01*
Y65281D01*
X496542D01*
G01X510462Y84020D02*
X507362D01*
Y84979D01*
X507517Y85285D01*
X507724Y85477D01*
X508137Y85554D01*
X508550Y85477D01*
X508809Y85247D01*
X508964Y84979D01*
Y84020D01*
G01Y84979D02*
X510462Y85554D01*
G01Y87887D02*
X507362D01*
X507982Y87427D01*
G01X510462D02*
Y88347D01*
G01Y90987D02*
X507362D01*
X507982Y90527D01*
G01X510462D02*
Y91447D01*
G01Y94547D02*
X507362D01*
X509584Y93129D01*
Y95045D01*
G01X510462Y97187D02*
X507362D01*
X507982Y96727D01*
G01X510462D02*
Y97647D01*
G01X498462Y84020D02*
X495362D01*
Y84979D01*
X495517Y85285D01*
X495724Y85477D01*
X496137Y85554D01*
X496550Y85477D01*
X496809Y85247D01*
X496964Y84979D01*
Y84020D01*
G01Y84979D02*
X498462Y85554D01*
G01Y87887D02*
X495362D01*
X495982Y87427D01*
G01X498462D02*
Y88347D01*
G01Y90987D02*
X495362D01*
X495982Y90527D01*
G01X498462D02*
Y91447D01*
G01Y94547D02*
X495362D01*
X497584Y93129D01*
Y95045D01*
G01X497842Y96344D02*
X498204Y96574D01*
X498410Y96880D01*
X498462Y97225D01*
X498410Y97532D01*
X498152Y97839D01*
X497842Y98030D01*
X497532Y98069D01*
X497170Y97992D01*
X496912Y97724D01*
X496809Y97455D01*
Y97110D01*
G01Y97455D02*
X496654Y97685D01*
X496395Y97877D01*
X496085Y97954D01*
X495775Y97877D01*
X495517Y97685D01*
X495362Y97340D01*
X495414Y96995D01*
X495620Y96650D01*
G01X506462Y84020D02*
X503362D01*
Y84979D01*
X503517Y85285D01*
X503724Y85477D01*
X504137Y85554D01*
X504550Y85477D01*
X504809Y85247D01*
X504964Y84979D01*
Y84020D01*
G01Y84979D02*
X506462Y85554D01*
G01Y87887D02*
X503362D01*
X503982Y87427D01*
G01X506462D02*
Y88347D01*
G01Y90987D02*
X503362D01*
X503982Y90527D01*
G01X506462D02*
Y91447D01*
G01Y94547D02*
X503362D01*
X505584Y93129D01*
Y95045D01*
G01X503879Y96459D02*
X503569Y96689D01*
X503414Y96957D01*
X503362Y97264D01*
X503465Y97647D01*
X503724Y97915D01*
X504034Y97992D01*
X504344Y97954D01*
X504602Y97800D01*
X505119Y97034D01*
X505480Y96689D01*
X505997Y96459D01*
X506462Y96382D01*
Y97992D01*
G01X502462Y84020D02*
X499362D01*
Y84979D01*
X499517Y85285D01*
X499724Y85477D01*
X500137Y85554D01*
X500550Y85477D01*
X500809Y85247D01*
X500964Y84979D01*
Y84020D01*
G01Y84979D02*
X502462Y85554D01*
G01Y87887D02*
X499362D01*
X499982Y87427D01*
G01X502462D02*
Y88347D01*
G01Y90987D02*
X499362D01*
X499982Y90527D01*
G01X502462D02*
Y91447D01*
G01Y94547D02*
X499362D01*
X501584Y93129D01*
Y95045D01*
G01X499362Y97187D02*
X499465Y96880D01*
X499724Y96650D01*
X500034Y96497D01*
X500447Y96382D01*
X500912Y96344D01*
X501377Y96382D01*
X501790Y96497D01*
X502100Y96650D01*
X502359Y96880D01*
X502462Y97187D01*
X502359Y97494D01*
X502100Y97724D01*
X501790Y97877D01*
X501377Y97992D01*
X500912Y98030D01*
X500447Y97992D01*
X500034Y97877D01*
X499724Y97724D01*
X499465Y97494D01*
X499362Y97187D01*
G01X500805Y114325D02*
Y108325D01*
G01X510555Y107704D02*
Y101504D01*
G01X507355Y107704D02*
X510555D01*
G01Y101504D02*
X507355D01*
G01D02*
Y107704D01*
G01X495355D02*
X498555D01*
G01D02*
Y101504D01*
G01D02*
X495355D01*
G01D02*
Y107704D01*
G01X503355D02*
X506555D01*
G01D02*
Y101504D01*
G01D02*
X503355D01*
G01D02*
Y107704D01*
G01X499355D02*
X502555D01*
G01D02*
Y101504D01*
G01D02*
X499355D01*
G01D02*
Y107704D01*
G01X501100Y201160D02*
X501470D01*
G01X497660Y198560D02*
Y192920D01*
G01X501470Y201160D02*
Y207210D01*
G01X497660Y198560D02*
X566982D01*
Y194785D01*
X593031D01*
Y221660D01*
X597526D01*
Y229080D01*
X597430D01*
Y229440D01*
G01X506805Y189925D02*
Y195925D01*
G01X496905Y189925D02*
Y192925D01*
G01X496876Y200228D02*
Y194028D01*
G01X509900Y197200D02*
X506700D01*
G01D02*
Y203400D01*
G01X509900D02*
Y197200D01*
G01X502452Y200621D02*
Y206821D01*
G01X505652D02*
Y200621D01*
G01D02*
X502452D01*
G01X510600Y197100D02*
Y203300D01*
X513800D01*
Y197100D01*
X510600D01*
G01X507600Y206680D02*
X540090D01*
G01X509190Y207917D02*
X495790D01*
G01X501490Y216717D02*
X495790D01*
G01X509190D02*
X503490D01*
G01X495790Y207917D02*
Y216717D01*
G01X509190D02*
Y207917D01*
G01X503490Y216717D02*
X502490Y215117D01*
G01D02*
X501490Y216717D01*
G01X509267Y217722D02*
X495867D01*
G01D02*
Y226522D01*
G01X509267D02*
Y217722D01*
G01X510560Y209925D02*
Y216125D01*
G01D02*
X513760D01*
G01Y209925D02*
X510560D01*
G01X506700Y203400D02*
X509900D01*
G01X502452Y206821D02*
X505652D01*
G01X502393Y230656D02*
Y228434D01*
X502546Y227969D01*
X502853Y227659D01*
X503236Y227556D01*
X503619Y227659D01*
X503926Y227969D01*
X504079Y228434D01*
Y230656D01*
G01X506336Y227556D02*
Y230656D01*
X505876Y230036D01*
G01Y227556D02*
X506796D01*
G01X508593Y228176D02*
X508823Y227814D01*
X509129Y227608D01*
X509474Y227556D01*
X509781Y227608D01*
X510088Y227866D01*
X510279Y228176D01*
X510318Y228486D01*
X510241Y228848D01*
X509973Y229106D01*
X509704Y229209D01*
X509359D01*
G01X509704D02*
X509934Y229364D01*
X510126Y229623D01*
X510203Y229933D01*
X510126Y230243D01*
X509934Y230501D01*
X509589Y230656D01*
X509244Y230604D01*
X508899Y230398D01*
G01X511808Y228848D02*
X512076Y229209D01*
X512306Y229416D01*
X512613Y229519D01*
X512881Y229416D01*
X513073Y229209D01*
X513226Y228899D01*
X513264Y228538D01*
X513226Y228228D01*
X513073Y227918D01*
X512843Y227659D01*
X512574Y227556D01*
X512268Y227659D01*
X511999Y227969D01*
X511846Y228434D01*
X511808Y228951D01*
X511884Y229623D01*
X511999Y229984D01*
X512191Y230346D01*
X512459Y230604D01*
X512728Y230656D01*
X512996Y230553D01*
X513188Y230294D01*
G01X502136Y234756D02*
Y232534D01*
X502289Y232069D01*
X502596Y231759D01*
X502979Y231656D01*
X503362Y231759D01*
X503669Y232069D01*
X503822Y232534D01*
Y234756D01*
G01X506079Y231656D02*
Y234756D01*
X505619Y234136D01*
G01Y231656D02*
X506539D01*
G01X508336Y232276D02*
X508566Y231914D01*
X508872Y231708D01*
X509217Y231656D01*
X509524Y231708D01*
X509831Y231966D01*
X510022Y232276D01*
X510061Y232586D01*
X509984Y232948D01*
X509716Y233206D01*
X509447Y233309D01*
X509102D01*
G01X509447D02*
X509677Y233464D01*
X509869Y233723D01*
X509946Y234033D01*
X509869Y234343D01*
X509677Y234601D01*
X509332Y234756D01*
X508987Y234704D01*
X508642Y234498D01*
G01X511436Y232121D02*
X511666Y231863D01*
X511934Y231708D01*
X512279Y231656D01*
X512624Y231759D01*
X512892Y231966D01*
X513084Y232328D01*
X513122Y232741D01*
X513046Y233154D01*
X512854Y233413D01*
X512586Y233619D01*
X512317Y233671D01*
X512049Y233619D01*
X511704Y233413D01*
X511819Y234756D01*
X512854D01*
G01X501567Y226522D02*
X495867D01*
G01X509267D02*
X503567D01*
G01D02*
X502567Y224922D01*
G01D02*
X501567Y226522D01*
G01X500798Y232420D02*
Y229220D01*
G01X498035Y247493D02*
Y268675D01*
G01X518507Y247493D02*
X509846D01*
G01D02*
X508271Y250584D01*
G01D02*
X506696Y247493D01*
G01D02*
X498035D01*
G01X496832Y244477D02*
Y241277D01*
G01X512800Y236083D02*
X509700D01*
Y237042D01*
X509855Y237348D01*
X510062Y237540D01*
X510475Y237617D01*
X510888Y237540D01*
X511147Y237310D01*
X511302Y237042D01*
Y236083D01*
G01Y237042D02*
X512800Y237617D01*
G01X512335Y239107D02*
X512593Y239337D01*
X512748Y239605D01*
X512800Y239950D01*
X512697Y240295D01*
X512490Y240563D01*
X512128Y240755D01*
X511715Y240793D01*
X511302Y240717D01*
X511043Y240525D01*
X510837Y240257D01*
X510785Y239988D01*
X510837Y239720D01*
X511043Y239375D01*
X509700Y239490D01*
Y240525D01*
G01X512800Y243050D02*
X509700D01*
X510320Y242590D01*
G01X512800D02*
Y243510D01*
G01X512438Y245498D02*
X512697Y245767D01*
X512800Y246073D01*
X512697Y246380D01*
X512387Y246648D01*
X511922Y246840D01*
X511457Y246917D01*
X510888D01*
X510423Y246840D01*
X510010Y246648D01*
X509803Y246418D01*
X509700Y246150D01*
X509803Y245843D01*
X510010Y245613D01*
X510320Y245460D01*
X510733Y245383D01*
X511095Y245460D01*
X511457Y245652D01*
X511663Y245882D01*
X511715Y246150D01*
X511612Y246457D01*
X511353Y246687D01*
X510888Y246917D01*
G01X508300Y236183D02*
X505200D01*
Y237142D01*
X505355Y237448D01*
X505562Y237640D01*
X505975Y237717D01*
X506388Y237640D01*
X506647Y237410D01*
X506802Y237142D01*
Y236183D01*
G01Y237142D02*
X508300Y237717D01*
G01X507835Y239207D02*
X508093Y239437D01*
X508248Y239705D01*
X508300Y240050D01*
X508197Y240395D01*
X507990Y240663D01*
X507628Y240855D01*
X507215Y240893D01*
X506802Y240817D01*
X506543Y240625D01*
X506337Y240357D01*
X506285Y240088D01*
X506337Y239820D01*
X506543Y239475D01*
X505200Y239590D01*
Y240625D01*
G01X508300Y243150D02*
X505200D01*
X505820Y242690D01*
G01X508300D02*
Y243610D01*
G01X507008Y245522D02*
X506647Y245790D01*
X506440Y246020D01*
X506337Y246327D01*
X506440Y246595D01*
X506647Y246787D01*
X506957Y246940D01*
X507318Y246978D01*
X507628Y246940D01*
X507938Y246787D01*
X508197Y246557D01*
X508300Y246288D01*
X508197Y245982D01*
X507887Y245713D01*
X507422Y245560D01*
X506905Y245522D01*
X506233Y245598D01*
X505872Y245713D01*
X505510Y245905D01*
X505252Y246173D01*
X505200Y246442D01*
X505303Y246710D01*
X505562Y246902D01*
G01X500425Y272830D02*
Y270608D01*
X500578Y270143D01*
X500885Y269833D01*
X501268Y269730D01*
X501651Y269833D01*
X501958Y270143D01*
X502111Y270608D01*
Y272830D01*
G01X503525Y270350D02*
X503755Y269988D01*
X504061Y269782D01*
X504406Y269730D01*
X504713Y269782D01*
X505020Y270040D01*
X505211Y270350D01*
X505250Y270660D01*
X505173Y271022D01*
X504905Y271280D01*
X504636Y271383D01*
X504291D01*
G01X504636D02*
X504866Y271538D01*
X505058Y271797D01*
X505135Y272107D01*
X505058Y272417D01*
X504866Y272675D01*
X504521Y272830D01*
X504176Y272778D01*
X503831Y272572D01*
G01X507468Y269730D02*
Y272830D01*
X507008Y272210D01*
G01Y269730D02*
X507928D01*
G01X498035Y268675D02*
X518507D01*
G01X511032Y298979D02*
G02I-3543J0D01*
G01X508986Y415799D02*
Y417194D01*
X508219Y418899D01*
G01X509753D02*
X508986Y417194D01*
G01X512086Y415799D02*
Y418899D01*
X511626Y418279D01*
G01Y415799D02*
X512546D01*
G01X499068Y421715D02*
X499228Y421423D01*
X499442Y421257D01*
X499682Y421215D01*
X499895Y421257D01*
X500108Y421465D01*
X500242Y421715D01*
X500268Y421965D01*
X500215Y422257D01*
X500028Y422465D01*
X499842Y422548D01*
X499602D01*
G01X499842D02*
X500002Y422673D01*
X500135Y422882D01*
X500188Y423132D01*
X500135Y423382D01*
X500002Y423590D01*
X499762Y423715D01*
X499522Y423673D01*
X499282Y423507D01*
G01X501136Y419990D02*
Y432590D01*
G01X516536Y419990D02*
X501136D01*
G01X507005Y435225D02*
Y438225D01*
G01X503905Y435125D02*
Y438325D01*
G01X510105Y435125D02*
X503905D01*
G01X510105Y438325D02*
Y435125D01*
G01X503905Y438325D02*
X510105D01*
G01X501487Y439267D02*
Y442367D01*
X502446D01*
X502752Y442212D01*
X502944Y442005D01*
X503021Y441592D01*
X502944Y441179D01*
X502714Y440920D01*
X502446Y440765D01*
X501487D01*
G01X502446D02*
X503021Y439267D01*
G01X505814D02*
Y442367D01*
X504396Y440145D01*
X506312D01*
G01X499329Y433236D02*
X499489Y433486D01*
X499676Y433611D01*
X499889Y433653D01*
X500156Y433570D01*
X500343Y433361D01*
X500396Y433111D01*
X500369Y432861D01*
X500263Y432653D01*
X499729Y432236D01*
X499489Y431945D01*
X499329Y431528D01*
X499276Y431153D01*
X500396D01*
G01X501136Y432590D02*
X516536D01*
G01X503974Y450487D02*
X504134Y450279D01*
X504321Y450154D01*
X504561Y450112D01*
X504801Y450195D01*
X504988Y450362D01*
X505121Y450654D01*
X505148Y450987D01*
X505094Y451320D01*
X504961Y451529D01*
X504774Y451695D01*
X504588Y451737D01*
X504401Y451695D01*
X504161Y451529D01*
X504241Y452612D01*
X504961D01*
G01X506254Y451154D02*
X506441Y451445D01*
X506601Y451612D01*
X506814Y451695D01*
X507001Y451612D01*
X507134Y451445D01*
X507241Y451195D01*
X507268Y450904D01*
X507241Y450654D01*
X507134Y450404D01*
X506974Y450195D01*
X506788Y450112D01*
X506574Y450195D01*
X506388Y450445D01*
X506281Y450820D01*
X506254Y451237D01*
X506308Y451779D01*
X506388Y452070D01*
X506521Y452362D01*
X506708Y452570D01*
X506894Y452612D01*
X507081Y452529D01*
X507214Y452320D01*
G01X506940Y453962D02*
X505140D01*
G01X509464Y451370D02*
Y450680D01*
G01D02*
X511464Y448680D01*
G01X496220Y448161D02*
Y451361D01*
G01X502420Y448161D02*
X496220D01*
G01X502420Y451361D02*
Y448161D01*
G01X496220Y451361D02*
X502420D01*
G01X497131Y452468D02*
Y455568D01*
X498090D01*
X498396Y455413D01*
X498588Y455206D01*
X498665Y454793D01*
X498588Y454380D01*
X498358Y454121D01*
X498090Y453966D01*
X497131D01*
G01X498090D02*
X498665Y452468D01*
G01X500921D02*
X500998Y453140D01*
X501113Y453708D01*
X501266Y454225D01*
X501458Y454793D01*
X501765Y455568D01*
X500231D01*
G01X496293Y443694D02*
Y446894D01*
G01X502493Y443694D02*
X496293D01*
G01X502493Y446894D02*
Y443694D01*
G01X496293Y446894D02*
X502493D01*
G01X507705Y439525D02*
Y442725D01*
G01X513905Y439525D02*
X507705D01*
G01Y442725D02*
X513905D01*
G01X506940Y469762D02*
X505140D01*
G01X506890Y461912D02*
X503390D01*
G01X497241Y456616D02*
Y459716D01*
X498200D01*
X498506Y459561D01*
X498698Y459354D01*
X498775Y458941D01*
X498698Y458528D01*
X498468Y458269D01*
X498200Y458114D01*
X497241D01*
G01X498200D02*
X498775Y456616D01*
G01X501108D02*
X501376Y456668D01*
X501683Y456823D01*
X501875Y457081D01*
X501951Y457443D01*
X501875Y457804D01*
X501645Y458114D01*
X501300Y458269D01*
X500916D01*
X500686Y458373D01*
X500495Y458631D01*
X500418Y458993D01*
X500533Y459354D01*
X500801Y459613D01*
X501108Y459716D01*
X501415Y459613D01*
X501683Y459354D01*
X501798Y458993D01*
X501721Y458631D01*
X501530Y458373D01*
X501300Y458269D01*
X500916D01*
X500571Y458114D01*
X500341Y457804D01*
X500265Y457443D01*
X500341Y457081D01*
X500533Y456823D01*
X500840Y456668D01*
X501108Y456616D01*
G01X509777Y477895D02*
Y480395D01*
X508790Y478603D01*
X510124D01*
G01X511150Y479978D02*
X511310Y480228D01*
X511497Y480353D01*
X511710Y480395D01*
X511977Y480312D01*
X512164Y480103D01*
X512217Y479853D01*
X512190Y479603D01*
X512084Y479395D01*
X511550Y478978D01*
X511310Y478687D01*
X511150Y478270D01*
X511097Y477895D01*
X512217D01*
G01X506186Y473833D02*
Y476333D01*
X505199Y474541D01*
X506533D01*
G01X507479Y474333D02*
X507639Y474041D01*
X507853Y473875D01*
X508093Y473833D01*
X508306Y473875D01*
X508519Y474083D01*
X508653Y474333D01*
X508679Y474583D01*
X508626Y474875D01*
X508439Y475083D01*
X508253Y475166D01*
X508013D01*
G01X508253D02*
X508413Y475291D01*
X508546Y475500D01*
X508599Y475750D01*
X508546Y476000D01*
X508413Y476208D01*
X508173Y476333D01*
X507933Y476291D01*
X507693Y476125D01*
G01X509464Y473870D02*
Y476632D01*
G01D02*
X512204D01*
G01X506775Y510030D02*
X506620Y509800D01*
X506517Y509532D01*
Y509225D01*
X506672Y508880D01*
X506930Y508612D01*
X507240Y508420D01*
X507757Y508267D01*
X508222Y508229D01*
X508687Y508305D01*
X508997Y508420D01*
X509307Y508650D01*
X509514Y508919D01*
X509617Y509187D01*
Y509455D01*
X509514Y509724D01*
X509359Y509954D01*
X509152Y510145D01*
G01X509617Y512287D02*
X509565Y512555D01*
X509410Y512862D01*
X509152Y513054D01*
X508790Y513130D01*
X508429Y513054D01*
X508119Y512824D01*
X507964Y512479D01*
Y512095D01*
X507860Y511865D01*
X507602Y511674D01*
X507240Y511597D01*
X506879Y511712D01*
X506620Y511980D01*
X506517Y512287D01*
X506620Y512594D01*
X506879Y512862D01*
X507240Y512977D01*
X507602Y512900D01*
X507860Y512709D01*
X507964Y512479D01*
Y512095D01*
X508119Y511750D01*
X508429Y511520D01*
X508790Y511444D01*
X509152Y511520D01*
X509410Y511712D01*
X509565Y512019D01*
X509617Y512287D01*
G01Y515310D02*
X508945Y515387D01*
X508377Y515502D01*
X507860Y515655D01*
X507292Y515847D01*
X506517Y516154D01*
Y514620D01*
G01X509617Y518410D02*
X508945Y518487D01*
X508377Y518602D01*
X507860Y518755D01*
X507292Y518947D01*
X506517Y519254D01*
Y517720D01*
G01X503765Y509190D02*
X500665D01*
Y510149D01*
X500820Y510455D01*
X501027Y510647D01*
X501440Y510724D01*
X501853Y510647D01*
X502112Y510417D01*
X502267Y510149D01*
Y509190D01*
G01Y510149D02*
X503765Y510724D01*
G01X501182Y512329D02*
X500872Y512559D01*
X500717Y512827D01*
X500665Y513134D01*
X500768Y513517D01*
X501027Y513785D01*
X501337Y513862D01*
X501647Y513824D01*
X501905Y513670D01*
X502422Y512904D01*
X502783Y512559D01*
X503300Y512329D01*
X503765Y512252D01*
Y513862D01*
G01Y516157D02*
X503713Y516425D01*
X503558Y516732D01*
X503300Y516924D01*
X502938Y517000D01*
X502577Y516924D01*
X502267Y516694D01*
X502112Y516349D01*
Y515965D01*
X502008Y515735D01*
X501750Y515544D01*
X501388Y515467D01*
X501027Y515582D01*
X500768Y515850D01*
X500665Y516157D01*
X500768Y516464D01*
X501027Y516732D01*
X501388Y516847D01*
X501750Y516770D01*
X502008Y516579D01*
X502112Y516349D01*
Y515965D01*
X502267Y515620D01*
X502577Y515390D01*
X502938Y515314D01*
X503300Y515390D01*
X503558Y515582D01*
X503713Y515889D01*
X503765Y516157D01*
G01X500665Y519257D02*
X500768Y518950D01*
X501027Y518720D01*
X501337Y518567D01*
X501750Y518452D01*
X502215Y518414D01*
X502680Y518452D01*
X503093Y518567D01*
X503403Y518720D01*
X503662Y518950D01*
X503765Y519257D01*
X503662Y519564D01*
X503403Y519794D01*
X503093Y519947D01*
X502680Y520062D01*
X502215Y520100D01*
X501750Y520062D01*
X501337Y519947D01*
X501027Y519794D01*
X500768Y519564D01*
X500665Y519257D01*
G01X496359Y530068D02*
X496545Y529859D01*
X496759Y529776D01*
X496972Y529859D01*
X497159Y530109D01*
X497292Y530484D01*
X497345Y530859D01*
Y531318D01*
X497292Y531693D01*
X497159Y532026D01*
X496999Y532193D01*
X496812Y532276D01*
X496599Y532193D01*
X496439Y532026D01*
X496332Y531776D01*
X496279Y531443D01*
X496332Y531151D01*
X496465Y530859D01*
X496625Y530693D01*
X496812Y530651D01*
X497025Y530734D01*
X497185Y530943D01*
X497345Y531318D01*
G01X498959Y529776D02*
X499012Y530318D01*
X499092Y530776D01*
X499199Y531193D01*
X499332Y531651D01*
X499545Y532276D01*
X498479D01*
G01X509238Y520525D02*
X506038D01*
G01X509238Y526725D02*
Y520525D01*
G01X506038D02*
Y526725D01*
G01X509138Y523625D02*
X506138D01*
G01X506038Y526725D02*
X509238D01*
G01X500438Y527425D02*
X503638D01*
G01X500438Y521225D02*
Y527425D01*
G01X503638Y521225D02*
X500438D01*
G01X503638Y527425D02*
Y521225D01*
G01X498940Y538458D02*
Y592058D01*
G01X549362Y538458D02*
X498940D01*
G01X496778Y595833D02*
X496965Y596124D01*
X497125Y596291D01*
X497338Y596374D01*
X497525Y596291D01*
X497658Y596124D01*
X497765Y595874D01*
X497792Y595583D01*
X497765Y595333D01*
X497658Y595083D01*
X497498Y594874D01*
X497312Y594791D01*
X497098Y594874D01*
X496912Y595124D01*
X496805Y595499D01*
X496778Y595916D01*
X496832Y596458D01*
X496912Y596749D01*
X497045Y597041D01*
X497232Y597249D01*
X497418Y597291D01*
X497605Y597208D01*
X497738Y596999D01*
G01X499805Y594791D02*
Y597291D01*
X498818Y595499D01*
X500152D01*
G01X498940Y592058D02*
X552540D01*
G01X508630Y600060D02*
Y605400D01*
G01X567990Y634740D02*
Y619256D01*
X554010D01*
Y605400D01*
X508630D01*
G01X499238Y611998D02*
Y615198D01*
G01X505438Y611998D02*
X499238D01*
G01X505438Y615198D02*
Y611998D01*
G01X503838Y601925D02*
X500638D01*
G01X503838Y608125D02*
Y601925D01*
G01X500638Y608125D02*
X503838D01*
G01X500638Y601925D02*
Y608125D01*
G01X495838D02*
Y601925D01*
G01X499838D02*
X496638D01*
G01X499838Y608125D02*
Y601925D01*
G01X496638Y608125D02*
X499838D01*
G01X496638Y601925D02*
Y608125D01*
G01X496217Y612401D02*
Y614901D01*
X496751D01*
X496964Y614776D01*
X497124Y614609D01*
X497257Y614359D01*
X497364Y614068D01*
X497391Y613651D01*
X497364Y613234D01*
X497257Y612943D01*
X497124Y612693D01*
X496964Y612526D01*
X496751Y612401D01*
X496217D01*
G01X499238Y615198D02*
X505438D01*
G01X504782Y631936D02*
Y616936D01*
G01X509711Y623663D02*
X509924Y623455D01*
X510164Y623330D01*
X510378D01*
X510591Y623455D01*
X510751Y623663D01*
X510831Y623955D01*
X510778Y624247D01*
X510644Y624497D01*
X510404Y624663D01*
X510084Y624747D01*
X509898Y624913D01*
X509818Y625205D01*
X509871Y625497D01*
X510004Y625705D01*
X510191Y625830D01*
X510378D01*
X510564Y625747D01*
X510724Y625538D01*
G01X505738Y617074D02*
Y632074D01*
G01X518738Y617074D02*
X505738D01*
G01X496990Y638470D02*
Y634800D01*
G01X499810Y640820D02*
Y632610D01*
G01X510440Y640820D02*
X499810D01*
G01X533770Y637120D02*
X510440D01*
G01Y640820D02*
Y637120D01*
G01X509076Y636418D02*
Y633218D01*
G01X502876Y636418D02*
X509076D01*
G01X502876Y633218D02*
Y636418D01*
G01X509076Y633218D02*
X502876D01*
G01X495298Y636203D02*
Y633003D01*
G01X502876Y637180D02*
Y640380D01*
G01X509076Y637180D02*
X502876D01*
G01X509076Y640380D02*
Y637180D01*
G01X502876Y640380D02*
X509076D01*
G01X496140Y633633D02*
X496353Y633425D01*
X496593Y633300D01*
X496807D01*
X497020Y633425D01*
X497180Y633633D01*
X497260Y633925D01*
X497207Y634217D01*
X497073Y634467D01*
X496833Y634633D01*
X496513Y634717D01*
X496327Y634883D01*
X496247Y635175D01*
X496300Y635467D01*
X496433Y635675D01*
X496620Y635800D01*
X496807D01*
X496993Y635717D01*
X497153Y635508D01*
G01X501260Y634550D02*
X501793D01*
Y633800D01*
X501633Y633550D01*
X501447Y633383D01*
X501180Y633300D01*
X500913Y633383D01*
X500727Y633550D01*
X500567Y633800D01*
X500460Y634092D01*
X500407Y634425D01*
Y634717D01*
X500460Y634967D01*
X500567Y635258D01*
X500727Y635508D01*
X500887Y635675D01*
X501100Y635800D01*
X501287D01*
X501500Y635717D01*
X501660Y635550D01*
G01X505738Y632074D02*
X518738D01*
G01X509092Y646440D02*
X509252Y646232D01*
X509439Y646107D01*
X509679Y646065D01*
X509919Y646148D01*
X510106Y646315D01*
X510239Y646607D01*
X510266Y646940D01*
X510212Y647273D01*
X510079Y647482D01*
X509892Y647648D01*
X509706Y647690D01*
X509519Y647648D01*
X509279Y647482D01*
X509359Y648565D01*
X510079D01*
G01X511879D02*
X511666Y648482D01*
X511506Y648273D01*
X511399Y648023D01*
X511319Y647690D01*
X511292Y647315D01*
X511319Y646940D01*
X511399Y646607D01*
X511506Y646357D01*
X511666Y646148D01*
X511879Y646065D01*
X512092Y646148D01*
X512252Y646357D01*
X512359Y646607D01*
X512439Y646940D01*
X512466Y647315D01*
X512439Y647690D01*
X512359Y648023D01*
X512252Y648273D01*
X512092Y648482D01*
X511879Y648565D01*
G01X496535Y658578D02*
Y661778D01*
G01X502735Y658578D02*
X496535D01*
G01X502735Y661778D02*
Y658578D01*
G01X499635Y658678D02*
Y661678D01*
G01X498788Y657713D02*
Y653113D01*
G01X503888Y657713D02*
Y653113D01*
G01X495510Y652226D02*
X501710D01*
G01X495510Y649026D02*
Y652226D01*
G01X501710Y649026D02*
X495510D01*
G01X501710Y652226D02*
Y649026D01*
G01X495499Y648169D02*
X501699D01*
G01X495499Y644969D02*
Y648169D01*
G01X501699Y644969D02*
X495499D01*
G01X501699Y648169D02*
Y644969D01*
G01X507040Y669656D02*
X505930D01*
G01X507040Y659856D02*
X502040D01*
G01X496535Y661778D02*
X502735D01*
G01X495283Y662267D02*
Y665367D01*
X496242D01*
X496548Y665212D01*
X496740Y665005D01*
X496817Y664592D01*
X496740Y664179D01*
X496510Y663920D01*
X496242Y663765D01*
X495283D01*
G01X496242D02*
X496817Y662267D01*
G01X498422Y663559D02*
X498690Y663920D01*
X498920Y664127D01*
X499227Y664230D01*
X499495Y664127D01*
X499687Y663920D01*
X499840Y663610D01*
X499878Y663249D01*
X499840Y662939D01*
X499687Y662629D01*
X499457Y662370D01*
X499188Y662267D01*
X498882Y662370D01*
X498613Y662680D01*
X498460Y663145D01*
X498422Y663662D01*
X498498Y664334D01*
X498613Y664695D01*
X498805Y665057D01*
X499073Y665315D01*
X499342Y665367D01*
X499610Y665264D01*
X499802Y665005D01*
G01X502250Y662267D02*
X502518Y662319D01*
X502825Y662474D01*
X503017Y662732D01*
X503093Y663094D01*
X503017Y663455D01*
X502787Y663765D01*
X502442Y663920D01*
X502058D01*
X501828Y664024D01*
X501637Y664282D01*
X501560Y664644D01*
X501675Y665005D01*
X501943Y665264D01*
X502250Y665367D01*
X502557Y665264D01*
X502825Y665005D01*
X502940Y664644D01*
X502863Y664282D01*
X502672Y664024D01*
X502442Y663920D01*
X502058D01*
X501713Y663765D01*
X501483Y663455D01*
X501407Y663094D01*
X501483Y662732D01*
X501675Y662474D01*
X501982Y662319D01*
X502250Y662267D01*
G01X505810D02*
Y665367D01*
X504392Y663145D01*
X506308D01*
G01X506640Y679556D02*
X501640D01*
G01X496865Y693590D02*
X496635Y693745D01*
X496367Y693848D01*
X496060D01*
X495715Y693693D01*
X495447Y693435D01*
X495255Y693125D01*
X495102Y692608D01*
X495064Y692143D01*
X495140Y691678D01*
X495255Y691368D01*
X495485Y691058D01*
X495754Y690851D01*
X496022Y690748D01*
X496290D01*
X496559Y690851D01*
X496789Y691006D01*
X496980Y691213D01*
G01X498470Y691110D02*
X498739Y690851D01*
X499045Y690748D01*
X499352Y690851D01*
X499620Y691161D01*
X499812Y691626D01*
X499889Y692091D01*
Y692660D01*
X499812Y693125D01*
X499620Y693538D01*
X499390Y693745D01*
X499122Y693848D01*
X498815Y693745D01*
X498585Y693538D01*
X498432Y693228D01*
X498355Y692815D01*
X498432Y692453D01*
X498624Y692091D01*
X498854Y691885D01*
X499122Y691833D01*
X499429Y691936D01*
X499659Y692195D01*
X499889Y692660D01*
G01X502222Y693848D02*
X501915Y693745D01*
X501685Y693486D01*
X501532Y693176D01*
X501417Y692763D01*
X501379Y692298D01*
X501417Y691833D01*
X501532Y691420D01*
X501685Y691110D01*
X501915Y690851D01*
X502222Y690748D01*
X502529Y690851D01*
X502759Y691110D01*
X502912Y691420D01*
X503027Y691833D01*
X503065Y692298D01*
X503027Y692763D01*
X502912Y693176D01*
X502759Y693486D01*
X502529Y693745D01*
X502222Y693848D01*
G01X505322D02*
X505015Y693745D01*
X504785Y693486D01*
X504632Y693176D01*
X504517Y692763D01*
X504479Y692298D01*
X504517Y691833D01*
X504632Y691420D01*
X504785Y691110D01*
X505015Y690851D01*
X505322Y690748D01*
X505629Y690851D01*
X505859Y691110D01*
X506012Y691420D01*
X506127Y691833D01*
X506165Y692298D01*
X506127Y692763D01*
X506012Y693176D01*
X505859Y693486D01*
X505629Y693745D01*
X505322Y693848D01*
G01X495330Y686069D02*
Y689269D01*
G01X501530Y686069D02*
X495330D01*
G01Y689269D02*
X501530D01*
G01D02*
Y686069D01*
G01X498430Y686169D02*
Y689169D01*
G01X509450Y700550D02*
X509610Y700800D01*
X509797Y700925D01*
X510010Y700967D01*
X510277Y700884D01*
X510464Y700675D01*
X510517Y700425D01*
X510490Y700175D01*
X510384Y699967D01*
X509850Y699550D01*
X509610Y699259D01*
X509450Y698842D01*
X509397Y698467D01*
X510517D01*
G01X511650Y699509D02*
X511837Y699800D01*
X511997Y699967D01*
X512210Y700050D01*
X512397Y699967D01*
X512530Y699800D01*
X512637Y699550D01*
X512664Y699259D01*
X512637Y699009D01*
X512530Y698759D01*
X512370Y698550D01*
X512184Y698467D01*
X511970Y698550D01*
X511784Y698800D01*
X511677Y699175D01*
X511650Y699592D01*
X511704Y700134D01*
X511784Y700425D01*
X511917Y700717D01*
X512104Y700925D01*
X512290Y700967D01*
X512477Y700884D01*
X512610Y700675D01*
G01X501581Y704085D02*
Y707185D01*
X502540D01*
X502846Y707030D01*
X503038Y706823D01*
X503115Y706410D01*
X503038Y705997D01*
X502808Y705738D01*
X502540Y705583D01*
X501581D01*
G01X502540D02*
X503115Y704085D01*
G01X505371D02*
X505448Y704757D01*
X505563Y705325D01*
X505716Y705842D01*
X505908Y706410D01*
X506215Y707185D01*
X504681D01*
G01X507820Y706668D02*
X508050Y706978D01*
X508318Y707133D01*
X508625Y707185D01*
X509008Y707082D01*
X509276Y706823D01*
X509353Y706513D01*
X509315Y706203D01*
X509161Y705945D01*
X508395Y705428D01*
X508050Y705067D01*
X507820Y704550D01*
X507743Y704085D01*
X509353D01*
G01X511648Y707185D02*
X511341Y707082D01*
X511111Y706823D01*
X510958Y706513D01*
X510843Y706100D01*
X510805Y705635D01*
X510843Y705170D01*
X510958Y704757D01*
X511111Y704447D01*
X511341Y704188D01*
X511648Y704085D01*
X511955Y704188D01*
X512185Y704447D01*
X512338Y704757D01*
X512453Y705170D01*
X512491Y705635D01*
X512453Y706100D01*
X512338Y706513D01*
X512185Y706823D01*
X511955Y707082D01*
X511648Y707185D01*
G01X498122Y708182D02*
Y704982D01*
G01X501140Y719664D02*
X498640D01*
Y720198D01*
X498765Y720411D01*
X498932Y720571D01*
X499182Y720704D01*
X499473Y720811D01*
X499890Y720838D01*
X500307Y720811D01*
X500598Y720704D01*
X500848Y720571D01*
X501015Y720411D01*
X501140Y720198D01*
Y719664D01*
G01Y722451D02*
X498640D01*
X499140Y722131D01*
G01X501140D02*
Y722771D01*
G01X500098Y724144D02*
X499807Y724331D01*
X499640Y724491D01*
X499557Y724704D01*
X499640Y724891D01*
X499807Y725024D01*
X500057Y725131D01*
X500348Y725158D01*
X500598Y725131D01*
X500848Y725024D01*
X501057Y724864D01*
X501140Y724678D01*
X501057Y724464D01*
X500807Y724278D01*
X500432Y724171D01*
X500015Y724144D01*
X499473Y724198D01*
X499182Y724278D01*
X498890Y724411D01*
X498682Y724598D01*
X498640Y724784D01*
X498723Y724971D01*
X498932Y725104D01*
G01X505133Y719729D02*
X502633D01*
Y720263D01*
X502758Y720476D01*
X502925Y720636D01*
X503175Y720769D01*
X503466Y720876D01*
X503883Y720903D01*
X504300Y720876D01*
X504591Y720769D01*
X504841Y720636D01*
X505008Y720476D01*
X505133Y720263D01*
Y719729D01*
G01Y722516D02*
X502633D01*
X503133Y722196D01*
G01X505133D02*
Y722836D01*
G01X504758Y724129D02*
X504966Y724289D01*
X505091Y724476D01*
X505133Y724716D01*
X505050Y724956D01*
X504883Y725143D01*
X504591Y725276D01*
X504258Y725303D01*
X503925Y725249D01*
X503716Y725116D01*
X503550Y724929D01*
X503508Y724743D01*
X503550Y724556D01*
X503716Y724316D01*
X502633Y724396D01*
Y725116D01*
G01X501391Y708111D02*
Y711211D01*
X502350D01*
X502656Y711056D01*
X502848Y710849D01*
X502925Y710436D01*
X502848Y710023D01*
X502618Y709764D01*
X502350Y709609D01*
X501391D01*
G01X502350D02*
X502925Y708111D01*
G01X505181D02*
X505258Y708783D01*
X505373Y709351D01*
X505526Y709868D01*
X505718Y710436D01*
X506025Y711211D01*
X504491D01*
G01X507630Y710694D02*
X507860Y711004D01*
X508128Y711159D01*
X508435Y711211D01*
X508818Y711108D01*
X509086Y710849D01*
X509163Y710539D01*
X509125Y710229D01*
X508971Y709971D01*
X508205Y709454D01*
X507860Y709093D01*
X507630Y708576D01*
X507553Y708111D01*
X509163D01*
G01X511458D02*
Y711211D01*
X510998Y710591D01*
G01Y708111D02*
X511918D01*
G01X498122Y716182D02*
Y712982D01*
G01Y720182D02*
Y716982D01*
G01X500895Y715845D02*
Y718945D01*
X501854D01*
X502160Y718790D01*
X502352Y718583D01*
X502429Y718170D01*
X502352Y717757D01*
X502122Y717498D01*
X501854Y717343D01*
X500895D01*
G01X501854D02*
X502429Y715845D01*
G01X504685D02*
X504762Y716517D01*
X504877Y717085D01*
X505030Y717602D01*
X505222Y718170D01*
X505529Y718945D01*
X503995D01*
G01X507134Y718428D02*
X507364Y718738D01*
X507632Y718893D01*
X507939Y718945D01*
X508322Y718842D01*
X508590Y718583D01*
X508667Y718273D01*
X508629Y717963D01*
X508475Y717705D01*
X507709Y717188D01*
X507364Y716827D01*
X507134Y716310D01*
X507057Y715845D01*
X508667D01*
G01X510119Y716465D02*
X510349Y716103D01*
X510655Y715897D01*
X511000Y715845D01*
X511307Y715897D01*
X511614Y716155D01*
X511805Y716465D01*
X511844Y716775D01*
X511767Y717137D01*
X511499Y717395D01*
X511230Y717498D01*
X510885D01*
G01X511230D02*
X511460Y717653D01*
X511652Y717912D01*
X511729Y718222D01*
X511652Y718532D01*
X511460Y718790D01*
X511115Y718945D01*
X510770Y718893D01*
X510425Y718687D01*
G01X500895Y711845D02*
Y714945D01*
X501854D01*
X502160Y714790D01*
X502352Y714583D01*
X502429Y714170D01*
X502352Y713757D01*
X502122Y713498D01*
X501854Y713343D01*
X500895D01*
G01X501854D02*
X502429Y711845D01*
G01X504685D02*
X504762Y712517D01*
X504877Y713085D01*
X505030Y713602D01*
X505222Y714170D01*
X505529Y714945D01*
X503995D01*
G01X507134Y714428D02*
X507364Y714738D01*
X507632Y714893D01*
X507939Y714945D01*
X508322Y714842D01*
X508590Y714583D01*
X508667Y714273D01*
X508629Y713963D01*
X508475Y713705D01*
X507709Y713188D01*
X507364Y712827D01*
X507134Y712310D01*
X507057Y711845D01*
X508667D01*
G01X510234Y714428D02*
X510464Y714738D01*
X510732Y714893D01*
X511039Y714945D01*
X511422Y714842D01*
X511690Y714583D01*
X511767Y714273D01*
X511729Y713963D01*
X511575Y713705D01*
X510809Y713188D01*
X510464Y712827D01*
X510234Y712310D01*
X510157Y711845D01*
X511767D01*
G01X498122Y712182D02*
Y708982D01*
G01X501740Y737556D02*
X498540D01*
G01X501740Y743756D02*
Y737556D01*
G01X498540D02*
Y743756D01*
G01X505740Y737556D02*
X502540D01*
G01X505740Y743756D02*
Y737556D01*
G01X502540D02*
Y743756D01*
G01X497440D02*
Y737556D01*
G01X513740D02*
X510540D01*
G01D02*
Y743756D01*
G01X506540Y726056D02*
X503340D01*
G01X506540Y732256D02*
Y726056D01*
G01X503340Y732256D02*
X506540D01*
G01X503340Y726056D02*
Y732256D01*
G01X506440Y729156D02*
X503440D01*
G01X508070Y732158D02*
X511270D01*
G01Y725958D02*
X508070D01*
G01D02*
Y732158D01*
G01X506540Y737556D02*
Y743756D01*
G01X509740Y737556D02*
X506540D01*
G01X509740Y743756D02*
Y737556D01*
G01X495340Y726056D02*
Y732256D01*
G01X498540Y726056D02*
X495340D01*
G01X498540Y732256D02*
Y726056D01*
G01X495340Y732256D02*
X498540D01*
G01Y743756D02*
X501740D01*
G01X501640Y740656D02*
X498640D01*
G01X505640D02*
X502640D01*
G01X502540Y743756D02*
X505740D01*
G01X510540D02*
X513740D01*
G01X504176Y749776D02*
X504021Y749546D01*
X503918Y749278D01*
Y748971D01*
X504073Y748626D01*
X504331Y748358D01*
X504641Y748166D01*
X505158Y748013D01*
X505623Y747975D01*
X506088Y748051D01*
X506398Y748166D01*
X506708Y748396D01*
X506915Y748665D01*
X507018Y748933D01*
Y749201D01*
X506915Y749470D01*
X506760Y749700D01*
X506553Y749891D01*
G01X507018Y751956D02*
X506346Y752033D01*
X505778Y752148D01*
X505261Y752301D01*
X504693Y752493D01*
X503918Y752800D01*
Y751266D01*
G01X505726Y754405D02*
X505365Y754673D01*
X505158Y754903D01*
X505055Y755210D01*
X505158Y755478D01*
X505365Y755670D01*
X505675Y755823D01*
X506036Y755861D01*
X506346Y755823D01*
X506656Y755670D01*
X506915Y755440D01*
X507018Y755171D01*
X506915Y754865D01*
X506605Y754596D01*
X506140Y754443D01*
X505623Y754405D01*
X504951Y754481D01*
X504590Y754596D01*
X504228Y754788D01*
X503970Y755056D01*
X503918Y755325D01*
X504021Y755593D01*
X504280Y755785D01*
G01X507018Y758233D02*
X503918D01*
X504538Y757773D01*
G01X507018D02*
Y758693D01*
G01X512565Y747298D02*
X509465D01*
Y748257D01*
X509620Y748563D01*
X509827Y748755D01*
X510240Y748832D01*
X510653Y748755D01*
X510912Y748525D01*
X511067Y748257D01*
Y747298D01*
G01Y748257D02*
X512565Y748832D01*
G01X512203Y750513D02*
X512462Y750782D01*
X512565Y751088D01*
X512462Y751395D01*
X512152Y751663D01*
X511687Y751855D01*
X511222Y751932D01*
X510653D01*
X510188Y751855D01*
X509775Y751663D01*
X509568Y751433D01*
X509465Y751165D01*
X509568Y750858D01*
X509775Y750628D01*
X510085Y750475D01*
X510498Y750398D01*
X510860Y750475D01*
X511222Y750667D01*
X511428Y750897D01*
X511480Y751165D01*
X511377Y751472D01*
X511118Y751702D01*
X510653Y751932D01*
G01X512565Y754188D02*
X511893Y754265D01*
X511325Y754380D01*
X510808Y754533D01*
X510240Y754725D01*
X509465Y755032D01*
Y753498D01*
G01X512565Y757365D02*
X509465D01*
X510085Y756905D01*
G01X512565D02*
Y757825D01*
G01X506540Y743756D02*
X509740D01*
G01X497131Y762135D02*
X496976Y761905D01*
X496873Y761637D01*
Y761330D01*
X497028Y760985D01*
X497286Y760717D01*
X497596Y760525D01*
X498113Y760372D01*
X498578Y760334D01*
X499043Y760410D01*
X499353Y760525D01*
X499663Y760755D01*
X499870Y761024D01*
X499973Y761292D01*
Y761560D01*
X499870Y761829D01*
X499715Y762059D01*
X499508Y762250D01*
G01X499973Y764315D02*
X499301Y764392D01*
X498733Y764507D01*
X498216Y764660D01*
X497648Y764852D01*
X496873Y765159D01*
Y763625D01*
G01X498681Y766764D02*
X498320Y767032D01*
X498113Y767262D01*
X498010Y767569D01*
X498113Y767837D01*
X498320Y768029D01*
X498630Y768182D01*
X498991Y768220D01*
X499301Y768182D01*
X499611Y768029D01*
X499870Y767799D01*
X499973Y767530D01*
X499870Y767224D01*
X499560Y766955D01*
X499095Y766802D01*
X498578Y766764D01*
X497906Y766840D01*
X497545Y766955D01*
X497183Y767147D01*
X496925Y767415D01*
X496873Y767684D01*
X496976Y767952D01*
X497235Y768144D01*
G01X499973Y771052D02*
X496873D01*
X499095Y769634D01*
Y771550D01*
G01X500739Y762143D02*
X500584Y761913D01*
X500481Y761645D01*
Y761338D01*
X500636Y760993D01*
X500894Y760725D01*
X501204Y760533D01*
X501721Y760380D01*
X502186Y760342D01*
X502651Y760418D01*
X502961Y760533D01*
X503271Y760763D01*
X503478Y761032D01*
X503581Y761300D01*
Y761568D01*
X503478Y761837D01*
X503323Y762067D01*
X503116Y762258D01*
G01X503581Y764323D02*
X502909Y764400D01*
X502341Y764515D01*
X501824Y764668D01*
X501256Y764860D01*
X500481Y765167D01*
Y763633D01*
G01X503581Y767960D02*
X500481D01*
X502703Y766542D01*
Y768458D01*
G01X500481Y770600D02*
X500584Y770293D01*
X500843Y770063D01*
X501153Y769910D01*
X501566Y769795D01*
X502031Y769757D01*
X502496Y769795D01*
X502909Y769910D01*
X503219Y770063D01*
X503478Y770293D01*
X503581Y770600D01*
X503478Y770907D01*
X503219Y771137D01*
X502909Y771290D01*
X502496Y771405D01*
X502031Y771443D01*
X501566Y771405D01*
X501153Y771290D01*
X500843Y771137D01*
X500584Y770907D01*
X500481Y770600D01*
G01X507896Y762135D02*
X507741Y761905D01*
X507638Y761637D01*
Y761330D01*
X507793Y760985D01*
X508051Y760717D01*
X508361Y760525D01*
X508878Y760372D01*
X509343Y760334D01*
X509808Y760410D01*
X510118Y760525D01*
X510428Y760755D01*
X510635Y761024D01*
X510738Y761292D01*
Y761560D01*
X510635Y761829D01*
X510480Y762059D01*
X510273Y762250D01*
G01X510738Y764315D02*
X510066Y764392D01*
X509498Y764507D01*
X508981Y764660D01*
X508413Y764852D01*
X507638Y765159D01*
Y763625D01*
G01X510273Y766649D02*
X510531Y766879D01*
X510686Y767147D01*
X510738Y767492D01*
X510635Y767837D01*
X510428Y768105D01*
X510066Y768297D01*
X509653Y768335D01*
X509240Y768259D01*
X508981Y768067D01*
X508775Y767799D01*
X508723Y767530D01*
X508775Y767262D01*
X508981Y766917D01*
X507638Y767032D01*
Y768067D01*
G01X510738Y770592D02*
X510686Y770860D01*
X510531Y771167D01*
X510273Y771359D01*
X509911Y771435D01*
X509550Y771359D01*
X509240Y771129D01*
X509085Y770784D01*
Y770400D01*
X508981Y770170D01*
X508723Y769979D01*
X508361Y769902D01*
X508000Y770017D01*
X507741Y770285D01*
X507638Y770592D01*
X507741Y770899D01*
X508000Y771167D01*
X508361Y771282D01*
X508723Y771205D01*
X508981Y771014D01*
X509085Y770784D01*
Y770400D01*
X509240Y770055D01*
X509550Y769825D01*
X509911Y769749D01*
X510273Y769825D01*
X510531Y770017D01*
X510686Y770324D01*
X510738Y770592D01*
G01X507238Y760525D02*
X504138D01*
Y761484D01*
X504293Y761790D01*
X504500Y761982D01*
X504913Y762059D01*
X505326Y761982D01*
X505585Y761752D01*
X505740Y761484D01*
Y760525D01*
G01Y761484D02*
X507238Y762059D01*
G01X506876Y763740D02*
X507135Y764009D01*
X507238Y764315D01*
X507135Y764622D01*
X506825Y764890D01*
X506360Y765082D01*
X505895Y765159D01*
X505326D01*
X504861Y765082D01*
X504448Y764890D01*
X504241Y764660D01*
X504138Y764392D01*
X504241Y764085D01*
X504448Y763855D01*
X504758Y763702D01*
X505171Y763625D01*
X505533Y763702D01*
X505895Y763894D01*
X506101Y764124D01*
X506153Y764392D01*
X506050Y764699D01*
X505791Y764929D01*
X505326Y765159D01*
G01X506876Y766840D02*
X507135Y767109D01*
X507238Y767415D01*
X507135Y767722D01*
X506825Y767990D01*
X506360Y768182D01*
X505895Y768259D01*
X505326D01*
X504861Y768182D01*
X504448Y767990D01*
X504241Y767760D01*
X504138Y767492D01*
X504241Y767185D01*
X504448Y766955D01*
X504758Y766802D01*
X505171Y766725D01*
X505533Y766802D01*
X505895Y766994D01*
X506101Y767224D01*
X506153Y767492D01*
X506050Y767799D01*
X505791Y768029D01*
X505326Y768259D01*
G01X507238Y770592D02*
X507186Y770860D01*
X507031Y771167D01*
X506773Y771359D01*
X506411Y771435D01*
X506050Y771359D01*
X505740Y771129D01*
X505585Y770784D01*
Y770400D01*
X505481Y770170D01*
X505223Y769979D01*
X504861Y769902D01*
X504500Y770017D01*
X504241Y770285D01*
X504138Y770592D01*
X504241Y770899D01*
X504500Y771167D01*
X504861Y771282D01*
X505223Y771205D01*
X505481Y771014D01*
X505585Y770784D01*
Y770400D01*
X505740Y770055D01*
X506050Y769825D01*
X506411Y769749D01*
X506773Y769825D01*
X507031Y770017D01*
X507186Y770324D01*
X507238Y770592D01*
G01X522812Y84020D02*
X519712D01*
Y84979D01*
X519867Y85285D01*
X520074Y85477D01*
X520487Y85554D01*
X520900Y85477D01*
X521159Y85247D01*
X521314Y84979D01*
Y84020D01*
G01Y84979D02*
X522812Y85554D01*
G01Y87887D02*
X519712D01*
X520332Y87427D01*
G01X522812D02*
Y88347D01*
G01Y90987D02*
X519712D01*
X520332Y90527D01*
G01X522812D02*
Y91447D01*
G01Y94547D02*
X519712D01*
X521934Y93129D01*
Y95045D01*
G01X521520Y96459D02*
X521159Y96727D01*
X520952Y96957D01*
X520849Y97264D01*
X520952Y97532D01*
X521159Y97724D01*
X521469Y97877D01*
X521830Y97915D01*
X522140Y97877D01*
X522450Y97724D01*
X522709Y97494D01*
X522812Y97225D01*
X522709Y96919D01*
X522399Y96650D01*
X521934Y96497D01*
X521417Y96459D01*
X520745Y96535D01*
X520384Y96650D01*
X520022Y96842D01*
X519764Y97110D01*
X519712Y97379D01*
X519815Y97647D01*
X520074Y97839D01*
G01X518852Y84020D02*
X515752D01*
Y84979D01*
X515907Y85285D01*
X516114Y85477D01*
X516527Y85554D01*
X516940Y85477D01*
X517199Y85247D01*
X517354Y84979D01*
Y84020D01*
G01Y84979D02*
X518852Y85554D01*
G01Y87887D02*
X515752D01*
X516372Y87427D01*
G01X518852D02*
Y88347D01*
G01Y90987D02*
X515752D01*
X516372Y90527D01*
G01X518852D02*
Y91447D01*
G01Y94547D02*
X515752D01*
X517974Y93129D01*
Y95045D01*
G01X518387Y96344D02*
X518645Y96574D01*
X518800Y96842D01*
X518852Y97187D01*
X518749Y97532D01*
X518542Y97800D01*
X518180Y97992D01*
X517767Y98030D01*
X517354Y97954D01*
X517095Y97762D01*
X516889Y97494D01*
X516837Y97225D01*
X516889Y96957D01*
X517095Y96612D01*
X515752Y96727D01*
Y97762D01*
G01X514462Y84020D02*
X511362D01*
Y84979D01*
X511517Y85285D01*
X511724Y85477D01*
X512137Y85554D01*
X512550Y85477D01*
X512809Y85247D01*
X512964Y84979D01*
Y84020D01*
G01Y84979D02*
X514462Y85554D01*
G01Y87887D02*
X511362D01*
X511982Y87427D01*
G01X514462D02*
Y88347D01*
G01Y90987D02*
X511362D01*
X511982Y90527D01*
G01X514462D02*
Y91447D01*
G01Y94547D02*
X511362D01*
X513584Y93129D01*
Y95045D01*
G01X514462Y97647D02*
X511362D01*
X513584Y96229D01*
Y98145D01*
G01X527262Y84020D02*
X524162D01*
Y84979D01*
X524317Y85285D01*
X524524Y85477D01*
X524937Y85554D01*
X525350Y85477D01*
X525609Y85247D01*
X525764Y84979D01*
Y84020D01*
G01Y84979D02*
X527262Y85554D01*
G01Y87887D02*
X524162D01*
X524782Y87427D01*
G01X527262D02*
Y88347D01*
G01Y90987D02*
X524162D01*
X524782Y90527D01*
G01X527262D02*
Y91447D01*
G01Y94547D02*
X524162D01*
X526384Y93129D01*
Y95045D01*
G01X527262Y97110D02*
X526590Y97187D01*
X526022Y97302D01*
X525505Y97455D01*
X524937Y97647D01*
X524162Y97954D01*
Y96420D01*
G01X520505Y114325D02*
Y108325D01*
G01X519355Y107704D02*
X522555D01*
G01D02*
Y101504D01*
G01D02*
X519355D01*
G01D02*
Y107704D01*
G01X515355D02*
X518555D01*
G01D02*
Y101504D01*
G01D02*
X515355D01*
G01D02*
Y107704D01*
G01X511355D02*
X514555D01*
G01D02*
Y101504D01*
G01D02*
X511355D01*
G01D02*
Y107704D01*
G01X523355D02*
X526555D01*
G01Y101504D02*
X523355D01*
G01D02*
Y107704D01*
G01X510605Y114325D02*
Y111325D01*
G01X516605Y189925D02*
Y192925D01*
G01X518257Y205665D02*
Y199465D01*
G01D02*
X515057D01*
G01D02*
Y205665D01*
G01X522100Y205600D02*
Y199400D01*
G01D02*
X518900D01*
G01D02*
Y205600D01*
G01X522900Y199400D02*
Y205600D01*
G01X526100Y199400D02*
X522900D01*
G01X526100Y205600D02*
Y199400D01*
G01X515058Y209993D02*
X514903Y209763D01*
X514800Y209495D01*
Y209188D01*
X514955Y208843D01*
X515213Y208575D01*
X515523Y208383D01*
X516040Y208230D01*
X516505Y208192D01*
X516970Y208268D01*
X517280Y208383D01*
X517590Y208613D01*
X517797Y208882D01*
X517900Y209150D01*
Y209418D01*
X517797Y209687D01*
X517642Y209917D01*
X517435Y210108D01*
G01Y211407D02*
X517693Y211637D01*
X517848Y211905D01*
X517900Y212250D01*
X517797Y212595D01*
X517590Y212863D01*
X517228Y213055D01*
X516815Y213093D01*
X516402Y213017D01*
X516143Y212825D01*
X515937Y212557D01*
X515885Y212288D01*
X515937Y212020D01*
X516143Y211675D01*
X514800Y211790D01*
Y212825D01*
G01X517280Y214507D02*
X517642Y214737D01*
X517848Y215043D01*
X517900Y215388D01*
X517848Y215695D01*
X517590Y216002D01*
X517280Y216193D01*
X516970Y216232D01*
X516608Y216155D01*
X516350Y215887D01*
X516247Y215618D01*
Y215273D01*
G01Y215618D02*
X516092Y215848D01*
X515833Y216040D01*
X515523Y216117D01*
X515213Y216040D01*
X514955Y215848D01*
X514800Y215503D01*
X514852Y215158D01*
X515058Y214813D01*
G01X517900Y218450D02*
X517848Y218718D01*
X517693Y219025D01*
X517435Y219217D01*
X517073Y219293D01*
X516712Y219217D01*
X516402Y218987D01*
X516247Y218642D01*
Y218258D01*
X516143Y218028D01*
X515885Y217837D01*
X515523Y217760D01*
X515162Y217875D01*
X514903Y218143D01*
X514800Y218450D01*
X514903Y218757D01*
X515162Y219025D01*
X515523Y219140D01*
X515885Y219063D01*
X516143Y218872D01*
X516247Y218642D01*
Y218258D01*
X516402Y217913D01*
X516712Y217683D01*
X517073Y217607D01*
X517435Y217683D01*
X517693Y217875D01*
X517848Y218182D01*
X517900Y218450D01*
G01X513760Y216125D02*
Y209925D01*
G01X513660Y213025D02*
X510660D01*
G01X515057Y205665D02*
X518257D01*
G01X518900Y205600D02*
X522100D01*
G01X522900D02*
X526100D01*
G01X525783Y209400D02*
Y212500D01*
X526742D01*
X527048Y212345D01*
X527240Y212138D01*
X527317Y211725D01*
X527240Y211312D01*
X527010Y211053D01*
X526742Y210898D01*
X525783D01*
G01X526742D02*
X527317Y209400D01*
G01X529650D02*
Y212500D01*
X529190Y211880D01*
G01Y209400D02*
X530110D01*
G01X532750D02*
Y212500D01*
X532290Y211880D01*
G01Y209400D02*
X533210D01*
G01X535007Y209865D02*
X535237Y209607D01*
X535505Y209452D01*
X535850Y209400D01*
X536195Y209503D01*
X536463Y209710D01*
X536655Y210072D01*
X536693Y210485D01*
X536617Y210898D01*
X536425Y211157D01*
X536157Y211363D01*
X535888Y211415D01*
X535620Y211363D01*
X535275Y211157D01*
X535390Y212500D01*
X536425D01*
G01X538222Y210692D02*
X538490Y211053D01*
X538720Y211260D01*
X539027Y211363D01*
X539295Y211260D01*
X539487Y211053D01*
X539640Y210743D01*
X539678Y210382D01*
X539640Y210072D01*
X539487Y209762D01*
X539257Y209503D01*
X538988Y209400D01*
X538682Y209503D01*
X538413Y209813D01*
X538260Y210278D01*
X538222Y210795D01*
X538298Y211467D01*
X538413Y211828D01*
X538605Y212190D01*
X538873Y212448D01*
X539142Y212500D01*
X539410Y212397D01*
X539602Y212138D01*
G01X524000Y217283D02*
X520900D01*
Y218242D01*
X521055Y218548D01*
X521262Y218740D01*
X521675Y218817D01*
X522088Y218740D01*
X522347Y218510D01*
X522502Y218242D01*
Y217283D01*
G01Y218242D02*
X524000Y218817D01*
G01Y221150D02*
X520900D01*
X521520Y220690D01*
G01X524000D02*
Y221610D01*
G01X523380Y223407D02*
X523742Y223637D01*
X523948Y223943D01*
X524000Y224288D01*
X523948Y224595D01*
X523690Y224902D01*
X523380Y225093D01*
X523070Y225132D01*
X522708Y225055D01*
X522450Y224787D01*
X522347Y224518D01*
Y224173D01*
G01Y224518D02*
X522192Y224748D01*
X521933Y224940D01*
X521623Y225017D01*
X521313Y224940D01*
X521055Y224748D01*
X520900Y224403D01*
X520952Y224058D01*
X521158Y223713D01*
G01X521417Y226622D02*
X521107Y226852D01*
X520952Y227120D01*
X520900Y227427D01*
X521003Y227810D01*
X521262Y228078D01*
X521572Y228155D01*
X521882Y228117D01*
X522140Y227963D01*
X522657Y227197D01*
X523018Y226852D01*
X523535Y226622D01*
X524000Y226545D01*
Y228155D01*
G01X522708Y229722D02*
X522347Y229990D01*
X522140Y230220D01*
X522037Y230527D01*
X522140Y230795D01*
X522347Y230987D01*
X522657Y231140D01*
X523018Y231178D01*
X523328Y231140D01*
X523638Y230987D01*
X523897Y230757D01*
X524000Y230488D01*
X523897Y230182D01*
X523587Y229913D01*
X523122Y229760D01*
X522605Y229722D01*
X521933Y229798D01*
X521572Y229913D01*
X521210Y230105D01*
X520952Y230373D01*
X520900Y230642D01*
X521003Y230910D01*
X521262Y231102D01*
G01X523400Y216200D02*
Y210000D01*
X520200D01*
Y216200D01*
X523400D01*
G01X516758Y222993D02*
X516603Y222763D01*
X516500Y222495D01*
Y222188D01*
X516655Y221843D01*
X516913Y221575D01*
X517223Y221383D01*
X517740Y221230D01*
X518205Y221192D01*
X518670Y221268D01*
X518980Y221383D01*
X519290Y221613D01*
X519497Y221882D01*
X519600Y222150D01*
Y222418D01*
X519497Y222687D01*
X519342Y222917D01*
X519135Y223108D01*
G01Y224407D02*
X519393Y224637D01*
X519548Y224905D01*
X519600Y225250D01*
X519497Y225595D01*
X519290Y225863D01*
X518928Y226055D01*
X518515Y226093D01*
X518102Y226017D01*
X517843Y225825D01*
X517637Y225557D01*
X517585Y225288D01*
X517637Y225020D01*
X517843Y224675D01*
X516500Y224790D01*
Y225825D01*
G01X518980Y227507D02*
X519342Y227737D01*
X519548Y228043D01*
X519600Y228388D01*
X519548Y228695D01*
X519290Y229002D01*
X518980Y229193D01*
X518670Y229232D01*
X518308Y229155D01*
X518050Y228887D01*
X517947Y228618D01*
Y228273D01*
G01Y228618D02*
X517792Y228848D01*
X517533Y229040D01*
X517223Y229117D01*
X516913Y229040D01*
X516655Y228848D01*
X516500Y228503D01*
X516552Y228158D01*
X516758Y227813D01*
G01X519238Y230798D02*
X519497Y231067D01*
X519600Y231373D01*
X519497Y231680D01*
X519187Y231948D01*
X518722Y232140D01*
X518257Y232217D01*
X517688D01*
X517223Y232140D01*
X516810Y231948D01*
X516603Y231718D01*
X516500Y231450D01*
X516603Y231143D01*
X516810Y230913D01*
X517120Y230760D01*
X517533Y230683D01*
X517895Y230760D01*
X518257Y230952D01*
X518463Y231182D01*
X518515Y231450D01*
X518412Y231757D01*
X518153Y231987D01*
X517688Y232217D01*
G01X515000Y223043D02*
X512000D01*
G01X511900Y219943D02*
Y226143D01*
G01D02*
X515100D01*
G01D02*
Y219943D01*
G01D02*
X511900D01*
G01X517171Y250484D02*
G02I-1000J0D01*
G01X518507Y268675D02*
Y247493D01*
G01X518075Y242983D02*
X521275D01*
G01X518075Y236783D02*
Y242983D01*
G01X521275D02*
Y236783D01*
G01D02*
X518075D01*
G01X514075Y242983D02*
X517275D01*
G01X514075Y236783D02*
Y242983D01*
G01X517275D02*
Y236783D01*
G01D02*
X514075D01*
G01X523075Y242983D02*
X526275D01*
G01D02*
Y236783D01*
G01D02*
X523075D01*
G01D02*
Y242983D01*
G01X524919Y280788D02*
Y278908D01*
G01X526284Y279926D02*
X523554D01*
G01X522843Y277089D02*
Y288428D01*
G01X518727Y419462D02*
Y421962D01*
X517740Y420170D01*
X519074D01*
G01X516536Y432590D02*
Y419990D01*
G01X511105Y435125D02*
Y438325D01*
G01X517305Y435125D02*
X511105D01*
G01Y438325D02*
X517305D01*
G01X514205Y438225D02*
Y435225D01*
G01X517305Y438325D02*
Y435125D01*
G01X528040Y423556D02*
X524840D01*
G01Y429756D02*
X528040D01*
G01X524840Y423556D02*
Y429756D01*
G01X522105Y436530D02*
X519005D01*
Y437489D01*
X519160Y437795D01*
X519367Y437987D01*
X519780Y438064D01*
X520193Y437987D01*
X520452Y437757D01*
X520607Y437489D01*
Y436530D01*
G01Y437489D02*
X522105Y438064D01*
G01X521743Y439745D02*
X522002Y440014D01*
X522105Y440320D01*
X522002Y440627D01*
X521692Y440895D01*
X521227Y441087D01*
X520762Y441164D01*
X520193D01*
X519728Y441087D01*
X519315Y440895D01*
X519108Y440665D01*
X519005Y440397D01*
X519108Y440090D01*
X519315Y439860D01*
X519625Y439707D01*
X520038Y439630D01*
X520400Y439707D01*
X520762Y439899D01*
X520968Y440129D01*
X521020Y440397D01*
X520917Y440704D01*
X520658Y440934D01*
X520193Y441164D01*
G01X521440Y429456D02*
X518240D01*
G01X521440Y435656D02*
Y429456D01*
G01X518240Y435656D02*
X521440D01*
G01X518240Y429456D02*
Y435656D01*
G01X524840Y433056D02*
Y439256D01*
G01X528040Y433056D02*
X524840D01*
G01Y439256D02*
X528040D01*
G01X517623Y426547D02*
Y429047D01*
X517303Y428547D01*
G01Y426547D02*
X517943D01*
G01X514836Y426290D02*
X516332Y426690D01*
G01Y425890D02*
X514836Y426290D01*
G01X511548Y445215D02*
Y447715D01*
X511228Y447215D01*
G01Y445215D02*
X511868D01*
G01X519440Y446262D02*
Y444462D01*
G01X511464Y448680D02*
X512104D01*
G01X513905Y442725D02*
Y439525D01*
G01X518445Y485223D02*
Y483001D01*
X518598Y482536D01*
X518905Y482226D01*
X519288Y482123D01*
X519671Y482226D01*
X519978Y482536D01*
X520131Y483001D01*
Y485223D01*
G01X522388Y482123D02*
Y485223D01*
X521928Y484603D01*
G01Y482123D02*
X522848D01*
G01X524140Y480950D02*
Y479150D01*
G01X516340Y482650D02*
Y479150D01*
G01X527074Y510629D02*
X523874D01*
G01Y516829D02*
X527074D01*
G01X523874Y510629D02*
Y516829D01*
G01X526974Y513729D02*
X523974D01*
G01X525038Y606525D02*
Y612725D01*
G01X528238Y606525D02*
X525038D01*
G01X516805Y610642D02*
Y607442D01*
G01X510605Y610642D02*
X516805D01*
G01X510605Y607442D02*
Y610642D01*
G01X516805Y607442D02*
X510605D01*
G01X517186Y614425D02*
X517719D01*
Y613675D01*
X517559Y613425D01*
X517373Y613258D01*
X517106Y613175D01*
X516839Y613258D01*
X516653Y613425D01*
X516493Y613675D01*
X516386Y613967D01*
X516333Y614300D01*
Y614592D01*
X516386Y614842D01*
X516493Y615133D01*
X516653Y615383D01*
X516813Y615550D01*
X517026Y615675D01*
X517213D01*
X517426Y615592D01*
X517586Y615425D01*
G01X510972Y612577D02*
Y615077D01*
X511506D01*
X511719Y614952D01*
X511879Y614785D01*
X512012Y614535D01*
X512119Y614244D01*
X512146Y613827D01*
X512119Y613410D01*
X512012Y613119D01*
X511879Y612869D01*
X511719Y612702D01*
X511506Y612577D01*
X510972D01*
G01X520088Y613787D02*
Y616987D01*
G01X526288Y613787D02*
X520088D01*
G01X526288Y616987D02*
Y613787D01*
G01X520088Y616987D02*
X526288D01*
G01X525038Y612725D02*
X528238D01*
G01X519778Y617695D02*
Y632695D01*
G01X532778Y617695D02*
X519778D01*
G01X518738Y632074D02*
Y617074D01*
G01X513401Y643748D02*
X513561Y643540D01*
X513748Y643415D01*
X513988Y643373D01*
X514228Y643456D01*
X514415Y643623D01*
X514548Y643915D01*
X514575Y644248D01*
X514521Y644581D01*
X514388Y644790D01*
X514201Y644956D01*
X514015Y644998D01*
X513828Y644956D01*
X513588Y644790D01*
X513668Y645873D01*
X514388D01*
G01X516188Y643373D02*
Y645873D01*
X515868Y645373D01*
G01Y643373D02*
X516508D01*
G01X512264Y636049D02*
X518464D01*
G01X512264Y632849D02*
Y636049D01*
G01X518464Y632849D02*
X512264D01*
G01X518464Y636049D02*
Y632849D01*
G01X519778Y632695D02*
X532778D01*
G01X522328Y635236D02*
X522861D01*
Y634486D01*
X522701Y634236D01*
X522515Y634069D01*
X522248Y633986D01*
X521981Y634069D01*
X521795Y634236D01*
X521635Y634486D01*
X521528Y634778D01*
X521475Y635111D01*
Y635403D01*
X521528Y635653D01*
X521635Y635944D01*
X521795Y636194D01*
X521955Y636361D01*
X522168Y636486D01*
X522355D01*
X522568Y636403D01*
X522728Y636236D01*
G01X516640Y648856D02*
Y698456D01*
G01X566240Y648856D02*
X516640D01*
G01X512932Y705157D02*
X513092Y705407D01*
X513279Y705532D01*
X513492Y705574D01*
X513759Y705491D01*
X513946Y705282D01*
X513999Y705032D01*
X513972Y704782D01*
X513866Y704574D01*
X513332Y704157D01*
X513092Y703866D01*
X512932Y703449D01*
X512879Y703074D01*
X513999D01*
G01X515052Y703449D02*
X515212Y703241D01*
X515399Y703116D01*
X515639Y703074D01*
X515879Y703157D01*
X516066Y703324D01*
X516199Y703616D01*
X516226Y703949D01*
X516172Y704282D01*
X516039Y704491D01*
X515852Y704657D01*
X515666Y704699D01*
X515479Y704657D01*
X515239Y704491D01*
X515319Y705574D01*
X516039D01*
G01X516640Y698456D02*
X564940D01*
G01X517740Y708056D02*
Y713056D01*
G01X527086Y710494D02*
X523986D01*
Y711453D01*
X524141Y711759D01*
X524348Y711951D01*
X524761Y712028D01*
X525174Y711951D01*
X525433Y711721D01*
X525588Y711453D01*
Y710494D01*
G01Y711453D02*
X527086Y712028D01*
G01Y714361D02*
X523986D01*
X524606Y713901D01*
G01X527086D02*
Y714821D01*
G01Y717461D02*
X523986D01*
X524606Y717001D01*
G01X527086D02*
Y717921D01*
G01X525794Y719833D02*
X525433Y720101D01*
X525226Y720331D01*
X525123Y720638D01*
X525226Y720906D01*
X525433Y721098D01*
X525743Y721251D01*
X526104Y721289D01*
X526414Y721251D01*
X526724Y721098D01*
X526983Y720868D01*
X527086Y720599D01*
X526983Y720293D01*
X526673Y720024D01*
X526208Y719871D01*
X525691Y719833D01*
X525019Y719909D01*
X524658Y720024D01*
X524296Y720216D01*
X524038Y720484D01*
X523986Y720753D01*
X524089Y721021D01*
X524348Y721213D01*
G01X523986Y723661D02*
X524089Y723354D01*
X524348Y723124D01*
X524658Y722971D01*
X525071Y722856D01*
X525536Y722818D01*
X526001Y722856D01*
X526414Y722971D01*
X526724Y723124D01*
X526983Y723354D01*
X527086Y723661D01*
X526983Y723968D01*
X526724Y724198D01*
X526414Y724351D01*
X526001Y724466D01*
X525536Y724504D01*
X525071Y724466D01*
X524658Y724351D01*
X524348Y724198D01*
X524089Y723968D01*
X523986Y723661D01*
G01X520540Y725456D02*
X517340D01*
G01X520540Y731656D02*
Y725456D01*
G01X517340Y731656D02*
X520540D01*
G01X517340Y725456D02*
Y731656D01*
G01X520440Y728556D02*
X517440D01*
G01X522540Y737556D02*
X519340D01*
G01X522540Y743756D02*
Y737556D01*
G01X519340D02*
Y743756D01*
G01X525540Y726056D02*
X522340D01*
G01X525540Y732256D02*
Y726056D01*
G01X522340Y732256D02*
X525540D01*
G01X522340Y726056D02*
Y732256D01*
G01X525440Y729156D02*
X522440D01*
G01X513740Y743756D02*
Y737556D01*
G01X516540Y726056D02*
X513340D01*
G01X516540Y732256D02*
Y726056D01*
G01X516440Y729156D02*
X513440D01*
G01X513340Y732256D02*
X516540D01*
G01X513340Y726056D02*
Y732256D01*
G01X511270Y732158D02*
Y725958D01*
G01X515340Y737556D02*
Y743756D01*
G01X518540Y737556D02*
X515340D01*
G01X518540Y743756D02*
Y737556D01*
G01X523840D02*
Y743756D01*
G01X527040Y737556D02*
X523840D01*
G01X513736Y748908D02*
X513581Y748678D01*
X513478Y748410D01*
Y748103D01*
X513633Y747758D01*
X513891Y747490D01*
X514201Y747298D01*
X514718Y747145D01*
X515183Y747107D01*
X515648Y747183D01*
X515958Y747298D01*
X516268Y747528D01*
X516475Y747797D01*
X516578Y748065D01*
Y748333D01*
X516475Y748602D01*
X516320Y748832D01*
X516113Y749023D01*
G01X516578Y751088D02*
X515906Y751165D01*
X515338Y751280D01*
X514821Y751433D01*
X514253Y751625D01*
X513478Y751932D01*
Y750398D01*
G01X516113Y753422D02*
X516371Y753652D01*
X516526Y753920D01*
X516578Y754265D01*
X516475Y754610D01*
X516268Y754878D01*
X515906Y755070D01*
X515493Y755108D01*
X515080Y755032D01*
X514821Y754840D01*
X514615Y754572D01*
X514563Y754303D01*
X514615Y754035D01*
X514821Y753690D01*
X513478Y753805D01*
Y754840D01*
G01X516113Y756522D02*
X516371Y756752D01*
X516526Y757020D01*
X516578Y757365D01*
X516475Y757710D01*
X516268Y757978D01*
X515906Y758170D01*
X515493Y758208D01*
X515080Y758132D01*
X514821Y757940D01*
X514615Y757672D01*
X514563Y757403D01*
X514615Y757135D01*
X514821Y756790D01*
X513478Y756905D01*
Y757940D01*
G01X519340Y743756D02*
X522540D01*
G01X522440Y740656D02*
X519440D01*
G01X521396Y748908D02*
X521241Y748678D01*
X521138Y748410D01*
Y748103D01*
X521293Y747758D01*
X521551Y747490D01*
X521861Y747298D01*
X522378Y747145D01*
X522843Y747107D01*
X523308Y747183D01*
X523618Y747298D01*
X523928Y747528D01*
X524135Y747797D01*
X524238Y748065D01*
Y748333D01*
X524135Y748602D01*
X523980Y748832D01*
X523773Y749023D01*
G01X524238Y751088D02*
X523566Y751165D01*
X522998Y751280D01*
X522481Y751433D01*
X521913Y751625D01*
X521138Y751932D01*
Y750398D01*
G01X524238Y754725D02*
X521138D01*
X523360Y753307D01*
Y755223D01*
G01X523876Y756713D02*
X524135Y756982D01*
X524238Y757288D01*
X524135Y757595D01*
X523825Y757863D01*
X523360Y758055D01*
X522895Y758132D01*
X522326D01*
X521861Y758055D01*
X521448Y757863D01*
X521241Y757633D01*
X521138Y757365D01*
X521241Y757058D01*
X521448Y756828D01*
X521758Y756675D01*
X522171Y756598D01*
X522533Y756675D01*
X522895Y756867D01*
X523101Y757097D01*
X523153Y757365D01*
X523050Y757672D01*
X522791Y757902D01*
X522326Y758132D01*
G01X513640Y740656D02*
X510640D01*
G01X517463Y748908D02*
X517308Y748678D01*
X517205Y748410D01*
Y748103D01*
X517360Y747758D01*
X517618Y747490D01*
X517928Y747298D01*
X518445Y747145D01*
X518910Y747107D01*
X519375Y747183D01*
X519685Y747298D01*
X519995Y747528D01*
X520202Y747797D01*
X520305Y748065D01*
Y748333D01*
X520202Y748602D01*
X520047Y748832D01*
X519840Y749023D01*
G01X520305Y751088D02*
X519633Y751165D01*
X519065Y751280D01*
X518548Y751433D01*
X517980Y751625D01*
X517205Y751932D01*
Y750398D01*
G01X519685Y753422D02*
X520047Y753652D01*
X520253Y753958D01*
X520305Y754303D01*
X520253Y754610D01*
X519995Y754917D01*
X519685Y755108D01*
X519375Y755147D01*
X519013Y755070D01*
X518755Y754802D01*
X518652Y754533D01*
Y754188D01*
G01Y754533D02*
X518497Y754763D01*
X518238Y754955D01*
X517928Y755032D01*
X517618Y754955D01*
X517360Y754763D01*
X517205Y754418D01*
X517257Y754073D01*
X517463Y753728D01*
G01X520305Y757825D02*
X517205D01*
X519427Y756407D01*
Y758323D01*
G01X528288Y747298D02*
X525188D01*
Y748257D01*
X525343Y748563D01*
X525550Y748755D01*
X525963Y748832D01*
X526376Y748755D01*
X526635Y748525D01*
X526790Y748257D01*
Y747298D01*
G01Y748257D02*
X528288Y748832D01*
G01X527926Y750513D02*
X528185Y750782D01*
X528288Y751088D01*
X528185Y751395D01*
X527875Y751663D01*
X527410Y751855D01*
X526945Y751932D01*
X526376D01*
X525911Y751855D01*
X525498Y751663D01*
X525291Y751433D01*
X525188Y751165D01*
X525291Y750858D01*
X525498Y750628D01*
X525808Y750475D01*
X526221Y750398D01*
X526583Y750475D01*
X526945Y750667D01*
X527151Y750897D01*
X527203Y751165D01*
X527100Y751472D01*
X526841Y751702D01*
X526376Y751932D01*
G01X528288Y754265D02*
X528236Y754533D01*
X528081Y754840D01*
X527823Y755032D01*
X527461Y755108D01*
X527100Y755032D01*
X526790Y754802D01*
X526635Y754457D01*
Y754073D01*
X526531Y753843D01*
X526273Y753652D01*
X525911Y753575D01*
X525550Y753690D01*
X525291Y753958D01*
X525188Y754265D01*
X525291Y754572D01*
X525550Y754840D01*
X525911Y754955D01*
X526273Y754878D01*
X526531Y754687D01*
X526635Y754457D01*
Y754073D01*
X526790Y753728D01*
X527100Y753498D01*
X527461Y753422D01*
X527823Y753498D01*
X528081Y753690D01*
X528236Y753997D01*
X528288Y754265D01*
G01X527668Y756522D02*
X528030Y756752D01*
X528236Y757058D01*
X528288Y757403D01*
X528236Y757710D01*
X527978Y758017D01*
X527668Y758208D01*
X527358Y758247D01*
X526996Y758170D01*
X526738Y757902D01*
X526635Y757633D01*
Y757288D01*
G01Y757633D02*
X526480Y757863D01*
X526221Y758055D01*
X525911Y758132D01*
X525601Y758055D01*
X525343Y757863D01*
X525188Y757518D01*
X525240Y757173D01*
X525446Y756828D01*
G01X515340Y743756D02*
X518540D01*
G01X523840D02*
X527040D01*
G01X515725Y762135D02*
X515570Y761905D01*
X515467Y761637D01*
Y761330D01*
X515622Y760985D01*
X515880Y760717D01*
X516190Y760525D01*
X516707Y760372D01*
X517172Y760334D01*
X517637Y760410D01*
X517947Y760525D01*
X518257Y760755D01*
X518464Y761024D01*
X518567Y761292D01*
Y761560D01*
X518464Y761829D01*
X518309Y762059D01*
X518102Y762250D01*
G01X518567Y764315D02*
X517895Y764392D01*
X517327Y764507D01*
X516810Y764660D01*
X516242Y764852D01*
X515467Y765159D01*
Y763625D01*
G01X518102Y766649D02*
X518360Y766879D01*
X518515Y767147D01*
X518567Y767492D01*
X518464Y767837D01*
X518257Y768105D01*
X517895Y768297D01*
X517482Y768335D01*
X517069Y768259D01*
X516810Y768067D01*
X516604Y767799D01*
X516552Y767530D01*
X516604Y767262D01*
X516810Y766917D01*
X515467Y767032D01*
Y768067D01*
G01X515984Y769864D02*
X515674Y770094D01*
X515519Y770362D01*
X515467Y770669D01*
X515570Y771052D01*
X515829Y771320D01*
X516139Y771397D01*
X516449Y771359D01*
X516707Y771205D01*
X517224Y770439D01*
X517585Y770094D01*
X518102Y769864D01*
X518567Y769787D01*
Y771397D01*
G01X523731Y762135D02*
X523576Y761905D01*
X523473Y761637D01*
Y761330D01*
X523628Y760985D01*
X523886Y760717D01*
X524196Y760525D01*
X524713Y760372D01*
X525178Y760334D01*
X525643Y760410D01*
X525953Y760525D01*
X526263Y760755D01*
X526470Y761024D01*
X526573Y761292D01*
Y761560D01*
X526470Y761829D01*
X526315Y762059D01*
X526108Y762250D01*
G01X526573Y764315D02*
X525901Y764392D01*
X525333Y764507D01*
X524816Y764660D01*
X524248Y764852D01*
X523473Y765159D01*
Y763625D01*
G01X526573Y767952D02*
X523473D01*
X525695Y766534D01*
Y768450D01*
G01X525281Y769864D02*
X524920Y770132D01*
X524713Y770362D01*
X524610Y770669D01*
X524713Y770937D01*
X524920Y771129D01*
X525230Y771282D01*
X525591Y771320D01*
X525901Y771282D01*
X526211Y771129D01*
X526470Y770899D01*
X526573Y770630D01*
X526470Y770324D01*
X526160Y770055D01*
X525695Y769902D01*
X525178Y769864D01*
X524506Y769940D01*
X524145Y770055D01*
X523783Y770247D01*
X523525Y770515D01*
X523473Y770784D01*
X523576Y771052D01*
X523835Y771244D01*
G01X515038Y760525D02*
X511938D01*
Y761484D01*
X512093Y761790D01*
X512300Y761982D01*
X512713Y762059D01*
X513126Y761982D01*
X513385Y761752D01*
X513540Y761484D01*
Y760525D01*
G01Y761484D02*
X515038Y762059D01*
G01X514676Y763740D02*
X514935Y764009D01*
X515038Y764315D01*
X514935Y764622D01*
X514625Y764890D01*
X514160Y765082D01*
X513695Y765159D01*
X513126D01*
X512661Y765082D01*
X512248Y764890D01*
X512041Y764660D01*
X511938Y764392D01*
X512041Y764085D01*
X512248Y763855D01*
X512558Y763702D01*
X512971Y763625D01*
X513333Y763702D01*
X513695Y763894D01*
X513901Y764124D01*
X513953Y764392D01*
X513850Y764699D01*
X513591Y764929D01*
X513126Y765159D01*
G01X514676Y766840D02*
X514935Y767109D01*
X515038Y767415D01*
X514935Y767722D01*
X514625Y767990D01*
X514160Y768182D01*
X513695Y768259D01*
X513126D01*
X512661Y768182D01*
X512248Y767990D01*
X512041Y767760D01*
X511938Y767492D01*
X512041Y767185D01*
X512248Y766955D01*
X512558Y766802D01*
X512971Y766725D01*
X513333Y766802D01*
X513695Y766994D01*
X513901Y767224D01*
X513953Y767492D01*
X513850Y767799D01*
X513591Y768029D01*
X513126Y768259D01*
G01X512455Y769864D02*
X512145Y770094D01*
X511990Y770362D01*
X511938Y770669D01*
X512041Y771052D01*
X512300Y771320D01*
X512610Y771397D01*
X512920Y771359D01*
X513178Y771205D01*
X513695Y770439D01*
X514056Y770094D01*
X514573Y769864D01*
X515038Y769787D01*
Y771397D01*
G01X522567Y760525D02*
X519467D01*
Y761484D01*
X519622Y761790D01*
X519829Y761982D01*
X520242Y762059D01*
X520655Y761982D01*
X520914Y761752D01*
X521069Y761484D01*
Y760525D01*
G01Y761484D02*
X522567Y762059D01*
G01X522205Y763740D02*
X522464Y764009D01*
X522567Y764315D01*
X522464Y764622D01*
X522154Y764890D01*
X521689Y765082D01*
X521224Y765159D01*
X520655D01*
X520190Y765082D01*
X519777Y764890D01*
X519570Y764660D01*
X519467Y764392D01*
X519570Y764085D01*
X519777Y763855D01*
X520087Y763702D01*
X520500Y763625D01*
X520862Y763702D01*
X521224Y763894D01*
X521430Y764124D01*
X521482Y764392D01*
X521379Y764699D01*
X521120Y764929D01*
X520655Y765159D01*
G01X522567Y767492D02*
X522515Y767760D01*
X522360Y768067D01*
X522102Y768259D01*
X521740Y768335D01*
X521379Y768259D01*
X521069Y768029D01*
X520914Y767684D01*
Y767300D01*
X520810Y767070D01*
X520552Y766879D01*
X520190Y766802D01*
X519829Y766917D01*
X519570Y767185D01*
X519467Y767492D01*
X519570Y767799D01*
X519829Y768067D01*
X520190Y768182D01*
X520552Y768105D01*
X520810Y767914D01*
X520914Y767684D01*
Y767300D01*
X521069Y766955D01*
X521379Y766725D01*
X521740Y766649D01*
X522102Y766725D01*
X522360Y766917D01*
X522515Y767224D01*
X522567Y767492D01*
G01X521275Y769864D02*
X520914Y770132D01*
X520707Y770362D01*
X520604Y770669D01*
X520707Y770937D01*
X520914Y771129D01*
X521224Y771282D01*
X521585Y771320D01*
X521895Y771282D01*
X522205Y771129D01*
X522464Y770899D01*
X522567Y770630D01*
X522464Y770324D01*
X522154Y770055D01*
X521689Y769902D01*
X521172Y769864D01*
X520500Y769940D01*
X520139Y770055D01*
X519777Y770247D01*
X519519Y770515D01*
X519467Y770784D01*
X519570Y771052D01*
X519829Y771244D01*
G01X537297Y13629D02*
Y20312D01*
X537318D01*
X539511Y18119D01*
X539490Y18098D01*
X534662D01*
X536897Y20333D01*
X537234D01*
G01X539082Y65532D02*
Y72215D01*
X539103D01*
X541296Y70022D01*
X541275Y70001D01*
X536447D01*
X538682Y72236D01*
X539019D01*
G01X538624Y73211D02*
X538934Y73403D01*
X539141Y73633D01*
X539244Y73901D01*
X539141Y74208D01*
X538934Y74438D01*
X538624Y74668D01*
X538211Y74745D01*
X536144D01*
G01X539244Y77078D02*
X539192Y77346D01*
X539037Y77653D01*
X538779Y77845D01*
X538417Y77921D01*
X538056Y77845D01*
X537746Y77615D01*
X537591Y77270D01*
Y76886D01*
X537487Y76656D01*
X537229Y76465D01*
X536867Y76388D01*
X536506Y76503D01*
X536247Y76771D01*
X536144Y77078D01*
X536247Y77385D01*
X536506Y77653D01*
X536867Y77768D01*
X537229Y77691D01*
X537487Y77500D01*
X537591Y77270D01*
Y76886D01*
X537746Y76541D01*
X538056Y76311D01*
X538417Y76235D01*
X538779Y76311D01*
X539037Y76503D01*
X539192Y76810D01*
X539244Y77078D01*
G01X540689Y71889D02*
X561673D01*
G01D02*
X540689D01*
G01D02*
Y91889D01*
G01X561673Y71889D02*
X540689D01*
G01Y91889D02*
X561673D01*
G01X536553Y85630D02*
X536398Y85400D01*
X536295Y85132D01*
Y84825D01*
X536450Y84480D01*
X536708Y84212D01*
X537018Y84020D01*
X537535Y83867D01*
X538000Y83829D01*
X538465Y83905D01*
X538775Y84020D01*
X539085Y84250D01*
X539292Y84519D01*
X539395Y84787D01*
Y85055D01*
X539292Y85324D01*
X539137Y85554D01*
X538930Y85745D01*
G01X539395Y88347D02*
X536295D01*
X538517Y86929D01*
Y88845D01*
G01X539395Y90987D02*
X539343Y91255D01*
X539188Y91562D01*
X538930Y91754D01*
X538568Y91830D01*
X538207Y91754D01*
X537897Y91524D01*
X537742Y91179D01*
Y90795D01*
X537638Y90565D01*
X537380Y90374D01*
X537018Y90297D01*
X536657Y90412D01*
X536398Y90680D01*
X536295Y90987D01*
X536398Y91294D01*
X536657Y91562D01*
X537018Y91677D01*
X537380Y91600D01*
X537638Y91409D01*
X537742Y91179D01*
Y90795D01*
X537897Y90450D01*
X538207Y90220D01*
X538568Y90144D01*
X538930Y90220D01*
X539188Y90412D01*
X539343Y90719D01*
X539395Y90987D01*
G01X538930Y93244D02*
X539188Y93474D01*
X539343Y93742D01*
X539395Y94087D01*
X539292Y94432D01*
X539085Y94700D01*
X538723Y94892D01*
X538310Y94930D01*
X537897Y94854D01*
X537638Y94662D01*
X537432Y94394D01*
X537380Y94125D01*
X537432Y93857D01*
X537638Y93512D01*
X536295Y93627D01*
Y94662D01*
G01X535357Y84020D02*
X532257D01*
Y84979D01*
X532412Y85285D01*
X532619Y85477D01*
X533032Y85554D01*
X533445Y85477D01*
X533704Y85247D01*
X533859Y84979D01*
Y84020D01*
G01Y84979D02*
X535357Y85554D01*
G01Y87887D02*
X532257D01*
X532877Y87427D01*
G01X535357D02*
Y88347D01*
G01Y90987D02*
X532257D01*
X532877Y90527D01*
G01X535357D02*
Y91447D01*
G01Y94547D02*
X532257D01*
X534479Y93129D01*
Y95045D01*
G01X534995Y96535D02*
X535254Y96804D01*
X535357Y97110D01*
X535254Y97417D01*
X534944Y97685D01*
X534479Y97877D01*
X534014Y97954D01*
X533445D01*
X532980Y97877D01*
X532567Y97685D01*
X532360Y97455D01*
X532257Y97187D01*
X532360Y96880D01*
X532567Y96650D01*
X532877Y96497D01*
X533290Y96420D01*
X533652Y96497D01*
X534014Y96689D01*
X534220Y96919D01*
X534272Y97187D01*
X534169Y97494D01*
X533910Y97724D01*
X533445Y97954D01*
G01X531302Y84020D02*
X528202D01*
Y84979D01*
X528357Y85285D01*
X528564Y85477D01*
X528977Y85554D01*
X529390Y85477D01*
X529649Y85247D01*
X529804Y84979D01*
Y84020D01*
G01Y84979D02*
X531302Y85554D01*
G01Y87887D02*
X528202D01*
X528822Y87427D01*
G01X531302D02*
Y88347D01*
G01Y90987D02*
X528202D01*
X528822Y90527D01*
G01X531302D02*
Y91447D01*
G01Y94547D02*
X528202D01*
X530424Y93129D01*
Y95045D01*
G01X531302Y97187D02*
X531250Y97455D01*
X531095Y97762D01*
X530837Y97954D01*
X530475Y98030D01*
X530114Y97954D01*
X529804Y97724D01*
X529649Y97379D01*
Y96995D01*
X529545Y96765D01*
X529287Y96574D01*
X528925Y96497D01*
X528564Y96612D01*
X528305Y96880D01*
X528202Y97187D01*
X528305Y97494D01*
X528564Y97762D01*
X528925Y97877D01*
X529287Y97800D01*
X529545Y97609D01*
X529649Y97379D01*
Y96995D01*
X529804Y96650D01*
X530114Y96420D01*
X530475Y96344D01*
X530837Y96420D01*
X531095Y96612D01*
X531250Y96919D01*
X531302Y97187D01*
G01X540460Y93880D02*
X563790D01*
G01X539240Y95950D02*
X539200D01*
G01X539240Y107150D02*
Y95950D01*
G01X557580Y107150D02*
X539240D01*
G01X540205Y114325D02*
Y108325D01*
G01X535355Y107704D02*
X538555D01*
G01X538455Y104604D02*
X535455D01*
G01X535355Y101504D02*
Y107704D01*
G01X538555D02*
Y101504D01*
G01D02*
X535355D01*
G01X539948Y105186D02*
X544548D01*
G01Y100086D02*
X539948D01*
G01X544548Y94986D02*
X539948D01*
G01D02*
Y105186D01*
G01X531355Y101504D02*
Y107704D01*
G01X534555D02*
Y101504D01*
G01D02*
X531355D01*
G01Y107704D02*
X534555D01*
G01X527355D02*
X530555D01*
G01D02*
Y101504D01*
G01D02*
X527355D01*
G01D02*
Y107704D01*
G01X526555D02*
Y101504D01*
G01X530305Y114325D02*
Y111325D01*
G01X533716Y195851D02*
Y193629D01*
X533869Y193164D01*
X534176Y192854D01*
X534559Y192751D01*
X534942Y192854D01*
X535249Y193164D01*
X535402Y193629D01*
Y195851D01*
G01X538119Y192751D02*
Y195851D01*
X536701Y193629D01*
X538617D01*
G01X539916Y193371D02*
X540146Y193009D01*
X540452Y192803D01*
X540797Y192751D01*
X541104Y192803D01*
X541411Y193061D01*
X541602Y193371D01*
X541641Y193681D01*
X541564Y194043D01*
X541296Y194301D01*
X541027Y194404D01*
X540682D01*
G01X541027D02*
X541257Y194559D01*
X541449Y194818D01*
X541526Y195128D01*
X541449Y195438D01*
X541257Y195696D01*
X540912Y195851D01*
X540567Y195799D01*
X540222Y195593D01*
G01X536305Y189925D02*
Y192925D01*
G01X526505Y189925D02*
Y195925D01*
G01X530900Y199400D02*
Y205600D01*
G01X534100D02*
Y199400D01*
G01D02*
X530900D01*
G01X542100D02*
X538900D01*
G01D02*
Y205600D01*
G01X542100D02*
Y199400D01*
G01X530100Y205600D02*
Y199400D01*
G01D02*
X526900D01*
G01D02*
Y205600D01*
G01X538257Y205665D02*
Y199465D01*
G01D02*
X535057D01*
G01D02*
Y205665D01*
G01X541132Y209067D02*
X544002D01*
G01X530900Y205600D02*
X534100D01*
G01X538849Y218470D02*
Y221570D01*
X539808D01*
X540114Y221415D01*
X540306Y221208D01*
X540383Y220795D01*
X540306Y220382D01*
X540076Y220123D01*
X539808Y219968D01*
X538849D01*
G01X539808D02*
X540383Y218470D01*
G01X541873Y218935D02*
X542103Y218677D01*
X542371Y218522D01*
X542716Y218470D01*
X543061Y218573D01*
X543329Y218780D01*
X543521Y219142D01*
X543559Y219555D01*
X543483Y219968D01*
X543291Y220227D01*
X543023Y220433D01*
X542754Y220485D01*
X542486Y220433D01*
X542141Y220227D01*
X542256Y221570D01*
X543291D01*
G01X545816Y218470D02*
Y221570D01*
X545356Y220950D01*
G01Y218470D02*
X546276D01*
G01X548916D02*
Y221570D01*
X548456Y220950D01*
G01Y218470D02*
X549376D01*
G01X539815Y214302D02*
Y217402D01*
X540774D01*
X541080Y217247D01*
X541272Y217040D01*
X541349Y216627D01*
X541272Y216214D01*
X541042Y215955D01*
X540774Y215800D01*
X539815D01*
G01X540774D02*
X541349Y214302D01*
G01X542839Y214767D02*
X543069Y214509D01*
X543337Y214354D01*
X543682Y214302D01*
X544027Y214405D01*
X544295Y214612D01*
X544487Y214974D01*
X544525Y215387D01*
X544449Y215800D01*
X544257Y216059D01*
X543989Y216265D01*
X543720Y216317D01*
X543452Y216265D01*
X543107Y216059D01*
X543222Y217402D01*
X544257D01*
G01X546782Y214302D02*
Y217402D01*
X546322Y216782D01*
G01Y214302D02*
X547242D01*
G01X549154Y216885D02*
X549384Y217195D01*
X549652Y217350D01*
X549959Y217402D01*
X550342Y217299D01*
X550610Y217040D01*
X550687Y216730D01*
X550649Y216420D01*
X550495Y216162D01*
X549729Y215645D01*
X549384Y215284D01*
X549154Y214767D01*
X549077Y214302D01*
X550687D01*
G01X530329Y214713D02*
Y220913D01*
G01X533529D02*
Y214713D01*
G01D02*
X530329D01*
G01X546335Y210032D02*
X540135D01*
G01D02*
Y213232D01*
G01D02*
X546335D01*
G01X534329Y214713D02*
Y220913D01*
G01X537529D02*
Y214713D01*
G01D02*
X534329D01*
G01X538900Y205600D02*
X542100D01*
G01X526900D02*
X530100D01*
G01X535057Y205665D02*
X538257D01*
G01X537059Y228053D02*
Y231153D01*
X538018D01*
X538324Y230998D01*
X538516Y230791D01*
X538593Y230378D01*
X538516Y229965D01*
X538286Y229706D01*
X538018Y229551D01*
X537059D01*
G01X538018D02*
X538593Y228053D01*
G01X540083Y228518D02*
X540313Y228260D01*
X540581Y228105D01*
X540926Y228053D01*
X541271Y228156D01*
X541539Y228363D01*
X541731Y228725D01*
X541769Y229138D01*
X541693Y229551D01*
X541501Y229810D01*
X541233Y230016D01*
X540964Y230068D01*
X540696Y230016D01*
X540351Y229810D01*
X540466Y231153D01*
X541501D01*
G01X544026Y228053D02*
Y231153D01*
X543566Y230533D01*
G01Y228053D02*
X544486D01*
G01X547126Y231153D02*
X546819Y231050D01*
X546589Y230791D01*
X546436Y230481D01*
X546321Y230068D01*
X546283Y229603D01*
X546321Y229138D01*
X546436Y228725D01*
X546589Y228415D01*
X546819Y228156D01*
X547126Y228053D01*
X547433Y228156D01*
X547663Y228415D01*
X547816Y228725D01*
X547931Y229138D01*
X547969Y229603D01*
X547931Y230068D01*
X547816Y230481D01*
X547663Y230791D01*
X547433Y231050D01*
X547126Y231153D01*
G01X538929Y222511D02*
Y225611D01*
X539888D01*
X540194Y225456D01*
X540386Y225249D01*
X540463Y224836D01*
X540386Y224423D01*
X540156Y224164D01*
X539888Y224009D01*
X538929D01*
G01X539888D02*
X540463Y222511D01*
G01X541953Y222976D02*
X542183Y222718D01*
X542451Y222563D01*
X542796Y222511D01*
X543141Y222614D01*
X543409Y222821D01*
X543601Y223183D01*
X543639Y223596D01*
X543563Y224009D01*
X543371Y224268D01*
X543103Y224474D01*
X542834Y224526D01*
X542566Y224474D01*
X542221Y224268D01*
X542336Y225611D01*
X543371D01*
G01X545896D02*
X545589Y225508D01*
X545359Y225249D01*
X545206Y224939D01*
X545091Y224526D01*
X545053Y224061D01*
X545091Y223596D01*
X545206Y223183D01*
X545359Y222873D01*
X545589Y222614D01*
X545896Y222511D01*
X546203Y222614D01*
X546433Y222873D01*
X546586Y223183D01*
X546701Y223596D01*
X546739Y224061D01*
X546701Y224526D01*
X546586Y224939D01*
X546433Y225249D01*
X546203Y225508D01*
X545896Y225611D01*
G01X548344Y222873D02*
X548613Y222614D01*
X548919Y222511D01*
X549226Y222614D01*
X549494Y222924D01*
X549686Y223389D01*
X549763Y223854D01*
Y224423D01*
X549686Y224888D01*
X549494Y225301D01*
X549264Y225508D01*
X548996Y225611D01*
X548689Y225508D01*
X548459Y225301D01*
X548306Y224991D01*
X548229Y224578D01*
X548306Y224216D01*
X548498Y223854D01*
X548728Y223648D01*
X548996Y223596D01*
X549303Y223699D01*
X549533Y223958D01*
X549763Y224423D01*
G01X544807Y233393D02*
X538607D01*
G01D02*
Y236593D01*
G01X532200Y221883D02*
X529100D01*
Y222842D01*
X529255Y223148D01*
X529462Y223340D01*
X529875Y223417D01*
X530288Y223340D01*
X530547Y223110D01*
X530702Y222842D01*
Y221883D01*
G01Y222842D02*
X532200Y223417D01*
G01Y225750D02*
X529100D01*
X529720Y225290D01*
G01X532200D02*
Y226210D01*
G01Y228850D02*
X529100D01*
X529720Y228390D01*
G01X532200D02*
Y229310D01*
G01X531580Y231107D02*
X531942Y231337D01*
X532148Y231643D01*
X532200Y231988D01*
X532148Y232295D01*
X531890Y232602D01*
X531580Y232793D01*
X531270Y232832D01*
X530908Y232755D01*
X530650Y232487D01*
X530547Y232218D01*
Y231873D01*
G01Y232218D02*
X530392Y232448D01*
X530133Y232640D01*
X529823Y232717D01*
X529513Y232640D01*
X529255Y232448D01*
X529100Y232103D01*
X529152Y231758D01*
X529358Y231413D01*
G01X532200Y235510D02*
X529100D01*
X531322Y234092D01*
Y236008D01*
G01X530329Y220913D02*
X533529D01*
G01X536300Y221883D02*
X533200D01*
Y222842D01*
X533355Y223148D01*
X533562Y223340D01*
X533975Y223417D01*
X534388Y223340D01*
X534647Y223110D01*
X534802Y222842D01*
Y221883D01*
G01Y222842D02*
X536300Y223417D01*
G01Y225750D02*
X533200D01*
X533820Y225290D01*
G01X536300D02*
Y226210D01*
G01Y228850D02*
X533200D01*
X533820Y228390D01*
G01X536300D02*
Y229310D01*
G01X535680Y231107D02*
X536042Y231337D01*
X536248Y231643D01*
X536300Y231988D01*
X536248Y232295D01*
X535990Y232602D01*
X535680Y232793D01*
X535370Y232832D01*
X535008Y232755D01*
X534750Y232487D01*
X534647Y232218D01*
Y231873D01*
G01Y232218D02*
X534492Y232448D01*
X534233Y232640D01*
X533923Y232717D01*
X533613Y232640D01*
X533355Y232448D01*
X533200Y232103D01*
X533252Y231758D01*
X533458Y231413D01*
G01X535835Y234207D02*
X536093Y234437D01*
X536248Y234705D01*
X536300Y235050D01*
X536197Y235395D01*
X535990Y235663D01*
X535628Y235855D01*
X535215Y235893D01*
X534802Y235817D01*
X534543Y235625D01*
X534337Y235357D01*
X534285Y235088D01*
X534337Y234820D01*
X534543Y234475D01*
X533200Y234590D01*
Y235625D01*
G01X534329Y220913D02*
X537529D01*
G01X529250Y251540D02*
X529095Y251310D01*
X528992Y251042D01*
Y250735D01*
X529147Y250390D01*
X529405Y250122D01*
X529715Y249930D01*
X530232Y249777D01*
X530697Y249739D01*
X531162Y249815D01*
X531472Y249930D01*
X531782Y250160D01*
X531989Y250429D01*
X532092Y250697D01*
Y250965D01*
X531989Y251234D01*
X531834Y251464D01*
X531627Y251655D01*
G01X531472Y252954D02*
X531834Y253184D01*
X532040Y253490D01*
X532092Y253835D01*
X532040Y254142D01*
X531782Y254449D01*
X531472Y254640D01*
X531162Y254679D01*
X530800Y254602D01*
X530542Y254334D01*
X530439Y254065D01*
Y253720D01*
G01Y254065D02*
X530284Y254295D01*
X530025Y254487D01*
X529715Y254564D01*
X529405Y254487D01*
X529147Y254295D01*
X528992Y253950D01*
X529044Y253605D01*
X529250Y253260D01*
G01X529509Y256169D02*
X529199Y256399D01*
X529044Y256667D01*
X528992Y256974D01*
X529095Y257357D01*
X529354Y257625D01*
X529664Y257702D01*
X529974Y257664D01*
X530232Y257510D01*
X530749Y256744D01*
X531110Y256399D01*
X531627Y256169D01*
X532092Y256092D01*
Y257702D01*
G01X531730Y259345D02*
X531989Y259614D01*
X532092Y259920D01*
X531989Y260227D01*
X531679Y260495D01*
X531214Y260687D01*
X530749Y260764D01*
X530180D01*
X529715Y260687D01*
X529302Y260495D01*
X529095Y260265D01*
X528992Y259997D01*
X529095Y259690D01*
X529302Y259460D01*
X529612Y259307D01*
X530025Y259230D01*
X530387Y259307D01*
X530749Y259499D01*
X530955Y259729D01*
X531007Y259997D01*
X530904Y260304D01*
X530645Y260534D01*
X530180Y260764D01*
G01X534400Y237483D02*
X531300D01*
Y238442D01*
X531455Y238748D01*
X531662Y238940D01*
X532075Y239017D01*
X532488Y238940D01*
X532747Y238710D01*
X532902Y238442D01*
Y237483D01*
G01Y238442D02*
X534400Y239017D01*
G01X533108Y240622D02*
X532747Y240890D01*
X532540Y241120D01*
X532437Y241427D01*
X532540Y241695D01*
X532747Y241887D01*
X533057Y242040D01*
X533418Y242078D01*
X533728Y242040D01*
X534038Y241887D01*
X534297Y241657D01*
X534400Y241388D01*
X534297Y241082D01*
X533987Y240813D01*
X533522Y240660D01*
X533005Y240622D01*
X532333Y240698D01*
X531972Y240813D01*
X531610Y241005D01*
X531352Y241273D01*
X531300Y241542D01*
X531403Y241810D01*
X531662Y242002D01*
G01X533935Y243607D02*
X534193Y243837D01*
X534348Y244105D01*
X534400Y244450D01*
X534297Y244795D01*
X534090Y245063D01*
X533728Y245255D01*
X533315Y245293D01*
X532902Y245217D01*
X532643Y245025D01*
X532437Y244757D01*
X532385Y244488D01*
X532437Y244220D01*
X532643Y243875D01*
X531300Y243990D01*
Y245025D01*
G01X533780Y246707D02*
X534142Y246937D01*
X534348Y247243D01*
X534400Y247588D01*
X534348Y247895D01*
X534090Y248202D01*
X533780Y248393D01*
X533470Y248432D01*
X533108Y248355D01*
X532850Y248087D01*
X532747Y247818D01*
Y247473D01*
G01Y247818D02*
X532592Y248048D01*
X532333Y248240D01*
X532023Y248317D01*
X531713Y248240D01*
X531455Y248048D01*
X531300Y247703D01*
X531352Y247358D01*
X531558Y247013D01*
G01X544807Y237393D02*
X538607D01*
G01D02*
Y240593D01*
G01D02*
X544807D01*
G01Y245393D02*
X538607D01*
G01D02*
Y248593D01*
G01D02*
X544807D01*
G01Y241393D02*
X538607D01*
G01D02*
Y244593D01*
G01D02*
X544807D01*
G01X538607Y236593D02*
X544807D01*
G01X538672Y251562D02*
Y256162D01*
G01X543772Y251562D02*
X533572D01*
G01D02*
Y256162D01*
G01D02*
X543772D01*
G01X532646Y263458D02*
Y266558D01*
X532186Y265938D01*
G01Y263458D02*
X533106D01*
G01X545531Y257456D02*
X533813D01*
G01D02*
Y269268D01*
G01X532301Y274359D02*
Y277459D01*
X533260D01*
X533566Y277304D01*
X533758Y277097D01*
X533835Y276684D01*
X533758Y276271D01*
X533528Y276012D01*
X533260Y275857D01*
X532301D01*
G01X533260D02*
X533835Y274359D01*
G01X535325Y274824D02*
X535555Y274566D01*
X535823Y274411D01*
X536168Y274359D01*
X536513Y274462D01*
X536781Y274669D01*
X536973Y275031D01*
X537011Y275444D01*
X536935Y275857D01*
X536743Y276116D01*
X536475Y276322D01*
X536206Y276374D01*
X535938Y276322D01*
X535593Y276116D01*
X535708Y277459D01*
X536743D01*
G01X539268D02*
X538961Y277356D01*
X538731Y277097D01*
X538578Y276787D01*
X538463Y276374D01*
X538425Y275909D01*
X538463Y275444D01*
X538578Y275031D01*
X538731Y274721D01*
X538961Y274462D01*
X539268Y274359D01*
X539575Y274462D01*
X539805Y274721D01*
X539958Y275031D01*
X540073Y275444D01*
X540111Y275909D01*
X540073Y276374D01*
X539958Y276787D01*
X539805Y277097D01*
X539575Y277356D01*
X539268Y277459D01*
G01X542368Y274359D02*
Y277459D01*
X541908Y276839D01*
G01Y274359D02*
X542828D01*
G01X530838Y269968D02*
X530531Y270020D01*
X530263Y270226D01*
X530033Y270536D01*
X529880Y270898D01*
X529803Y271311D01*
Y271725D01*
X529880Y272138D01*
X530033Y272500D01*
X530263Y272810D01*
X530531Y273016D01*
X530838Y273068D01*
X531145Y273016D01*
X531413Y272810D01*
X531643Y272500D01*
X531796Y272138D01*
X531873Y271725D01*
Y271311D01*
X531796Y270898D01*
X531643Y270536D01*
X531413Y270226D01*
X531145Y270020D01*
X530838Y269968D01*
G01X531145Y270795D02*
X531605Y269968D01*
G01X533938D02*
Y273068D01*
X533478Y272448D01*
G01Y269968D02*
X534398D01*
G01X536310Y272551D02*
X536540Y272861D01*
X536808Y273016D01*
X537115Y273068D01*
X537498Y272965D01*
X537766Y272706D01*
X537843Y272396D01*
X537805Y272086D01*
X537651Y271828D01*
X536885Y271311D01*
X536540Y270950D01*
X536310Y270433D01*
X536233Y269968D01*
X537843D01*
G01X533813Y269268D02*
X545531D01*
G01X545363Y350947D02*
G02I-3543J0D01*
G01X535270Y369843D02*
X535423Y369998D01*
X535538Y370257D01*
X535615Y370618D01*
X535538Y370928D01*
X535385Y371135D01*
X535116Y371290D01*
X534081D01*
Y368190D01*
X535346D01*
X535615Y368397D01*
X535768Y368707D01*
X535845Y369068D01*
X535768Y369430D01*
X535538Y369740D01*
X535270Y369843D01*
X534081D01*
G01X538063Y371290D02*
Y368190D01*
G01X537181Y371290D02*
X538945D01*
G01X541163Y368190D02*
Y371290D01*
X540703Y370670D01*
G01Y368190D02*
X541623D01*
G01X534644Y401113D02*
X531544D01*
Y402072D01*
X531699Y402378D01*
X531906Y402570D01*
X532319Y402647D01*
X532732Y402570D01*
X532991Y402340D01*
X533146Y402072D01*
Y401113D01*
G01Y402072D02*
X534644Y402647D01*
G01Y404980D02*
X531544D01*
X532164Y404520D01*
G01X534644D02*
Y405440D01*
G01Y408080D02*
X534592Y408348D01*
X534437Y408655D01*
X534179Y408847D01*
X533817Y408923D01*
X533456Y408847D01*
X533146Y408617D01*
X532991Y408272D01*
Y407888D01*
X532887Y407658D01*
X532629Y407467D01*
X532267Y407390D01*
X531906Y407505D01*
X531647Y407773D01*
X531544Y408080D01*
X531647Y408387D01*
X531906Y408655D01*
X532267Y408770D01*
X532629Y408693D01*
X532887Y408502D01*
X532991Y408272D01*
Y407888D01*
X533146Y407543D01*
X533456Y407313D01*
X533817Y407237D01*
X534179Y407313D01*
X534437Y407505D01*
X534592Y407812D01*
X534644Y408080D01*
G01Y411180D02*
X534592Y411448D01*
X534437Y411755D01*
X534179Y411947D01*
X533817Y412023D01*
X533456Y411947D01*
X533146Y411717D01*
X532991Y411372D01*
Y410988D01*
X532887Y410758D01*
X532629Y410567D01*
X532267Y410490D01*
X531906Y410605D01*
X531647Y410873D01*
X531544Y411180D01*
X531647Y411487D01*
X531906Y411755D01*
X532267Y411870D01*
X532629Y411793D01*
X532887Y411602D01*
X532991Y411372D01*
Y410988D01*
X533146Y410643D01*
X533456Y410413D01*
X533817Y410337D01*
X534179Y410413D01*
X534437Y410605D01*
X534592Y410912D01*
X534644Y411180D01*
G01X544173Y401113D02*
X541073D01*
Y402072D01*
X541228Y402378D01*
X541435Y402570D01*
X541848Y402647D01*
X542261Y402570D01*
X542520Y402340D01*
X542675Y402072D01*
Y401113D01*
G01Y402072D02*
X544173Y402647D01*
G01Y404980D02*
X541073D01*
X541693Y404520D01*
G01X544173D02*
Y405440D01*
G01X543811Y407428D02*
X544070Y407697D01*
X544173Y408003D01*
X544070Y408310D01*
X543760Y408578D01*
X543295Y408770D01*
X542830Y408847D01*
X542261D01*
X541796Y408770D01*
X541383Y408578D01*
X541176Y408348D01*
X541073Y408080D01*
X541176Y407773D01*
X541383Y407543D01*
X541693Y407390D01*
X542106Y407313D01*
X542468Y407390D01*
X542830Y407582D01*
X543036Y407812D01*
X543088Y408080D01*
X542985Y408387D01*
X542726Y408617D01*
X542261Y408847D01*
G01X539173Y401113D02*
X536073D01*
Y402072D01*
X536228Y402378D01*
X536435Y402570D01*
X536848Y402647D01*
X537261Y402570D01*
X537520Y402340D01*
X537675Y402072D01*
Y401113D01*
G01Y402072D02*
X539173Y402647D01*
G01Y404980D02*
X536073D01*
X536693Y404520D01*
G01X539173D02*
Y405440D01*
G01Y408540D02*
X536073D01*
X538295Y407122D01*
Y409038D01*
G01X529673Y401113D02*
X526573D01*
Y402072D01*
X526728Y402378D01*
X526935Y402570D01*
X527348Y402647D01*
X527761Y402570D01*
X528020Y402340D01*
X528175Y402072D01*
Y401113D01*
G01Y402072D02*
X529673Y402647D01*
G01Y404980D02*
X526573D01*
X527193Y404520D01*
G01X529673D02*
Y405440D01*
G01Y408080D02*
X526573D01*
X527193Y407620D01*
G01X529673D02*
Y408540D01*
G01X539308Y413514D02*
X536208D01*
Y414473D01*
X536363Y414779D01*
X536570Y414971D01*
X536983Y415048D01*
X537396Y414971D01*
X537655Y414741D01*
X537810Y414473D01*
Y413514D01*
G01Y414473D02*
X539308Y415048D01*
G01X536725Y416653D02*
X536415Y416883D01*
X536260Y417151D01*
X536208Y417458D01*
X536311Y417841D01*
X536570Y418109D01*
X536880Y418186D01*
X537190Y418148D01*
X537448Y417994D01*
X537965Y417228D01*
X538326Y416883D01*
X538843Y416653D01*
X539308Y416576D01*
Y418186D01*
G01X538688Y419638D02*
X539050Y419868D01*
X539256Y420174D01*
X539308Y420519D01*
X539256Y420826D01*
X538998Y421133D01*
X538688Y421324D01*
X538378Y421363D01*
X538016Y421286D01*
X537758Y421018D01*
X537655Y420749D01*
Y420404D01*
G01Y420749D02*
X537500Y420979D01*
X537241Y421171D01*
X536931Y421248D01*
X536621Y421171D01*
X536363Y420979D01*
X536208Y420634D01*
X536260Y420289D01*
X536466Y419944D01*
G01X535308Y413514D02*
X532208D01*
Y414473D01*
X532363Y414779D01*
X532570Y414971D01*
X532983Y415048D01*
X533396Y414971D01*
X533655Y414741D01*
X533810Y414473D01*
Y413514D01*
G01Y414473D02*
X535308Y415048D01*
G01Y417381D02*
X532208D01*
X532828Y416921D01*
G01X535308D02*
Y417841D01*
G01X534016Y419753D02*
X533655Y420021D01*
X533448Y420251D01*
X533345Y420558D01*
X533448Y420826D01*
X533655Y421018D01*
X533965Y421171D01*
X534326Y421209D01*
X534636Y421171D01*
X534946Y421018D01*
X535205Y420788D01*
X535308Y420519D01*
X535205Y420213D01*
X534895Y419944D01*
X534430Y419791D01*
X533913Y419753D01*
X533241Y419829D01*
X532880Y419944D01*
X532518Y420136D01*
X532260Y420404D01*
X532208Y420673D01*
X532311Y420941D01*
X532570Y421133D01*
G01X531308Y413514D02*
X528208D01*
Y414473D01*
X528363Y414779D01*
X528570Y414971D01*
X528983Y415048D01*
X529396Y414971D01*
X529655Y414741D01*
X529810Y414473D01*
Y413514D01*
G01Y414473D02*
X531308Y415048D01*
G01Y417381D02*
X528208D01*
X528828Y416921D01*
G01X531308D02*
Y417841D01*
G01Y420404D02*
X530636Y420481D01*
X530068Y420596D01*
X529551Y420749D01*
X528983Y420941D01*
X528208Y421248D01*
Y419714D01*
G01X532540Y423556D02*
X529340D01*
G01X532540Y429756D02*
Y423556D01*
G01X529340Y429756D02*
X532540D01*
G01X529340Y423556D02*
Y429756D01*
G01X542540Y423556D02*
X539340D01*
G01Y429756D02*
X542540D01*
G01X539340Y423556D02*
Y429756D01*
G01X537540Y423556D02*
X534340D01*
G01X537540Y429756D02*
Y423556D01*
G01X534340Y429756D02*
X537540D01*
G01X534340Y423556D02*
Y429756D01*
G01X539840Y433056D02*
Y439256D01*
G01X543040Y433056D02*
X539840D01*
G01Y439256D02*
X543040D01*
G01X534840Y433056D02*
Y439256D01*
G01X538040Y433056D02*
X534840D01*
G01X538040Y439256D02*
Y433056D01*
G01X534840Y439256D02*
X538040D01*
G01X529840Y433056D02*
Y439256D01*
G01X533040Y433056D02*
X529840D01*
G01X533040Y439256D02*
Y433056D01*
G01X529840Y439256D02*
X533040D01*
G01X528040Y429756D02*
Y423556D01*
G01Y439256D02*
Y433056D01*
G01X535827Y444780D02*
Y447280D01*
X535507Y446780D01*
G01Y444780D02*
X536147D01*
G01X538347D02*
Y447280D01*
X537360Y445488D01*
X538694D01*
G01X538946Y448480D02*
Y450980D01*
X538626Y450480D01*
G01Y448480D02*
X539266D01*
G01X540559Y448855D02*
X540719Y448647D01*
X540906Y448522D01*
X541146Y448480D01*
X541386Y448563D01*
X541573Y448730D01*
X541706Y449022D01*
X541733Y449355D01*
X541679Y449688D01*
X541546Y449897D01*
X541359Y450063D01*
X541173Y450105D01*
X540986Y450063D01*
X540746Y449897D01*
X540826Y450980D01*
X541546D01*
G01X537416Y451470D02*
Y448680D01*
G01D02*
X534604D01*
G01X541840Y452362D02*
X540040D01*
G01X527440Y446262D02*
Y442762D01*
G01X541740Y468162D02*
X539940D01*
G01X543490Y460312D02*
X539990D01*
G01X534848Y480487D02*
X535008Y480737D01*
X535195Y480862D01*
X535408Y480904D01*
X535675Y480821D01*
X535862Y480612D01*
X535915Y480362D01*
X535888Y480112D01*
X535782Y479904D01*
X535248Y479487D01*
X535008Y479196D01*
X534848Y478779D01*
X534795Y478404D01*
X535915D01*
G01X537102Y478696D02*
X537288Y478487D01*
X537502Y478404D01*
X537715Y478487D01*
X537902Y478737D01*
X538035Y479112D01*
X538088Y479487D01*
Y479946D01*
X538035Y480321D01*
X537902Y480654D01*
X537742Y480821D01*
X537555Y480904D01*
X537342Y480821D01*
X537182Y480654D01*
X537075Y480404D01*
X537022Y480071D01*
X537075Y479779D01*
X537208Y479487D01*
X537368Y479321D01*
X537555Y479279D01*
X537768Y479362D01*
X537928Y479571D01*
X538088Y479946D01*
G01X538403Y476606D02*
X538563Y476856D01*
X538750Y476981D01*
X538963Y477023D01*
X539230Y476940D01*
X539417Y476731D01*
X539470Y476481D01*
X539443Y476231D01*
X539337Y476023D01*
X538803Y475606D01*
X538563Y475315D01*
X538403Y474898D01*
X538350Y474523D01*
X539470D01*
G01X541110D02*
X541297Y474565D01*
X541510Y474690D01*
X541643Y474898D01*
X541697Y475190D01*
X541643Y475481D01*
X541483Y475731D01*
X541243Y475856D01*
X540977D01*
X540817Y475940D01*
X540683Y476148D01*
X540630Y476440D01*
X540710Y476731D01*
X540897Y476940D01*
X541110Y477023D01*
X541323Y476940D01*
X541510Y476731D01*
X541590Y476440D01*
X541537Y476148D01*
X541403Y475940D01*
X541243Y475856D01*
X540977D01*
X540737Y475731D01*
X540577Y475481D01*
X540523Y475190D01*
X540577Y474898D01*
X540710Y474690D01*
X540923Y474565D01*
X541110Y474523D01*
G01X534704Y476632D02*
X537416D01*
G01D02*
Y473870D01*
G01X532040Y482550D02*
Y479050D01*
G01X532384Y509530D02*
X532229Y509300D01*
X532126Y509032D01*
Y508725D01*
X532281Y508380D01*
X532539Y508112D01*
X532849Y507920D01*
X533366Y507767D01*
X533831Y507729D01*
X534296Y507805D01*
X534606Y507920D01*
X534916Y508150D01*
X535123Y508419D01*
X535226Y508687D01*
Y508955D01*
X535123Y509224D01*
X534968Y509454D01*
X534761Y509645D01*
G01X535226Y511787D02*
X532126D01*
X532746Y511327D01*
G01X535226D02*
Y512247D01*
G01Y514887D02*
X535174Y515155D01*
X535019Y515462D01*
X534761Y515654D01*
X534399Y515730D01*
X534038Y515654D01*
X533728Y515424D01*
X533573Y515079D01*
Y514695D01*
X533469Y514465D01*
X533211Y514274D01*
X532849Y514197D01*
X532488Y514312D01*
X532229Y514580D01*
X532126Y514887D01*
X532229Y515194D01*
X532488Y515462D01*
X532849Y515577D01*
X533211Y515500D01*
X533469Y515309D01*
X533573Y515079D01*
Y514695D01*
X533728Y514350D01*
X534038Y514120D01*
X534399Y514044D01*
X534761Y514120D01*
X535019Y514312D01*
X535174Y514619D01*
X535226Y514887D01*
G01X534864Y517335D02*
X535123Y517604D01*
X535226Y517910D01*
X535123Y518217D01*
X534813Y518485D01*
X534348Y518677D01*
X533883Y518754D01*
X533314D01*
X532849Y518677D01*
X532436Y518485D01*
X532229Y518255D01*
X532126Y517987D01*
X532229Y517680D01*
X532436Y517450D01*
X532746Y517297D01*
X533159Y517220D01*
X533521Y517297D01*
X533883Y517489D01*
X534089Y517719D01*
X534141Y517987D01*
X534038Y518294D01*
X533779Y518524D01*
X533314Y518754D01*
G01X527074Y516829D02*
Y510629D01*
G01X536584Y509530D02*
X536429Y509300D01*
X536326Y509032D01*
Y508725D01*
X536481Y508380D01*
X536739Y508112D01*
X537049Y507920D01*
X537566Y507767D01*
X538031Y507729D01*
X538496Y507805D01*
X538806Y507920D01*
X539116Y508150D01*
X539323Y508419D01*
X539426Y508687D01*
Y508955D01*
X539323Y509224D01*
X539168Y509454D01*
X538961Y509645D01*
G01X539426Y511787D02*
X536326D01*
X536946Y511327D01*
G01X539426D02*
Y512247D01*
G01X539064Y514235D02*
X539323Y514504D01*
X539426Y514810D01*
X539323Y515117D01*
X539013Y515385D01*
X538548Y515577D01*
X538083Y515654D01*
X537514D01*
X537049Y515577D01*
X536636Y515385D01*
X536429Y515155D01*
X536326Y514887D01*
X536429Y514580D01*
X536636Y514350D01*
X536946Y514197D01*
X537359Y514120D01*
X537721Y514197D01*
X538083Y514389D01*
X538289Y514619D01*
X538341Y514887D01*
X538238Y515194D01*
X537979Y515424D01*
X537514Y515654D01*
G01X536326Y517987D02*
X536429Y517680D01*
X536688Y517450D01*
X536998Y517297D01*
X537411Y517182D01*
X537876Y517144D01*
X538341Y517182D01*
X538754Y517297D01*
X539064Y517450D01*
X539323Y517680D01*
X539426Y517987D01*
X539323Y518294D01*
X539064Y518524D01*
X538754Y518677D01*
X538341Y518792D01*
X537876Y518830D01*
X537411Y518792D01*
X536998Y518677D01*
X536688Y518524D01*
X536429Y518294D01*
X536326Y517987D01*
G01X531074Y510629D02*
X527874D01*
G01X531074Y516829D02*
Y510629D01*
G01X527874Y516829D02*
X531074D01*
G01X527874Y510629D02*
Y516829D01*
G01X530974Y513729D02*
X527974D01*
G01X528115Y524425D02*
Y522203D01*
X528268Y521738D01*
X528575Y521428D01*
X528958Y521325D01*
X529341Y521428D01*
X529648Y521738D01*
X529801Y522203D01*
Y524425D01*
G01X532058Y521325D02*
Y524425D01*
X531598Y523805D01*
G01Y521325D02*
X532518D01*
G01X534430Y523908D02*
X534660Y524218D01*
X534928Y524373D01*
X535235Y524425D01*
X535618Y524322D01*
X535886Y524063D01*
X535963Y523753D01*
X535925Y523443D01*
X535771Y523185D01*
X535005Y522668D01*
X534660Y522307D01*
X534430Y521790D01*
X534353Y521325D01*
X535963D01*
G01X537415Y521790D02*
X537645Y521532D01*
X537913Y521377D01*
X538258Y521325D01*
X538603Y521428D01*
X538871Y521635D01*
X539063Y521997D01*
X539101Y522410D01*
X539025Y522823D01*
X538833Y523082D01*
X538565Y523288D01*
X538296Y523340D01*
X538028Y523288D01*
X537683Y523082D01*
X537798Y524425D01*
X538833D01*
G01X528238Y612725D02*
Y606525D01*
G01X544038Y606325D02*
X540838D01*
G01D02*
Y612525D01*
G01X536238Y606425D02*
X533038D01*
G01X536238Y612625D02*
Y606425D01*
G01X533038D02*
Y612625D01*
G01X529138Y606425D02*
Y612625D01*
G01X532338D02*
Y606425D01*
G01D02*
X529138D01*
G01X537668Y627801D02*
X534468D01*
G01X537668Y634001D02*
Y627801D01*
G01X534468D02*
Y634001D01*
G01X534106Y622627D02*
Y625827D01*
G01X540306Y622627D02*
X534106D01*
G01X540306Y625827D02*
Y622627D01*
G01X534106Y625827D02*
X540306D01*
G01X540838Y612525D02*
X544038D01*
G01X534106Y618627D02*
Y621827D01*
G01X540306Y618627D02*
X534106D01*
G01X540306Y621827D02*
Y618627D01*
G01X534106Y621827D02*
X540306D01*
G01X541800Y627781D02*
Y633981D01*
G01X545000Y627781D02*
X541800D01*
G01X533038Y612625D02*
X536238D01*
G01X529138D02*
X532338D01*
G01X529142Y614074D02*
X529355Y613866D01*
X529595Y613741D01*
X529809D01*
X530022Y613866D01*
X530182Y614074D01*
X530262Y614366D01*
X530209Y614658D01*
X530075Y614908D01*
X529835Y615074D01*
X529515Y615158D01*
X529329Y615324D01*
X529249Y615616D01*
X529302Y615908D01*
X529435Y616116D01*
X529622Y616241D01*
X529809D01*
X529995Y616158D01*
X530155Y615949D01*
G01X532778Y632695D02*
Y617695D01*
G01X533770Y635130D02*
Y637120D01*
G01X558370Y635130D02*
X533770D01*
G01X535540Y634873D02*
Y639256D01*
G01X537568Y630901D02*
X534568D01*
G01X534468Y634001D02*
X537668D01*
G01X541800Y633981D02*
X545000D01*
G01X526694Y633820D02*
Y636320D01*
X527228D01*
X527441Y636195D01*
X527601Y636028D01*
X527734Y635778D01*
X527841Y635487D01*
X527868Y635070D01*
X527841Y634653D01*
X527734Y634362D01*
X527601Y634112D01*
X527441Y633945D01*
X527228Y633820D01*
X526694D01*
G01X527640Y708056D02*
Y718856D01*
G01X537340Y708156D02*
Y713156D01*
G01X536012Y715917D02*
X535857Y715687D01*
X535754Y715419D01*
Y715112D01*
X535909Y714767D01*
X536167Y714499D01*
X536477Y714307D01*
X536994Y714154D01*
X537459Y714116D01*
X537924Y714192D01*
X538234Y714307D01*
X538544Y714537D01*
X538751Y714806D01*
X538854Y715074D01*
Y715342D01*
X538751Y715611D01*
X538596Y715841D01*
X538389Y716032D01*
G01X538492Y717522D02*
X538751Y717791D01*
X538854Y718097D01*
X538751Y718404D01*
X538441Y718672D01*
X537976Y718864D01*
X537511Y718941D01*
X536942D01*
X536477Y718864D01*
X536064Y718672D01*
X535857Y718442D01*
X535754Y718174D01*
X535857Y717867D01*
X536064Y717637D01*
X536374Y717484D01*
X536787Y717407D01*
X537149Y717484D01*
X537511Y717676D01*
X537717Y717906D01*
X537769Y718174D01*
X537666Y718481D01*
X537407Y718711D01*
X536942Y718941D01*
G01X535754Y721274D02*
X535857Y720967D01*
X536116Y720737D01*
X536426Y720584D01*
X536839Y720469D01*
X537304Y720431D01*
X537769Y720469D01*
X538182Y720584D01*
X538492Y720737D01*
X538751Y720967D01*
X538854Y721274D01*
X538751Y721581D01*
X538492Y721811D01*
X538182Y721964D01*
X537769Y722079D01*
X537304Y722117D01*
X536839Y722079D01*
X536426Y721964D01*
X536116Y721811D01*
X535857Y721581D01*
X535754Y721274D01*
G01X538234Y723531D02*
X538596Y723761D01*
X538802Y724067D01*
X538854Y724412D01*
X538802Y724719D01*
X538544Y725026D01*
X538234Y725217D01*
X537924Y725256D01*
X537562Y725179D01*
X537304Y724911D01*
X537201Y724642D01*
Y724297D01*
G01Y724642D02*
X537046Y724872D01*
X536787Y725064D01*
X536477Y725141D01*
X536167Y725064D01*
X535909Y724872D01*
X535754Y724527D01*
X535806Y724182D01*
X536012Y723837D01*
G01X539840Y717693D02*
X543040D01*
G01X539840Y711493D02*
Y717693D01*
G01X543040Y711493D02*
X539840D01*
G01X539940Y714593D02*
X542940D01*
G01X529970Y717870D02*
X533170D01*
G01X529970Y711670D02*
Y717870D01*
G01X533170Y711670D02*
X529970D01*
G01X533170Y717870D02*
Y711670D01*
G01X543540Y737556D02*
X540340D01*
G01D02*
Y743756D01*
G01X534540Y726056D02*
X531340D01*
G01X534540Y732256D02*
Y726056D01*
G01X531340Y732256D02*
X534540D01*
G01X531340Y726056D02*
Y732256D01*
G01X534440Y729156D02*
X531440D01*
G01X531540Y737556D02*
X528340D01*
G01D02*
Y743756D01*
G01X531540D02*
Y737556D01*
G01X532840D02*
Y743756D01*
G01X536040Y737556D02*
X532840D01*
G01X536040Y743756D02*
Y737556D01*
G01X540340Y732256D02*
X543540D01*
G01X540340Y726056D02*
Y732256D01*
G01X543540Y726056D02*
X540340D01*
G01X526840Y732256D02*
X530040D01*
G01X526840Y726056D02*
Y732256D01*
G01X530040Y726056D02*
X526840D01*
G01X530040Y732256D02*
Y726056D01*
G01X527040Y743756D02*
Y737556D01*
G01X540340Y743756D02*
X543540D01*
G01X543440Y740656D02*
X540440D01*
G01X531191Y748908D02*
X531036Y748678D01*
X530933Y748410D01*
Y748103D01*
X531088Y747758D01*
X531346Y747490D01*
X531656Y747298D01*
X532173Y747145D01*
X532638Y747107D01*
X533103Y747183D01*
X533413Y747298D01*
X533723Y747528D01*
X533930Y747797D01*
X534033Y748065D01*
Y748333D01*
X533930Y748602D01*
X533775Y748832D01*
X533568Y749023D01*
G01X534033Y751088D02*
X533361Y751165D01*
X532793Y751280D01*
X532276Y751433D01*
X531708Y751625D01*
X530933Y751932D01*
Y750398D01*
G01X534033Y754725D02*
X530933D01*
X533155Y753307D01*
Y755223D01*
G01X533413Y756522D02*
X533775Y756752D01*
X533981Y757058D01*
X534033Y757403D01*
X533981Y757710D01*
X533723Y758017D01*
X533413Y758208D01*
X533103Y758247D01*
X532741Y758170D01*
X532483Y757902D01*
X532380Y757633D01*
Y757288D01*
G01Y757633D02*
X532225Y757863D01*
X531966Y758055D01*
X531656Y758132D01*
X531346Y758055D01*
X531088Y757863D01*
X530933Y757518D01*
X530985Y757173D01*
X531191Y756828D01*
G01X528340Y743756D02*
X531540D01*
G01X531440Y740656D02*
X528440D01*
G01X532840Y743756D02*
X536040D01*
G01X541467Y748311D02*
X538367D01*
Y749270D01*
X538522Y749576D01*
X538729Y749768D01*
X539142Y749845D01*
X539555Y749768D01*
X539814Y749538D01*
X539969Y749270D01*
Y748311D01*
G01Y749270D02*
X541467Y749845D01*
G01Y752178D02*
X541415Y752446D01*
X541260Y752753D01*
X541002Y752945D01*
X540640Y753021D01*
X540279Y752945D01*
X539969Y752715D01*
X539814Y752370D01*
Y751986D01*
X539710Y751756D01*
X539452Y751565D01*
X539090Y751488D01*
X538729Y751603D01*
X538470Y751871D01*
X538367Y752178D01*
X538470Y752485D01*
X538729Y752753D01*
X539090Y752868D01*
X539452Y752791D01*
X539710Y752600D01*
X539814Y752370D01*
Y751986D01*
X539969Y751641D01*
X540279Y751411D01*
X540640Y751335D01*
X541002Y751411D01*
X541260Y751603D01*
X541415Y751910D01*
X541467Y752178D01*
G01Y755278D02*
X541415Y755546D01*
X541260Y755853D01*
X541002Y756045D01*
X540640Y756121D01*
X540279Y756045D01*
X539969Y755815D01*
X539814Y755470D01*
Y755086D01*
X539710Y754856D01*
X539452Y754665D01*
X539090Y754588D01*
X538729Y754703D01*
X538470Y754971D01*
X538367Y755278D01*
X538470Y755585D01*
X538729Y755853D01*
X539090Y755968D01*
X539452Y755891D01*
X539710Y755700D01*
X539814Y755470D01*
Y755086D01*
X539969Y754741D01*
X540279Y754511D01*
X540640Y754435D01*
X541002Y754511D01*
X541260Y754703D01*
X541415Y755010D01*
X541467Y755278D01*
G01X538884Y757650D02*
X538574Y757880D01*
X538419Y758148D01*
X538367Y758455D01*
X538470Y758838D01*
X538729Y759106D01*
X539039Y759183D01*
X539349Y759145D01*
X539607Y758991D01*
X540124Y758225D01*
X540485Y757880D01*
X541002Y757650D01*
X541467Y757573D01*
Y759183D01*
G01X540215Y764380D02*
X540060Y764150D01*
X539957Y763882D01*
Y763575D01*
X540112Y763230D01*
X540370Y762962D01*
X540680Y762770D01*
X541197Y762617D01*
X541662Y762579D01*
X542127Y762655D01*
X542437Y762770D01*
X542747Y763000D01*
X542954Y763269D01*
X543057Y763537D01*
Y763805D01*
X542954Y764074D01*
X542799Y764304D01*
X542592Y764495D01*
G01X541765Y765909D02*
X541404Y766177D01*
X541197Y766407D01*
X541094Y766714D01*
X541197Y766982D01*
X541404Y767174D01*
X541714Y767327D01*
X542075Y767365D01*
X542385Y767327D01*
X542695Y767174D01*
X542954Y766944D01*
X543057Y766675D01*
X542954Y766369D01*
X542644Y766100D01*
X542179Y765947D01*
X541662Y765909D01*
X540990Y765985D01*
X540629Y766100D01*
X540267Y766292D01*
X540009Y766560D01*
X539957Y766829D01*
X540060Y767097D01*
X540319Y767289D01*
G01X543057Y770197D02*
X539957D01*
X542179Y768779D01*
Y770695D01*
G01X542592Y771994D02*
X542850Y772224D01*
X543005Y772492D01*
X543057Y772837D01*
X542954Y773182D01*
X542747Y773450D01*
X542385Y773642D01*
X541972Y773680D01*
X541559Y773604D01*
X541300Y773412D01*
X541094Y773144D01*
X541042Y772875D01*
X541094Y772607D01*
X541300Y772262D01*
X539957Y772377D01*
Y773412D01*
G01X530573Y760525D02*
X527473D01*
Y761484D01*
X527628Y761790D01*
X527835Y761982D01*
X528248Y762059D01*
X528661Y761982D01*
X528920Y761752D01*
X529075Y761484D01*
Y760525D01*
G01Y761484D02*
X530573Y762059D01*
G01X530211Y763740D02*
X530470Y764009D01*
X530573Y764315D01*
X530470Y764622D01*
X530160Y764890D01*
X529695Y765082D01*
X529230Y765159D01*
X528661D01*
X528196Y765082D01*
X527783Y764890D01*
X527576Y764660D01*
X527473Y764392D01*
X527576Y764085D01*
X527783Y763855D01*
X528093Y763702D01*
X528506Y763625D01*
X528868Y763702D01*
X529230Y763894D01*
X529436Y764124D01*
X529488Y764392D01*
X529385Y764699D01*
X529126Y764929D01*
X528661Y765159D01*
G01X530573Y767492D02*
X530521Y767760D01*
X530366Y768067D01*
X530108Y768259D01*
X529746Y768335D01*
X529385Y768259D01*
X529075Y768029D01*
X528920Y767684D01*
Y767300D01*
X528816Y767070D01*
X528558Y766879D01*
X528196Y766802D01*
X527835Y766917D01*
X527576Y767185D01*
X527473Y767492D01*
X527576Y767799D01*
X527835Y768067D01*
X528196Y768182D01*
X528558Y768105D01*
X528816Y767914D01*
X528920Y767684D01*
Y767300D01*
X529075Y766955D01*
X529385Y766725D01*
X529746Y766649D01*
X530108Y766725D01*
X530366Y766917D01*
X530521Y767224D01*
X530573Y767492D01*
G01X527473Y770592D02*
X527576Y770285D01*
X527835Y770055D01*
X528145Y769902D01*
X528558Y769787D01*
X529023Y769749D01*
X529488Y769787D01*
X529901Y769902D01*
X530211Y770055D01*
X530470Y770285D01*
X530573Y770592D01*
X530470Y770899D01*
X530211Y771129D01*
X529901Y771282D01*
X529488Y771397D01*
X529023Y771435D01*
X528558Y771397D01*
X528145Y771282D01*
X527835Y771129D01*
X527576Y770899D01*
X527473Y770592D01*
G01X557460Y59070D02*
X558350D01*
G01X557460Y69870D02*
Y59070D01*
G01X557420Y69870D02*
X557460D01*
G01X543179Y68132D02*
Y70632D01*
X542859Y70132D01*
G01Y68132D02*
X543499D01*
G01X554252Y70277D02*
X554412Y70527D01*
X554599Y70652D01*
X554812Y70694D01*
X555079Y70611D01*
X555266Y70402D01*
X555319Y70152D01*
X555292Y69902D01*
X555186Y69694D01*
X554652Y69277D01*
X554412Y68986D01*
X554252Y68569D01*
X554199Y68194D01*
X555319D01*
G01X557580Y109710D02*
Y107150D01*
G01X548848Y104686D02*
Y98486D01*
G01D02*
X545648D01*
G01D02*
Y104686D01*
G01D02*
X548848D01*
G01X545748Y101586D02*
X548748D01*
G01X554338Y104723D02*
X557538D01*
G01X557438Y101623D02*
X554438D01*
G01X554338Y98523D02*
Y104723D01*
G01X557538D02*
Y98523D01*
G01D02*
X554338D01*
G01X544548Y105186D02*
Y94986D01*
G01X549854Y104723D02*
X553054D01*
G01D02*
Y98523D01*
G01D02*
X549854D01*
G01D02*
Y104723D01*
G01X563950Y109710D02*
X557580D01*
G01X550005Y114225D02*
Y111225D01*
G01X546205Y190025D02*
Y196025D01*
G01X556005Y190025D02*
Y193025D01*
G01X552309Y199564D02*
Y205764D01*
G01X555509D02*
Y199564D01*
G01D02*
X552309D01*
G01X548309D02*
Y205764D01*
G01X551509D02*
Y199564D01*
G01D02*
X548309D01*
G01X556309D02*
Y205764D01*
G01X559509Y199564D02*
X556309D01*
G01X542900Y199400D02*
Y205600D01*
X546100D01*
Y199400D01*
X542900D01*
G01X543080Y206680D02*
X544830D01*
G01X548090D02*
X548320D01*
G01X551570D02*
X552330D01*
G01X555190D02*
X567442D01*
Y211708D01*
X584409D01*
Y221109D01*
X576888D01*
Y229440D01*
X584180D01*
G01X552309Y205764D02*
X555509D01*
G01X548309D02*
X551509D01*
G01X556309D02*
X559509D01*
G01X546335Y213232D02*
Y210032D01*
G01X555440Y232323D02*
Y234823D01*
X555120Y234323D01*
G01Y232323D02*
X555760D01*
G01X544807Y236593D02*
Y233393D01*
G01X553259Y226217D02*
Y229317D01*
X554218D01*
X554524Y229162D01*
X554716Y228955D01*
X554793Y228542D01*
X554716Y228129D01*
X554486Y227870D01*
X554218Y227715D01*
X553259D01*
G01X554218D02*
X554793Y226217D01*
G01X557126D02*
X557394Y226269D01*
X557701Y226424D01*
X557893Y226682D01*
X557969Y227044D01*
X557893Y227405D01*
X557663Y227715D01*
X557318Y227870D01*
X556934D01*
X556704Y227974D01*
X556513Y228232D01*
X556436Y228594D01*
X556551Y228955D01*
X556819Y229214D01*
X557126Y229317D01*
X557433Y229214D01*
X557701Y228955D01*
X557816Y228594D01*
X557739Y228232D01*
X557548Y227974D01*
X557318Y227870D01*
X556934D01*
X556589Y227715D01*
X556359Y227405D01*
X556283Y227044D01*
X556359Y226682D01*
X556551Y226424D01*
X556858Y226269D01*
X557126Y226217D01*
G01X560226Y229317D02*
X559919Y229214D01*
X559689Y228955D01*
X559536Y228645D01*
X559421Y228232D01*
X559383Y227767D01*
X559421Y227302D01*
X559536Y226889D01*
X559689Y226579D01*
X559919Y226320D01*
X560226Y226217D01*
X560533Y226320D01*
X560763Y226579D01*
X560916Y226889D01*
X561031Y227302D01*
X561069Y227767D01*
X561031Y228232D01*
X560916Y228645D01*
X560763Y228955D01*
X560533Y229214D01*
X560226Y229317D01*
G01X563786Y226217D02*
Y229317D01*
X562368Y227095D01*
X564284D01*
G01X567238Y219133D02*
X552238D01*
G01Y225933D02*
X567238D01*
G01X552238Y219133D02*
Y225933D01*
G01X549934Y235551D02*
X549987Y236093D01*
X550067Y236551D01*
X550174Y236968D01*
X550307Y237426D01*
X550520Y238051D01*
X549454D01*
G01X551680Y236593D02*
X551867Y236884D01*
X552027Y237051D01*
X552240Y237134D01*
X552427Y237051D01*
X552560Y236884D01*
X552667Y236634D01*
X552694Y236343D01*
X552667Y236093D01*
X552560Y235843D01*
X552400Y235634D01*
X552214Y235551D01*
X552000Y235634D01*
X551814Y235884D01*
X551707Y236259D01*
X551680Y236676D01*
X551734Y237218D01*
X551814Y237509D01*
X551947Y237801D01*
X552134Y238009D01*
X552320Y238051D01*
X552507Y237968D01*
X552640Y237759D01*
G01X546757Y248721D02*
X550757D01*
G01X548668Y240810D02*
X550668D01*
G01X553664Y238355D02*
Y235661D01*
G01D02*
X556357D01*
G01X544807Y240593D02*
Y237393D01*
G01Y248593D02*
Y245393D01*
G01Y244593D02*
Y241393D01*
G01X546731Y264414D02*
X550731D01*
G01X548798Y256450D02*
X550798D01*
G01X543772Y256162D02*
Y251562D01*
G01X546595Y260743D02*
X546825Y260381D01*
X547131Y260175D01*
X547476Y260123D01*
X547783Y260175D01*
X548090Y260433D01*
X548281Y260743D01*
X548320Y261053D01*
X548243Y261415D01*
X547975Y261673D01*
X547706Y261776D01*
X547361D01*
G01X547706D02*
X547936Y261931D01*
X548128Y262190D01*
X548205Y262500D01*
X548128Y262810D01*
X547936Y263068D01*
X547591Y263223D01*
X547246Y263171D01*
X546901Y262965D01*
G01X545355Y254895D02*
X545045Y255125D01*
X544890Y255393D01*
X544838Y255700D01*
X544941Y256083D01*
X545200Y256351D01*
X545510Y256428D01*
X545820Y256390D01*
X546078Y256236D01*
X546595Y255470D01*
X546956Y255125D01*
X547473Y254895D01*
X547938Y254818D01*
Y256428D01*
G01X545531Y269268D02*
Y257456D01*
G01X549339Y268803D02*
X549499Y268595D01*
X549686Y268470D01*
X549926Y268428D01*
X550166Y268511D01*
X550353Y268678D01*
X550486Y268970D01*
X550513Y269303D01*
X550459Y269636D01*
X550326Y269845D01*
X550139Y270011D01*
X549953Y270053D01*
X549766Y270011D01*
X549526Y269845D01*
X549606Y270928D01*
X550326D01*
G01X552126Y268428D02*
X552313Y268470D01*
X552526Y268595D01*
X552659Y268803D01*
X552713Y269095D01*
X552659Y269386D01*
X552499Y269636D01*
X552259Y269761D01*
X551993D01*
X551833Y269845D01*
X551699Y270053D01*
X551646Y270345D01*
X551726Y270636D01*
X551913Y270845D01*
X552126Y270928D01*
X552339Y270845D01*
X552526Y270636D01*
X552606Y270345D01*
X552553Y270053D01*
X552419Y269845D01*
X552259Y269761D01*
X551993D01*
X551753Y269636D01*
X551593Y269386D01*
X551539Y269095D01*
X551593Y268803D01*
X551726Y268595D01*
X551939Y268470D01*
X552126Y268428D01*
G01X552858Y272249D02*
X553018Y272041D01*
X553205Y271916D01*
X553445Y271874D01*
X553685Y271957D01*
X553872Y272124D01*
X554005Y272416D01*
X554032Y272749D01*
X553978Y273082D01*
X553845Y273291D01*
X553658Y273457D01*
X553472Y273499D01*
X553285Y273457D01*
X553045Y273291D01*
X553125Y274374D01*
X553845D01*
G01X555592Y271874D02*
X555645Y272416D01*
X555725Y272874D01*
X555832Y273291D01*
X555965Y273749D01*
X556178Y274374D01*
X555112D01*
G01X556357Y271095D02*
X553664D01*
G01D02*
Y268401D01*
G01X553376Y282728D02*
Y278328D01*
G01X553976Y282728D02*
Y278328D01*
G01X554576D02*
Y282728D01*
G01X555176D02*
Y278328D01*
G01D02*
X553376D01*
G01D02*
X542976D01*
G01D02*
Y282728D01*
G01X549872Y275862D02*
Y272662D01*
G01D02*
X543672D01*
G01D02*
Y275862D01*
G01D02*
X549872D01*
G01X542625Y283843D02*
Y286943D01*
X543391D01*
X543698Y286788D01*
X543928Y286581D01*
X544120Y286271D01*
X544273Y285910D01*
X544311Y285393D01*
X544273Y284876D01*
X544120Y284515D01*
X543928Y284205D01*
X543698Y283998D01*
X543391Y283843D01*
X542625D01*
G01X545725Y284308D02*
X545955Y284050D01*
X546223Y283895D01*
X546568Y283843D01*
X546913Y283946D01*
X547181Y284153D01*
X547373Y284515D01*
X547411Y284928D01*
X547335Y285341D01*
X547143Y285600D01*
X546875Y285806D01*
X546606Y285858D01*
X546338Y285806D01*
X545993Y285600D01*
X546108Y286943D01*
X547143D01*
G01X555176Y282728D02*
X553376D01*
G01X542976D02*
X553376D01*
G01X552070Y290924D02*
X545870D01*
G01D02*
Y294124D01*
G01D02*
X552070D01*
G01D02*
Y290924D01*
G01X551770Y295224D02*
X545570D01*
G01D02*
Y298424D01*
G01X551770D02*
Y295224D01*
G01X553403Y384240D02*
X561628D01*
Y312202D01*
X552963D01*
Y384240D01*
X553403D01*
G01X552750Y307479D02*
Y310579D01*
X553709D01*
X554015Y310424D01*
X554207Y310217D01*
X554284Y309804D01*
X554207Y309391D01*
X553977Y309132D01*
X553709Y308977D01*
X552750D01*
G01X553709D02*
X554284Y307479D01*
G01X555774Y307944D02*
X556004Y307686D01*
X556272Y307531D01*
X556617Y307479D01*
X556962Y307582D01*
X557230Y307789D01*
X557422Y308151D01*
X557460Y308564D01*
X557384Y308977D01*
X557192Y309236D01*
X556924Y309442D01*
X556655Y309494D01*
X556387Y309442D01*
X556042Y309236D01*
X556157Y310579D01*
X557192D01*
G01X559717D02*
X559410Y310476D01*
X559180Y310217D01*
X559027Y309907D01*
X558912Y309494D01*
X558874Y309029D01*
X558912Y308564D01*
X559027Y308151D01*
X559180Y307841D01*
X559410Y307582D01*
X559717Y307479D01*
X560024Y307582D01*
X560254Y307841D01*
X560407Y308151D01*
X560522Y308564D01*
X560560Y309029D01*
X560522Y309494D01*
X560407Y309907D01*
X560254Y310217D01*
X560024Y310476D01*
X559717Y310579D01*
G01X562089Y308771D02*
X562357Y309132D01*
X562587Y309339D01*
X562894Y309442D01*
X563162Y309339D01*
X563354Y309132D01*
X563507Y308822D01*
X563545Y308461D01*
X563507Y308151D01*
X563354Y307841D01*
X563124Y307582D01*
X562855Y307479D01*
X562549Y307582D01*
X562280Y307892D01*
X562127Y308357D01*
X562089Y308874D01*
X562165Y309546D01*
X562280Y309907D01*
X562472Y310269D01*
X562740Y310527D01*
X563009Y310579D01*
X563277Y310476D01*
X563469Y310217D01*
G01X551770Y299524D02*
X545570D01*
G01D02*
Y302724D01*
G01D02*
X551770D01*
G01D02*
Y299524D01*
G01X552803Y299560D02*
Y302660D01*
X553762D01*
X554068Y302505D01*
X554260Y302298D01*
X554337Y301885D01*
X554260Y301472D01*
X554030Y301213D01*
X553762Y301058D01*
X552803D01*
G01X553762D02*
X554337Y299560D01*
G01X555827Y300025D02*
X556057Y299767D01*
X556325Y299612D01*
X556670Y299560D01*
X557015Y299663D01*
X557283Y299870D01*
X557475Y300232D01*
X557513Y300645D01*
X557437Y301058D01*
X557245Y301317D01*
X556977Y301523D01*
X556708Y301575D01*
X556440Y301523D01*
X556095Y301317D01*
X556210Y302660D01*
X557245D01*
G01X559770D02*
X559463Y302557D01*
X559233Y302298D01*
X559080Y301988D01*
X558965Y301575D01*
X558927Y301110D01*
X558965Y300645D01*
X559080Y300232D01*
X559233Y299922D01*
X559463Y299663D01*
X559770Y299560D01*
X560077Y299663D01*
X560307Y299922D01*
X560460Y300232D01*
X560575Y300645D01*
X560613Y301110D01*
X560575Y301575D01*
X560460Y301988D01*
X560307Y302298D01*
X560077Y302557D01*
X559770Y302660D01*
G01X562870Y299560D02*
X563138Y299612D01*
X563445Y299767D01*
X563637Y300025D01*
X563713Y300387D01*
X563637Y300748D01*
X563407Y301058D01*
X563062Y301213D01*
X562678D01*
X562448Y301317D01*
X562257Y301575D01*
X562180Y301937D01*
X562295Y302298D01*
X562563Y302557D01*
X562870Y302660D01*
X563177Y302557D01*
X563445Y302298D01*
X563560Y301937D01*
X563483Y301575D01*
X563292Y301317D01*
X563062Y301213D01*
X562678D01*
X562333Y301058D01*
X562103Y300748D01*
X562027Y300387D01*
X562103Y300025D01*
X562295Y299767D01*
X562602Y299612D01*
X562870Y299560D01*
G01X552786Y303541D02*
Y306641D01*
X553745D01*
X554051Y306486D01*
X554243Y306279D01*
X554320Y305866D01*
X554243Y305453D01*
X554013Y305194D01*
X553745Y305039D01*
X552786D01*
G01X553745D02*
X554320Y303541D01*
G01X555810Y304006D02*
X556040Y303748D01*
X556308Y303593D01*
X556653Y303541D01*
X556998Y303644D01*
X557266Y303851D01*
X557458Y304213D01*
X557496Y304626D01*
X557420Y305039D01*
X557228Y305298D01*
X556960Y305504D01*
X556691Y305556D01*
X556423Y305504D01*
X556078Y305298D01*
X556193Y306641D01*
X557228D01*
G01X559753D02*
X559446Y306538D01*
X559216Y306279D01*
X559063Y305969D01*
X558948Y305556D01*
X558910Y305091D01*
X558948Y304626D01*
X559063Y304213D01*
X559216Y303903D01*
X559446Y303644D01*
X559753Y303541D01*
X560060Y303644D01*
X560290Y303903D01*
X560443Y304213D01*
X560558Y304626D01*
X560596Y305091D01*
X560558Y305556D01*
X560443Y305969D01*
X560290Y306279D01*
X560060Y306538D01*
X559753Y306641D01*
G01X562776Y303541D02*
X562853Y304213D01*
X562968Y304781D01*
X563121Y305298D01*
X563313Y305866D01*
X563620Y306641D01*
X562086D01*
G01X545570Y298424D02*
X551770D01*
G01X557471Y315754D02*
X557221Y316007D01*
X556805Y316197D01*
X556221Y316324D01*
X555721Y316197D01*
X555388Y315944D01*
X555138Y315500D01*
Y313790D01*
X560138D01*
Y315880D01*
X559805Y316324D01*
X559305Y316577D01*
X558721Y316704D01*
X558138Y316577D01*
X557638Y316197D01*
X557471Y315754D01*
Y313790D01*
G01X560138Y318764D02*
X555138Y320347D01*
X560138Y321930D01*
G01X558388Y321360D02*
Y319334D01*
G01X555138Y325447D02*
X560138D01*
G01X555138Y323990D02*
Y326904D01*
G01Y330547D02*
X560138D01*
G01X555138Y329090D02*
Y332004D01*
G01X560138Y336914D02*
Y334380D01*
X555138D01*
Y336914D01*
G01X557555Y335900D02*
Y334380D01*
G01X560138Y339480D02*
X555138D01*
Y341064D01*
X555388Y341570D01*
X555721Y341887D01*
X556388Y342014D01*
X557055Y341887D01*
X557471Y341507D01*
X557721Y341064D01*
Y339480D01*
G01Y341064D02*
X560138Y342014D01*
G01Y345847D02*
X557888D01*
X555138Y344580D01*
G01Y347114D02*
X557888Y345847D01*
G01X559471Y354717D02*
X559888Y355224D01*
X560138Y355794D01*
Y356300D01*
X559888Y356807D01*
X559471Y357187D01*
X558888Y357377D01*
X558305Y357250D01*
X557805Y356934D01*
X557471Y356364D01*
X557305Y355604D01*
X556971Y355160D01*
X556388Y354970D01*
X555805Y355097D01*
X555388Y355414D01*
X555138Y355857D01*
Y356300D01*
X555305Y356744D01*
X555721Y357124D01*
G01X560138Y361147D02*
X560055Y360640D01*
X559721Y360197D01*
X559221Y359817D01*
X558638Y359564D01*
X557971Y359437D01*
X557305D01*
X556638Y359564D01*
X556055Y359817D01*
X555555Y360197D01*
X555221Y360640D01*
X555138Y361147D01*
X555221Y361654D01*
X555555Y362097D01*
X556055Y362477D01*
X556638Y362730D01*
X557305Y362857D01*
X557971D01*
X558638Y362730D01*
X559221Y362477D01*
X559721Y362097D01*
X560055Y361654D01*
X560138Y361147D01*
G01X555555Y367640D02*
X555305Y367260D01*
X555138Y366817D01*
Y366310D01*
X555388Y365740D01*
X555805Y365297D01*
X556305Y364980D01*
X557138Y364727D01*
X557888Y364664D01*
X558638Y364790D01*
X559138Y364980D01*
X559638Y365360D01*
X559971Y365804D01*
X560138Y366247D01*
Y366690D01*
X559971Y367134D01*
X559721Y367514D01*
X559388Y367830D01*
G01X560138Y369954D02*
X555138D01*
G01Y372360D02*
X558221Y369954D01*
G01X560138Y372740D02*
X556805Y371030D01*
G01X560138Y377714D02*
Y375180D01*
X555138D01*
Y377714D01*
G01X557555Y376700D02*
Y375180D01*
G01X555138Y381547D02*
X560138D01*
G01X555138Y380090D02*
Y383004D01*
G01X550655Y359702D02*
X543972D01*
Y359723D01*
X546165Y361916D01*
X546186Y361895D01*
Y357067D01*
X543951Y359302D01*
Y359639D01*
G01X549173Y401113D02*
X546073D01*
Y402072D01*
X546228Y402378D01*
X546435Y402570D01*
X546848Y402647D01*
X547261Y402570D01*
X547520Y402340D01*
X547675Y402072D01*
Y401113D01*
G01Y402072D02*
X549173Y402647D01*
G01X546590Y404252D02*
X546280Y404482D01*
X546125Y404750D01*
X546073Y405057D01*
X546176Y405440D01*
X546435Y405708D01*
X546745Y405785D01*
X547055Y405747D01*
X547313Y405593D01*
X547830Y404827D01*
X548191Y404482D01*
X548708Y404252D01*
X549173Y404175D01*
Y405785D01*
G01X546590Y407352D02*
X546280Y407582D01*
X546125Y407850D01*
X546073Y408157D01*
X546176Y408540D01*
X546435Y408808D01*
X546745Y408885D01*
X547055Y408847D01*
X547313Y408693D01*
X547830Y407927D01*
X548191Y407582D01*
X548708Y407352D01*
X549173Y407275D01*
Y408885D01*
G01X553398Y401113D02*
X550298D01*
Y402072D01*
X550453Y402378D01*
X550660Y402570D01*
X551073Y402647D01*
X551486Y402570D01*
X551745Y402340D01*
X551900Y402072D01*
Y401113D01*
G01Y402072D02*
X553398Y402647D01*
G01Y404980D02*
X550298D01*
X550918Y404520D01*
G01X553398D02*
Y405440D01*
G01X550298Y408080D02*
X550401Y407773D01*
X550660Y407543D01*
X550970Y407390D01*
X551383Y407275D01*
X551848Y407237D01*
X552313Y407275D01*
X552726Y407390D01*
X553036Y407543D01*
X553295Y407773D01*
X553398Y408080D01*
X553295Y408387D01*
X553036Y408617D01*
X552726Y408770D01*
X552313Y408885D01*
X551848Y408923D01*
X551383Y408885D01*
X550970Y408770D01*
X550660Y408617D01*
X550401Y408387D01*
X550298Y408080D01*
G01X546184Y413563D02*
X543084D01*
Y414522D01*
X543239Y414828D01*
X543446Y415020D01*
X543859Y415097D01*
X544272Y415020D01*
X544531Y414790D01*
X544686Y414522D01*
Y413563D01*
G01Y414522D02*
X546184Y415097D01*
G01X543601Y416702D02*
X543291Y416932D01*
X543136Y417200D01*
X543084Y417507D01*
X543187Y417890D01*
X543446Y418158D01*
X543756Y418235D01*
X544066Y418197D01*
X544324Y418043D01*
X544841Y417277D01*
X545202Y416932D01*
X545719Y416702D01*
X546184Y416625D01*
Y418235D01*
G01X544892Y419802D02*
X544531Y420070D01*
X544324Y420300D01*
X544221Y420607D01*
X544324Y420875D01*
X544531Y421067D01*
X544841Y421220D01*
X545202Y421258D01*
X545512Y421220D01*
X545822Y421067D01*
X546081Y420837D01*
X546184Y420568D01*
X546081Y420262D01*
X545771Y419993D01*
X545306Y419840D01*
X544789Y419802D01*
X544117Y419878D01*
X543756Y419993D01*
X543394Y420185D01*
X543136Y420453D01*
X543084Y420722D01*
X543187Y420990D01*
X543446Y421182D01*
G01X547540Y423556D02*
X544340D01*
G01Y429756D02*
X547540D01*
G01X544340Y423556D02*
Y429756D01*
G01X547540D02*
Y423556D01*
G01X542540Y429756D02*
Y423556D01*
G01X543040Y439256D02*
Y433056D01*
G01X551540Y423556D02*
X548340D01*
G01X551540Y429756D02*
Y423556D01*
G01X548340Y429756D02*
X551540D01*
G01X548340Y423556D02*
Y429756D01*
G01X549165Y437407D02*
Y440607D01*
G01X555365Y437407D02*
X549165D01*
G01X555365Y440607D02*
Y437407D01*
G01X556740Y453427D02*
Y447227D01*
G01X553540Y453427D02*
X556740D01*
G01X553540Y447227D02*
Y453427D01*
G01X556740Y447227D02*
X553540D01*
G01X549340Y454556D02*
Y457756D01*
G01X555540Y454556D02*
X549340D01*
G01X555540Y457756D02*
Y454556D01*
G01X549540Y453427D02*
X552740D01*
G01X549540Y447227D02*
Y453427D01*
G01X552740Y447227D02*
X549540D01*
G01X552740Y453427D02*
Y447227D01*
G01X549146Y441448D02*
Y444648D01*
G01X555346Y441448D02*
X549146D01*
G01X555346Y444648D02*
Y441448D01*
G01X549146Y444648D02*
X555346D01*
G01X560740Y447227D02*
X557540D01*
G01Y453427D02*
X560740D01*
G01X557540Y447227D02*
Y453427D01*
G01X549165Y440607D02*
X555365D01*
G01X551340Y470156D02*
Y485156D01*
G01X558040Y470156D02*
X551440D01*
G01X549349Y466613D02*
Y469713D01*
X550308D01*
X550614Y469558D01*
X550806Y469351D01*
X550883Y468938D01*
X550806Y468525D01*
X550576Y468266D01*
X550308Y468111D01*
X549349D01*
G01X550308D02*
X550883Y466613D01*
G01X553216D02*
Y469713D01*
X552756Y469093D01*
G01Y466613D02*
X553676D01*
G01X556316D02*
X556584Y466665D01*
X556891Y466820D01*
X557083Y467078D01*
X557159Y467440D01*
X557083Y467801D01*
X556853Y468111D01*
X556508Y468266D01*
X556124D01*
X555894Y468370D01*
X555703Y468628D01*
X555626Y468990D01*
X555741Y469351D01*
X556009Y469610D01*
X556316Y469713D01*
X556623Y469610D01*
X556891Y469351D01*
X557006Y468990D01*
X556929Y468628D01*
X556738Y468370D01*
X556508Y468266D01*
X556124D01*
X555779Y468111D01*
X555549Y467801D01*
X555473Y467440D01*
X555549Y467078D01*
X555741Y466820D01*
X556048Y466665D01*
X556316Y466613D01*
G01X549440Y462256D02*
X555640D01*
G01D02*
Y459056D01*
G01D02*
X549440D01*
G01D02*
Y462256D01*
G01X549349Y462731D02*
Y465831D01*
X550308D01*
X550614Y465676D01*
X550806Y465469D01*
X550883Y465056D01*
X550806Y464643D01*
X550576Y464384D01*
X550308Y464229D01*
X549349D01*
G01X550308D02*
X550883Y462731D01*
G01X553216D02*
Y465831D01*
X552756Y465211D01*
G01Y462731D02*
X553676D01*
G01X555473Y463196D02*
X555703Y462938D01*
X555971Y462783D01*
X556316Y462731D01*
X556661Y462834D01*
X556929Y463041D01*
X557121Y463403D01*
X557159Y463816D01*
X557083Y464229D01*
X556891Y464488D01*
X556623Y464694D01*
X556354Y464746D01*
X556086Y464694D01*
X555741Y464488D01*
X555856Y465831D01*
X556891D01*
G01X549340Y457756D02*
X555540D01*
G01X552662Y486722D02*
X555762D01*
Y488256D01*
G01Y490589D02*
X552662D01*
X553282Y490129D01*
G01X555762D02*
Y491049D01*
G01X558040Y477156D02*
X551440D01*
G01X558040Y485156D02*
X551440D01*
G01X558040Y478156D02*
X551440D01*
G01X545992Y484603D02*
X545837Y484373D01*
X545734Y484105D01*
Y483798D01*
X545889Y483453D01*
X546147Y483185D01*
X546457Y482993D01*
X546974Y482840D01*
X547439Y482802D01*
X547904Y482878D01*
X548214Y482993D01*
X548524Y483223D01*
X548731Y483492D01*
X548834Y483760D01*
Y484028D01*
X548731Y484297D01*
X548576Y484527D01*
X548369Y484718D01*
G01X547542Y486132D02*
X547181Y486400D01*
X546974Y486630D01*
X546871Y486937D01*
X546974Y487205D01*
X547181Y487397D01*
X547491Y487550D01*
X547852Y487588D01*
X548162Y487550D01*
X548472Y487397D01*
X548731Y487167D01*
X548834Y486898D01*
X548731Y486592D01*
X548421Y486323D01*
X547956Y486170D01*
X547439Y486132D01*
X546767Y486208D01*
X546406Y486323D01*
X546044Y486515D01*
X545786Y486783D01*
X545734Y487052D01*
X545837Y487320D01*
X546096Y487512D01*
G01X549640Y481756D02*
Y471556D01*
G01D02*
X545040D01*
G01D02*
Y481756D01*
G01D02*
X549640D01*
G01Y476656D02*
X545040D01*
G01X550104Y514964D02*
Y518064D01*
X551063D01*
X551369Y517909D01*
X551561Y517702D01*
X551638Y517289D01*
X551561Y516876D01*
X551331Y516617D01*
X551063Y516462D01*
X550104D01*
G01X551063D02*
X551638Y514964D01*
G01X553971D02*
Y518064D01*
X553511Y517444D01*
G01Y514964D02*
X554431D01*
G01X556343Y517547D02*
X556573Y517857D01*
X556841Y518012D01*
X557148Y518064D01*
X557531Y517961D01*
X557799Y517702D01*
X557876Y517392D01*
X557838Y517082D01*
X557684Y516824D01*
X556918Y516307D01*
X556573Y515946D01*
X556343Y515429D01*
X556266Y514964D01*
X557876D01*
G01X559443Y517547D02*
X559673Y517857D01*
X559941Y518012D01*
X560248Y518064D01*
X560631Y517961D01*
X560899Y517702D01*
X560976Y517392D01*
X560938Y517082D01*
X560784Y516824D01*
X560018Y516307D01*
X559673Y515946D01*
X559443Y515429D01*
X559366Y514964D01*
X560976D01*
G01X563271D02*
X563539Y515016D01*
X563846Y515171D01*
X564038Y515429D01*
X564114Y515791D01*
X564038Y516152D01*
X563808Y516462D01*
X563463Y516617D01*
X563079D01*
X562849Y516721D01*
X562658Y516979D01*
X562581Y517341D01*
X562696Y517702D01*
X562964Y517961D01*
X563271Y518064D01*
X563578Y517961D01*
X563846Y517702D01*
X563961Y517341D01*
X563884Y516979D01*
X563693Y516721D01*
X563463Y516617D01*
X563079D01*
X562734Y516462D01*
X562504Y516152D01*
X562428Y515791D01*
X562504Y515429D01*
X562696Y515171D01*
X563003Y515016D01*
X563271Y514964D01*
G01X550104Y518964D02*
Y522064D01*
X551063D01*
X551369Y521909D01*
X551561Y521702D01*
X551638Y521289D01*
X551561Y520876D01*
X551331Y520617D01*
X551063Y520462D01*
X550104D01*
G01X551063D02*
X551638Y518964D01*
G01X553128Y519584D02*
X553358Y519222D01*
X553664Y519016D01*
X554009Y518964D01*
X554316Y519016D01*
X554623Y519274D01*
X554814Y519584D01*
X554853Y519894D01*
X554776Y520256D01*
X554508Y520514D01*
X554239Y520617D01*
X553894D01*
G01X554239D02*
X554469Y520772D01*
X554661Y521031D01*
X554738Y521341D01*
X554661Y521651D01*
X554469Y521909D01*
X554124Y522064D01*
X553779Y522012D01*
X553434Y521806D01*
G01X557071Y522064D02*
X556764Y521961D01*
X556534Y521702D01*
X556381Y521392D01*
X556266Y520979D01*
X556228Y520514D01*
X556266Y520049D01*
X556381Y519636D01*
X556534Y519326D01*
X556764Y519067D01*
X557071Y518964D01*
X557378Y519067D01*
X557608Y519326D01*
X557761Y519636D01*
X557876Y520049D01*
X557914Y520514D01*
X557876Y520979D01*
X557761Y521392D01*
X557608Y521702D01*
X557378Y521961D01*
X557071Y522064D01*
G01X559328Y519429D02*
X559558Y519171D01*
X559826Y519016D01*
X560171Y518964D01*
X560516Y519067D01*
X560784Y519274D01*
X560976Y519636D01*
X561014Y520049D01*
X560938Y520462D01*
X560746Y520721D01*
X560478Y520927D01*
X560209Y520979D01*
X559941Y520927D01*
X559596Y520721D01*
X559711Y522064D01*
X560746D01*
G01X550104Y510714D02*
Y513814D01*
X551063D01*
X551369Y513659D01*
X551561Y513452D01*
X551638Y513039D01*
X551561Y512626D01*
X551331Y512367D01*
X551063Y512212D01*
X550104D01*
G01X551063D02*
X551638Y510714D01*
G01X553243Y513297D02*
X553473Y513607D01*
X553741Y513762D01*
X554048Y513814D01*
X554431Y513711D01*
X554699Y513452D01*
X554776Y513142D01*
X554738Y512832D01*
X554584Y512574D01*
X553818Y512057D01*
X553473Y511696D01*
X553243Y511179D01*
X553166Y510714D01*
X554776D01*
G01X557071D02*
X557339Y510766D01*
X557646Y510921D01*
X557838Y511179D01*
X557914Y511541D01*
X557838Y511902D01*
X557608Y512212D01*
X557263Y512367D01*
X556879D01*
X556649Y512471D01*
X556458Y512729D01*
X556381Y513091D01*
X556496Y513452D01*
X556764Y513711D01*
X557071Y513814D01*
X557378Y513711D01*
X557646Y513452D01*
X557761Y513091D01*
X557684Y512729D01*
X557493Y512471D01*
X557263Y512367D01*
X556879D01*
X556534Y512212D01*
X556304Y511902D01*
X556228Y511541D01*
X556304Y511179D01*
X556496Y510921D01*
X556803Y510766D01*
X557071Y510714D01*
G01X559519Y511076D02*
X559788Y510817D01*
X560094Y510714D01*
X560401Y510817D01*
X560669Y511127D01*
X560861Y511592D01*
X560938Y512057D01*
Y512626D01*
X560861Y513091D01*
X560669Y513504D01*
X560439Y513711D01*
X560171Y513814D01*
X559864Y513711D01*
X559634Y513504D01*
X559481Y513194D01*
X559404Y512781D01*
X559481Y512419D01*
X559673Y512057D01*
X559903Y511851D01*
X560171Y511799D01*
X560478Y511902D01*
X560708Y512161D01*
X560938Y512626D01*
G01X551840Y527809D02*
Y530309D01*
X551520Y529809D01*
G01Y527809D02*
X552160D01*
G01X553533Y529892D02*
X553693Y530142D01*
X553880Y530267D01*
X554093Y530309D01*
X554360Y530226D01*
X554547Y530017D01*
X554600Y529767D01*
X554573Y529517D01*
X554467Y529309D01*
X553933Y528892D01*
X553693Y528601D01*
X553533Y528184D01*
X553480Y527809D01*
X554600D01*
G01X556240D02*
X556427Y527851D01*
X556640Y527976D01*
X556773Y528184D01*
X556827Y528476D01*
X556773Y528767D01*
X556613Y529017D01*
X556373Y529142D01*
X556107D01*
X555947Y529226D01*
X555813Y529434D01*
X555760Y529726D01*
X555840Y530017D01*
X556027Y530226D01*
X556240Y530309D01*
X556453Y530226D01*
X556640Y530017D01*
X556720Y529726D01*
X556667Y529434D01*
X556533Y529226D01*
X556373Y529142D01*
X556107D01*
X555867Y529017D01*
X555707Y528767D01*
X555653Y528476D01*
X555707Y528184D01*
X555840Y527976D01*
X556053Y527851D01*
X556240Y527809D01*
G01X556192Y535490D02*
Y537990D01*
X555872Y537490D01*
G01Y535490D02*
X556512D01*
G01X552540Y592058D02*
Y541636D01*
G01D02*
X549362Y538458D01*
G01X552079Y594246D02*
X552239Y593954D01*
X552453Y593788D01*
X552693Y593746D01*
X552906Y593788D01*
X553119Y593996D01*
X553253Y594246D01*
X553279Y594496D01*
X553226Y594788D01*
X553039Y594996D01*
X552853Y595079D01*
X552613D01*
G01X552853D02*
X553013Y595204D01*
X553146Y595413D01*
X553199Y595663D01*
X553146Y595913D01*
X553013Y596121D01*
X552773Y596246D01*
X552533Y596204D01*
X552293Y596038D01*
G01X554279Y594246D02*
X554439Y593954D01*
X554653Y593788D01*
X554893Y593746D01*
X555106Y593788D01*
X555319Y593996D01*
X555453Y594246D01*
X555479Y594496D01*
X555426Y594788D01*
X555239Y594996D01*
X555053Y595079D01*
X554813D01*
G01X555053D02*
X555213Y595204D01*
X555346Y595413D01*
X555399Y595663D01*
X555346Y595913D01*
X555213Y596121D01*
X554973Y596246D01*
X554733Y596204D01*
X554493Y596038D01*
G01X544038Y612525D02*
Y606325D01*
G01X548538D02*
X545338D01*
G01X548538Y612525D02*
Y606325D01*
G01X545338D02*
Y612525D01*
G01X545893Y634052D02*
Y622362D01*
G01D02*
X560354D01*
G01X550309Y618702D02*
Y615502D01*
G01X544109D02*
Y618702D01*
G01X550309Y615502D02*
X544109D01*
G01Y618702D02*
X550309D01*
G01X545338Y612525D02*
X548538D01*
G01X545000Y633981D02*
Y627781D01*
G01X545340Y634456D02*
Y639456D01*
G01X560354Y634052D02*
X545893D01*
G01X557240Y707956D02*
Y712956D01*
G01X547340Y708056D02*
Y718856D01*
G01X552992Y714700D02*
X552837Y714470D01*
X552734Y714202D01*
Y713895D01*
X552889Y713550D01*
X553147Y713282D01*
X553457Y713090D01*
X553974Y712937D01*
X554439Y712899D01*
X554904Y712975D01*
X555214Y713090D01*
X555524Y713320D01*
X555731Y713589D01*
X555834Y713857D01*
Y714125D01*
X555731Y714394D01*
X555576Y714624D01*
X555369Y714815D01*
G01X555472Y716305D02*
X555731Y716574D01*
X555834Y716880D01*
X555731Y717187D01*
X555421Y717455D01*
X554956Y717647D01*
X554491Y717724D01*
X553922D01*
X553457Y717647D01*
X553044Y717455D01*
X552837Y717225D01*
X552734Y716957D01*
X552837Y716650D01*
X553044Y716420D01*
X553354Y716267D01*
X553767Y716190D01*
X554129Y716267D01*
X554491Y716459D01*
X554697Y716689D01*
X554749Y716957D01*
X554646Y717264D01*
X554387Y717494D01*
X553922Y717724D01*
G01X552734Y720057D02*
X552837Y719750D01*
X553096Y719520D01*
X553406Y719367D01*
X553819Y719252D01*
X554284Y719214D01*
X554749Y719252D01*
X555162Y719367D01*
X555472Y719520D01*
X555731Y719750D01*
X555834Y720057D01*
X555731Y720364D01*
X555472Y720594D01*
X555162Y720747D01*
X554749Y720862D01*
X554284Y720900D01*
X553819Y720862D01*
X553406Y720747D01*
X553096Y720594D01*
X552837Y720364D01*
X552734Y720057D01*
G01X555834Y723157D02*
X552734D01*
X553354Y722697D01*
G01X555834D02*
Y723617D01*
G01X548340Y717693D02*
X551540D01*
G01X548340Y711493D02*
Y717693D01*
G01X551540Y711493D02*
X548340D01*
G01X551540Y717693D02*
Y711493D01*
G01X548440Y714593D02*
X551440D01*
G01X543040Y717693D02*
Y711493D01*
G01X548040Y737556D02*
X544840D01*
G01X548040Y743756D02*
Y737556D01*
G01X544840D02*
Y743756D01*
G01X552540Y737556D02*
X549340D01*
G01X552540Y743756D02*
Y737556D01*
G01X549340D02*
Y743756D01*
G01X557040Y737556D02*
X553840D01*
G01X557040Y743756D02*
Y737556D01*
G01X553840D02*
Y743756D01*
G01X543540D02*
Y737556D01*
G01X544840Y732256D02*
X548040D01*
G01X544840Y726056D02*
Y732256D01*
G01X548040Y726056D02*
X544840D01*
G01X548040Y732256D02*
Y726056D01*
G01X549340Y732256D02*
X552540D01*
G01X549340Y726056D02*
Y732256D01*
G01X552540Y726056D02*
X549340D01*
G01X552540Y732256D02*
Y726056D01*
G01X553840Y732256D02*
X557040D01*
G01X553840Y726056D02*
Y732256D01*
G01X557040Y726056D02*
X553840D01*
G01X557040Y732256D02*
Y726056D01*
G01X543540Y732256D02*
Y726056D01*
G01X544840Y743756D02*
X548040D01*
G01X547940Y740656D02*
X544940D01*
G01X549340Y743756D02*
X552540D01*
G01X552440Y740656D02*
X549440D01*
G01X553840Y743756D02*
X557040D01*
G01X556940Y740656D02*
X553940D01*
G01X545967Y748311D02*
X542867D01*
Y749270D01*
X543022Y749576D01*
X543229Y749768D01*
X543642Y749845D01*
X544055Y749768D01*
X544314Y749538D01*
X544469Y749270D01*
Y748311D01*
G01Y749270D02*
X545967Y749845D01*
G01Y752178D02*
X545915Y752446D01*
X545760Y752753D01*
X545502Y752945D01*
X545140Y753021D01*
X544779Y752945D01*
X544469Y752715D01*
X544314Y752370D01*
Y751986D01*
X544210Y751756D01*
X543952Y751565D01*
X543590Y751488D01*
X543229Y751603D01*
X542970Y751871D01*
X542867Y752178D01*
X542970Y752485D01*
X543229Y752753D01*
X543590Y752868D01*
X543952Y752791D01*
X544210Y752600D01*
X544314Y752370D01*
Y751986D01*
X544469Y751641D01*
X544779Y751411D01*
X545140Y751335D01*
X545502Y751411D01*
X545760Y751603D01*
X545915Y751910D01*
X545967Y752178D01*
G01Y755201D02*
X545295Y755278D01*
X544727Y755393D01*
X544210Y755546D01*
X543642Y755738D01*
X542867Y756045D01*
Y754511D01*
G01X545605Y757726D02*
X545864Y757995D01*
X545967Y758301D01*
X545864Y758608D01*
X545554Y758876D01*
X545089Y759068D01*
X544624Y759145D01*
X544055D01*
X543590Y759068D01*
X543177Y758876D01*
X542970Y758646D01*
X542867Y758378D01*
X542970Y758071D01*
X543177Y757841D01*
X543487Y757688D01*
X543900Y757611D01*
X544262Y757688D01*
X544624Y757880D01*
X544830Y758110D01*
X544882Y758378D01*
X544779Y758685D01*
X544520Y758915D01*
X544055Y759145D01*
G01X550467Y748311D02*
X547367D01*
Y749270D01*
X547522Y749576D01*
X547729Y749768D01*
X548142Y749845D01*
X548555Y749768D01*
X548814Y749538D01*
X548969Y749270D01*
Y748311D01*
G01Y749270D02*
X550467Y749845D01*
G01Y752178D02*
X550415Y752446D01*
X550260Y752753D01*
X550002Y752945D01*
X549640Y753021D01*
X549279Y752945D01*
X548969Y752715D01*
X548814Y752370D01*
Y751986D01*
X548710Y751756D01*
X548452Y751565D01*
X548090Y751488D01*
X547729Y751603D01*
X547470Y751871D01*
X547367Y752178D01*
X547470Y752485D01*
X547729Y752753D01*
X548090Y752868D01*
X548452Y752791D01*
X548710Y752600D01*
X548814Y752370D01*
Y751986D01*
X548969Y751641D01*
X549279Y751411D01*
X549640Y751335D01*
X550002Y751411D01*
X550260Y751603D01*
X550415Y751910D01*
X550467Y752178D01*
G01Y755201D02*
X549795Y755278D01*
X549227Y755393D01*
X548710Y755546D01*
X548142Y755738D01*
X547367Y756045D01*
Y754511D01*
G01X549175Y757650D02*
X548814Y757918D01*
X548607Y758148D01*
X548504Y758455D01*
X548607Y758723D01*
X548814Y758915D01*
X549124Y759068D01*
X549485Y759106D01*
X549795Y759068D01*
X550105Y758915D01*
X550364Y758685D01*
X550467Y758416D01*
X550364Y758110D01*
X550054Y757841D01*
X549589Y757688D01*
X549072Y757650D01*
X548400Y757726D01*
X548039Y757841D01*
X547677Y758033D01*
X547419Y758301D01*
X547367Y758570D01*
X547470Y758838D01*
X547729Y759030D01*
G01X554727Y748311D02*
X551627D01*
Y749270D01*
X551782Y749576D01*
X551989Y749768D01*
X552402Y749845D01*
X552815Y749768D01*
X553074Y749538D01*
X553229Y749270D01*
Y748311D01*
G01Y749270D02*
X554727Y749845D01*
G01Y752178D02*
X554675Y752446D01*
X554520Y752753D01*
X554262Y752945D01*
X553900Y753021D01*
X553539Y752945D01*
X553229Y752715D01*
X553074Y752370D01*
Y751986D01*
X552970Y751756D01*
X552712Y751565D01*
X552350Y751488D01*
X551989Y751603D01*
X551730Y751871D01*
X551627Y752178D01*
X551730Y752485D01*
X551989Y752753D01*
X552350Y752868D01*
X552712Y752791D01*
X552970Y752600D01*
X553074Y752370D01*
Y751986D01*
X553229Y751641D01*
X553539Y751411D01*
X553900Y751335D01*
X554262Y751411D01*
X554520Y751603D01*
X554675Y751910D01*
X554727Y752178D01*
G01Y755201D02*
X554055Y755278D01*
X553487Y755393D01*
X552970Y755546D01*
X552402Y755738D01*
X551627Y756045D01*
Y754511D01*
G01X554107Y757535D02*
X554469Y757765D01*
X554675Y758071D01*
X554727Y758416D01*
X554675Y758723D01*
X554417Y759030D01*
X554107Y759221D01*
X553797Y759260D01*
X553435Y759183D01*
X553177Y758915D01*
X553074Y758646D01*
Y758301D01*
G01Y758646D02*
X552919Y758876D01*
X552660Y759068D01*
X552350Y759145D01*
X552040Y759068D01*
X551782Y758876D01*
X551627Y758531D01*
X551679Y758186D01*
X551885Y757841D01*
G01X559227Y748311D02*
X556127D01*
Y749270D01*
X556282Y749576D01*
X556489Y749768D01*
X556902Y749845D01*
X557315Y749768D01*
X557574Y749538D01*
X557729Y749270D01*
Y748311D01*
G01Y749270D02*
X559227Y749845D01*
G01Y752178D02*
X556127D01*
X556747Y751718D01*
G01X559227D02*
Y752638D01*
G01X556127Y755278D02*
X556230Y754971D01*
X556489Y754741D01*
X556799Y754588D01*
X557212Y754473D01*
X557677Y754435D01*
X558142Y754473D01*
X558555Y754588D01*
X558865Y754741D01*
X559124Y754971D01*
X559227Y755278D01*
X559124Y755585D01*
X558865Y755815D01*
X558555Y755968D01*
X558142Y756083D01*
X557677Y756121D01*
X557212Y756083D01*
X556799Y755968D01*
X556489Y755815D01*
X556230Y755585D01*
X556127Y755278D01*
G01Y758378D02*
X556230Y758071D01*
X556489Y757841D01*
X556799Y757688D01*
X557212Y757573D01*
X557677Y757535D01*
X558142Y757573D01*
X558555Y757688D01*
X558865Y757841D01*
X559124Y758071D01*
X559227Y758378D01*
X559124Y758685D01*
X558865Y758915D01*
X558555Y759068D01*
X558142Y759183D01*
X557677Y759221D01*
X557212Y759183D01*
X556799Y759068D01*
X556489Y758915D01*
X556230Y758685D01*
X556127Y758378D01*
G01X556644Y760750D02*
X556334Y760980D01*
X556179Y761248D01*
X556127Y761555D01*
X556230Y761938D01*
X556489Y762206D01*
X556799Y762283D01*
X557109Y762245D01*
X557367Y762091D01*
X557884Y761325D01*
X558245Y760980D01*
X558762Y760750D01*
X559227Y760673D01*
Y762283D01*
G01X544149Y764380D02*
X543994Y764150D01*
X543891Y763882D01*
Y763575D01*
X544046Y763230D01*
X544304Y762962D01*
X544614Y762770D01*
X545131Y762617D01*
X545596Y762579D01*
X546061Y762655D01*
X546371Y762770D01*
X546681Y763000D01*
X546888Y763269D01*
X546991Y763537D01*
Y763805D01*
X546888Y764074D01*
X546733Y764304D01*
X546526Y764495D01*
G01X545699Y765909D02*
X545338Y766177D01*
X545131Y766407D01*
X545028Y766714D01*
X545131Y766982D01*
X545338Y767174D01*
X545648Y767327D01*
X546009Y767365D01*
X546319Y767327D01*
X546629Y767174D01*
X546888Y766944D01*
X546991Y766675D01*
X546888Y766369D01*
X546578Y766100D01*
X546113Y765947D01*
X545596Y765909D01*
X544924Y765985D01*
X544563Y766100D01*
X544201Y766292D01*
X543943Y766560D01*
X543891Y766829D01*
X543994Y767097D01*
X544253Y767289D01*
G01X546991Y770197D02*
X543891D01*
X546113Y768779D01*
Y770695D01*
G01X544408Y772109D02*
X544098Y772339D01*
X543943Y772607D01*
X543891Y772914D01*
X543994Y773297D01*
X544253Y773565D01*
X544563Y773642D01*
X544873Y773604D01*
X545131Y773450D01*
X545648Y772684D01*
X546009Y772339D01*
X546526Y772109D01*
X546991Y772032D01*
Y773642D01*
G01X555989Y764380D02*
X555834Y764150D01*
X555731Y763882D01*
Y763575D01*
X555886Y763230D01*
X556144Y762962D01*
X556454Y762770D01*
X556971Y762617D01*
X557436Y762579D01*
X557901Y762655D01*
X558211Y762770D01*
X558521Y763000D01*
X558728Y763269D01*
X558831Y763537D01*
Y763805D01*
X558728Y764074D01*
X558573Y764304D01*
X558366Y764495D01*
G01X558831Y766560D02*
X558159Y766637D01*
X557591Y766752D01*
X557074Y766905D01*
X556506Y767097D01*
X555731Y767404D01*
Y765870D01*
G01X557539Y769009D02*
X557178Y769277D01*
X556971Y769507D01*
X556868Y769814D01*
X556971Y770082D01*
X557178Y770274D01*
X557488Y770427D01*
X557849Y770465D01*
X558159Y770427D01*
X558469Y770274D01*
X558728Y770044D01*
X558831Y769775D01*
X558728Y769469D01*
X558418Y769200D01*
X557953Y769047D01*
X557436Y769009D01*
X556764Y769085D01*
X556403Y769200D01*
X556041Y769392D01*
X555783Y769660D01*
X555731Y769929D01*
X555834Y770197D01*
X556093Y770389D01*
G01X558366Y771994D02*
X558624Y772224D01*
X558779Y772492D01*
X558831Y772837D01*
X558728Y773182D01*
X558521Y773450D01*
X558159Y773642D01*
X557746Y773680D01*
X557333Y773604D01*
X557074Y773412D01*
X556868Y773144D01*
X556816Y772875D01*
X556868Y772607D01*
X557074Y772262D01*
X555731Y772377D01*
Y773412D01*
G01X548221Y764380D02*
X548066Y764150D01*
X547963Y763882D01*
Y763575D01*
X548118Y763230D01*
X548376Y762962D01*
X548686Y762770D01*
X549203Y762617D01*
X549668Y762579D01*
X550133Y762655D01*
X550443Y762770D01*
X550753Y763000D01*
X550960Y763269D01*
X551063Y763537D01*
Y763805D01*
X550960Y764074D01*
X550805Y764304D01*
X550598Y764495D01*
G01X549771Y765909D02*
X549410Y766177D01*
X549203Y766407D01*
X549100Y766714D01*
X549203Y766982D01*
X549410Y767174D01*
X549720Y767327D01*
X550081Y767365D01*
X550391Y767327D01*
X550701Y767174D01*
X550960Y766944D01*
X551063Y766675D01*
X550960Y766369D01*
X550650Y766100D01*
X550185Y765947D01*
X549668Y765909D01*
X548996Y765985D01*
X548635Y766100D01*
X548273Y766292D01*
X548015Y766560D01*
X547963Y766829D01*
X548066Y767097D01*
X548325Y767289D01*
G01X550443Y768894D02*
X550805Y769124D01*
X551011Y769430D01*
X551063Y769775D01*
X551011Y770082D01*
X550753Y770389D01*
X550443Y770580D01*
X550133Y770619D01*
X549771Y770542D01*
X549513Y770274D01*
X549410Y770005D01*
Y769660D01*
G01Y770005D02*
X549255Y770235D01*
X548996Y770427D01*
X548686Y770504D01*
X548376Y770427D01*
X548118Y770235D01*
X547963Y769890D01*
X548015Y769545D01*
X548221Y769200D01*
G01X550701Y772185D02*
X550960Y772454D01*
X551063Y772760D01*
X550960Y773067D01*
X550650Y773335D01*
X550185Y773527D01*
X549720Y773604D01*
X549151D01*
X548686Y773527D01*
X548273Y773335D01*
X548066Y773105D01*
X547963Y772837D01*
X548066Y772530D01*
X548273Y772300D01*
X548583Y772147D01*
X548996Y772070D01*
X549358Y772147D01*
X549720Y772339D01*
X549926Y772569D01*
X549978Y772837D01*
X549875Y773144D01*
X549616Y773374D01*
X549151Y773604D01*
G01X552105Y764380D02*
X551950Y764150D01*
X551847Y763882D01*
Y763575D01*
X552002Y763230D01*
X552260Y762962D01*
X552570Y762770D01*
X553087Y762617D01*
X553552Y762579D01*
X554017Y762655D01*
X554327Y762770D01*
X554637Y763000D01*
X554844Y763269D01*
X554947Y763537D01*
Y763805D01*
X554844Y764074D01*
X554689Y764304D01*
X554482Y764495D01*
G01X553655Y765909D02*
X553294Y766177D01*
X553087Y766407D01*
X552984Y766714D01*
X553087Y766982D01*
X553294Y767174D01*
X553604Y767327D01*
X553965Y767365D01*
X554275Y767327D01*
X554585Y767174D01*
X554844Y766944D01*
X554947Y766675D01*
X554844Y766369D01*
X554534Y766100D01*
X554069Y765947D01*
X553552Y765909D01*
X552880Y765985D01*
X552519Y766100D01*
X552157Y766292D01*
X551899Y766560D01*
X551847Y766829D01*
X551950Y767097D01*
X552209Y767289D01*
G01X554327Y768894D02*
X554689Y769124D01*
X554895Y769430D01*
X554947Y769775D01*
X554895Y770082D01*
X554637Y770389D01*
X554327Y770580D01*
X554017Y770619D01*
X553655Y770542D01*
X553397Y770274D01*
X553294Y770005D01*
Y769660D01*
G01Y770005D02*
X553139Y770235D01*
X552880Y770427D01*
X552570Y770504D01*
X552260Y770427D01*
X552002Y770235D01*
X551847Y769890D01*
X551899Y769545D01*
X552105Y769200D01*
G01X553655Y772109D02*
X553294Y772377D01*
X553087Y772607D01*
X552984Y772914D01*
X553087Y773182D01*
X553294Y773374D01*
X553604Y773527D01*
X553965Y773565D01*
X554275Y773527D01*
X554585Y773374D01*
X554844Y773144D01*
X554947Y772875D01*
X554844Y772569D01*
X554534Y772300D01*
X554069Y772147D01*
X553552Y772109D01*
X552880Y772185D01*
X552519Y772300D01*
X552157Y772492D01*
X551899Y772760D01*
X551847Y773029D01*
X551950Y773297D01*
X552209Y773489D01*
G01X575316Y13267D02*
X574936Y13517D01*
X574493Y13684D01*
X573986D01*
X573416Y13434D01*
X572973Y13017D01*
X572656Y12517D01*
X572403Y11684D01*
X572340Y10934D01*
X572466Y10184D01*
X572656Y9684D01*
X573036Y9184D01*
X573480Y8851D01*
X573923Y8684D01*
X574366D01*
X574810Y8851D01*
X575190Y9101D01*
X575506Y9434D01*
G01X577756Y8684D02*
Y13684D01*
X579276D01*
X579783Y13434D01*
X580163Y12851D01*
X580290Y12184D01*
X580163Y11517D01*
X579846Y11017D01*
X579276Y10767D01*
X577756D01*
G01X582856Y13684D02*
Y8684D01*
X585390D01*
G01X587830D02*
Y13684D01*
X589096D01*
X589603Y13434D01*
X589983Y13101D01*
X590300Y12601D01*
X590553Y12017D01*
X590616Y11184D01*
X590553Y10351D01*
X590300Y9767D01*
X589983Y9267D01*
X589603Y8934D01*
X589096Y8684D01*
X587830D01*
G01X593120Y12851D02*
X593500Y13351D01*
X593943Y13601D01*
X594450Y13684D01*
X595083Y13517D01*
X595526Y13101D01*
X595653Y12601D01*
X595590Y12101D01*
X595336Y11684D01*
X594070Y10851D01*
X593500Y10267D01*
X593120Y9434D01*
X592993Y8684D01*
X595653D01*
G01X603256Y9684D02*
X603573Y9184D01*
X603953Y8851D01*
X604396Y8684D01*
X604903Y8851D01*
X605283Y9184D01*
X605663Y9684D01*
X605790Y10351D01*
Y13684D01*
G01X609623D02*
Y8684D01*
G01X608166Y13684D02*
X611080D01*
G01X613140Y8684D02*
X614723Y13684D01*
X616306Y8684D01*
G01X615736Y10434D02*
X613710D01*
G01X620203Y11184D02*
X621470D01*
Y9684D01*
X621090Y9184D01*
X620646Y8851D01*
X620013Y8684D01*
X619380Y8851D01*
X618936Y9184D01*
X618556Y9684D01*
X618303Y10267D01*
X618176Y10934D01*
Y11517D01*
X618303Y12017D01*
X618556Y12601D01*
X618936Y13101D01*
X619316Y13434D01*
X619823Y13684D01*
X620266D01*
X620773Y13517D01*
X621153Y13184D01*
G01X572640Y15125D02*
X623372D01*
Y6386D01*
X571455D01*
Y15125D01*
X572640D01*
G01X562225Y29265D02*
X562455Y29575D01*
X562723Y29730D01*
X563030Y29782D01*
X563413Y29679D01*
X563681Y29420D01*
X563758Y29110D01*
X563720Y28800D01*
X563566Y28542D01*
X562800Y28025D01*
X562455Y27664D01*
X562225Y27147D01*
X562148Y26682D01*
X563758D01*
G01X560764Y44197D02*
Y23409D01*
G01X572485Y18653D02*
Y21753D01*
X572025Y21133D01*
G01Y18653D02*
X572945D01*
G01X575585Y21753D02*
X575278Y21650D01*
X575048Y21391D01*
X574895Y21081D01*
X574780Y20668D01*
X574742Y20203D01*
X574780Y19738D01*
X574895Y19325D01*
X575048Y19015D01*
X575278Y18756D01*
X575585Y18653D01*
X575892Y18756D01*
X576122Y19015D01*
X576275Y19325D01*
X576390Y19738D01*
X576428Y20203D01*
X576390Y20668D01*
X576275Y21081D01*
X576122Y21391D01*
X575892Y21650D01*
X575585Y21753D01*
G01X623355Y23409D02*
X571387D01*
G01D02*
Y44197D01*
G01X562300Y36076D02*
Y39176D01*
X561840Y38556D01*
G01Y36076D02*
X562760D01*
G01X568713Y41476D02*
X568982Y41217D01*
X569288Y41114D01*
X569595Y41217D01*
X569863Y41527D01*
X570055Y41992D01*
X570132Y42457D01*
Y43026D01*
X570055Y43491D01*
X569863Y43904D01*
X569633Y44111D01*
X569365Y44214D01*
X569058Y44111D01*
X568828Y43904D01*
X568675Y43594D01*
X568598Y43181D01*
X568675Y42819D01*
X568867Y42457D01*
X569097Y42251D01*
X569365Y42199D01*
X569672Y42302D01*
X569902Y42561D01*
X570132Y43026D01*
G01X571387Y44197D02*
X623355D01*
G01X561280Y58670D02*
X578440D01*
G01X562676Y61364D02*
X562521Y61134D01*
X562418Y60866D01*
Y60559D01*
X562573Y60214D01*
X562831Y59946D01*
X563141Y59754D01*
X563658Y59601D01*
X564123Y59563D01*
X564588Y59639D01*
X564898Y59754D01*
X565208Y59984D01*
X565415Y60253D01*
X565518Y60521D01*
Y60789D01*
X565415Y61058D01*
X565260Y61288D01*
X565053Y61479D01*
G01X565518Y64081D02*
X562418D01*
X564640Y62663D01*
Y64579D01*
G01X565156Y66069D02*
X565415Y66338D01*
X565518Y66644D01*
X565415Y66951D01*
X565105Y67219D01*
X564640Y67411D01*
X564175Y67488D01*
X563606D01*
X563141Y67411D01*
X562728Y67219D01*
X562521Y66989D01*
X562418Y66721D01*
X562521Y66414D01*
X562728Y66184D01*
X563038Y66031D01*
X563451Y65954D01*
X563813Y66031D01*
X564175Y66223D01*
X564381Y66453D01*
X564433Y66721D01*
X564330Y67028D01*
X564071Y67258D01*
X563606Y67488D01*
G01X564898Y68978D02*
X565260Y69208D01*
X565466Y69514D01*
X565518Y69859D01*
X565466Y70166D01*
X565208Y70473D01*
X564898Y70664D01*
X564588Y70703D01*
X564226Y70626D01*
X563968Y70358D01*
X563865Y70089D01*
Y69744D01*
G01Y70089D02*
X563710Y70319D01*
X563451Y70511D01*
X563141Y70588D01*
X562831Y70511D01*
X562573Y70319D01*
X562418Y69974D01*
X562470Y69629D01*
X562676Y69284D01*
G01X570976Y61364D02*
X570821Y61134D01*
X570718Y60866D01*
Y60559D01*
X570873Y60214D01*
X571131Y59946D01*
X571441Y59754D01*
X571958Y59601D01*
X572423Y59563D01*
X572888Y59639D01*
X573198Y59754D01*
X573508Y59984D01*
X573715Y60253D01*
X573818Y60521D01*
Y60789D01*
X573715Y61058D01*
X573560Y61288D01*
X573353Y61479D01*
G01X573818Y64081D02*
X570718D01*
X572940Y62663D01*
Y64579D01*
G01X573818Y66721D02*
X573766Y66989D01*
X573611Y67296D01*
X573353Y67488D01*
X572991Y67564D01*
X572630Y67488D01*
X572320Y67258D01*
X572165Y66913D01*
Y66529D01*
X572061Y66299D01*
X571803Y66108D01*
X571441Y66031D01*
X571080Y66146D01*
X570821Y66414D01*
X570718Y66721D01*
X570821Y67028D01*
X571080Y67296D01*
X571441Y67411D01*
X571803Y67334D01*
X572061Y67143D01*
X572165Y66913D01*
Y66529D01*
X572320Y66184D01*
X572630Y65954D01*
X572991Y65878D01*
X573353Y65954D01*
X573611Y66146D01*
X573766Y66453D01*
X573818Y66721D01*
G01X571235Y69093D02*
X570925Y69323D01*
X570770Y69591D01*
X570718Y69898D01*
X570821Y70281D01*
X571080Y70549D01*
X571390Y70626D01*
X571700Y70588D01*
X571958Y70434D01*
X572475Y69668D01*
X572836Y69323D01*
X573353Y69093D01*
X573818Y69016D01*
Y70626D01*
G01X558596Y61364D02*
X558441Y61134D01*
X558338Y60866D01*
Y60559D01*
X558493Y60214D01*
X558751Y59946D01*
X559061Y59754D01*
X559578Y59601D01*
X560043Y59563D01*
X560508Y59639D01*
X560818Y59754D01*
X561128Y59984D01*
X561335Y60253D01*
X561438Y60521D01*
Y60789D01*
X561335Y61058D01*
X561180Y61288D01*
X560973Y61479D01*
G01X561438Y64081D02*
X558338D01*
X560560Y62663D01*
Y64579D01*
G01X561076Y66069D02*
X561335Y66338D01*
X561438Y66644D01*
X561335Y66951D01*
X561025Y67219D01*
X560560Y67411D01*
X560095Y67488D01*
X559526D01*
X559061Y67411D01*
X558648Y67219D01*
X558441Y66989D01*
X558338Y66721D01*
X558441Y66414D01*
X558648Y66184D01*
X558958Y66031D01*
X559371Y65954D01*
X559733Y66031D01*
X560095Y66223D01*
X560301Y66453D01*
X560353Y66721D01*
X560250Y67028D01*
X559991Y67258D01*
X559526Y67488D01*
G01X561438Y69821D02*
X558338D01*
X558958Y69361D01*
G01X561438D02*
Y70281D01*
G01X569618Y59754D02*
X566518D01*
Y60713D01*
X566673Y61019D01*
X566880Y61211D01*
X567293Y61288D01*
X567706Y61211D01*
X567965Y60981D01*
X568120Y60713D01*
Y59754D01*
G01Y60713D02*
X569618Y61288D01*
G01Y63621D02*
X566518D01*
X567138Y63161D01*
G01X569618D02*
Y64081D01*
G01Y66721D02*
X566518D01*
X567138Y66261D01*
G01X569618D02*
Y67181D01*
G01X568998Y68978D02*
X569360Y69208D01*
X569566Y69514D01*
X569618Y69859D01*
X569566Y70166D01*
X569308Y70473D01*
X568998Y70664D01*
X568688Y70703D01*
X568326Y70626D01*
X568068Y70358D01*
X567965Y70089D01*
Y69744D01*
G01Y70089D02*
X567810Y70319D01*
X567551Y70511D01*
X567241Y70588D01*
X566931Y70511D01*
X566673Y70319D01*
X566518Y69974D01*
X566570Y69629D01*
X566776Y69284D01*
G01X569256Y72269D02*
X569515Y72538D01*
X569618Y72844D01*
X569515Y73151D01*
X569205Y73419D01*
X568740Y73611D01*
X568275Y73688D01*
X567706D01*
X567241Y73611D01*
X566828Y73419D01*
X566621Y73189D01*
X566518Y72921D01*
X566621Y72614D01*
X566828Y72384D01*
X567138Y72231D01*
X567551Y72154D01*
X567913Y72231D01*
X568275Y72423D01*
X568481Y72653D01*
X568533Y72921D01*
X568430Y73228D01*
X568171Y73458D01*
X567706Y73688D01*
G01X572665Y79671D02*
X572415Y79291D01*
X572248Y78848D01*
Y78341D01*
X572498Y77771D01*
X572915Y77328D01*
X573415Y77011D01*
X574248Y76758D01*
X574998Y76695D01*
X575748Y76821D01*
X576248Y77011D01*
X576748Y77391D01*
X577081Y77835D01*
X577248Y78278D01*
Y78721D01*
X577081Y79165D01*
X576831Y79545D01*
X576498Y79861D01*
G01X577248Y83378D02*
X577165Y82871D01*
X576831Y82428D01*
X576331Y82048D01*
X575748Y81795D01*
X575081Y81668D01*
X574415D01*
X573748Y81795D01*
X573165Y82048D01*
X572665Y82428D01*
X572331Y82871D01*
X572248Y83378D01*
X572331Y83885D01*
X572665Y84328D01*
X573165Y84708D01*
X573748Y84961D01*
X574415Y85088D01*
X575081D01*
X575748Y84961D01*
X576331Y84708D01*
X576831Y84328D01*
X577165Y83885D01*
X577248Y83378D01*
G01Y86831D02*
X572248D01*
X576415Y88478D01*
X572248Y90125D01*
X577248D01*
G01Y94338D02*
X572248D01*
X575831Y91995D01*
Y95161D01*
G01X570690Y76160D02*
X569550Y75020D01*
G01X570690Y76230D02*
Y76160D01*
G01X568210Y76230D02*
X570690D01*
G01X569500Y74940D02*
X568210Y76230D01*
G01X569550Y74940D02*
X569500D01*
G01X569550Y93880D02*
Y74940D01*
G01X562370Y74730D02*
X578190D01*
G01X577822Y95902D02*
X571823D01*
Y75881D01*
X577822D01*
Y95902D01*
G01X561673Y91889D02*
Y71889D01*
G01X563790Y93880D02*
X569550D01*
G01X563790D02*
Y97700D01*
G01X563950Y105730D02*
Y109710D01*
G01X560105Y114125D02*
Y108125D01*
G01X563238Y108723D02*
Y98523D01*
G01X558638Y103623D02*
X563238D01*
G01X558638Y98523D02*
Y108723D01*
G01X563238Y98523D02*
X558638D01*
G01X570211Y109129D02*
Y106029D01*
X571745D01*
G01X573235Y106649D02*
X573465Y106287D01*
X573771Y106081D01*
X574116Y106029D01*
X574423Y106081D01*
X574730Y106339D01*
X574921Y106649D01*
X574960Y106959D01*
X574883Y107321D01*
X574615Y107579D01*
X574346Y107682D01*
X574001D01*
G01X574346D02*
X574576Y107837D01*
X574768Y108096D01*
X574845Y108406D01*
X574768Y108716D01*
X574576Y108974D01*
X574231Y109129D01*
X573886Y109077D01*
X573541Y108871D01*
G01X577101Y106029D02*
X577178Y106701D01*
X577293Y107269D01*
X577446Y107786D01*
X577638Y108354D01*
X577945Y109129D01*
X576411D01*
G01X570838Y104723D02*
X577038D01*
G01Y101523D02*
X570838D01*
G01D02*
Y104723D01*
G01X573588Y101523D02*
Y104723D01*
G01X564938Y106824D02*
X568038D01*
Y108358D01*
G01X567418Y109848D02*
X567780Y110078D01*
X567986Y110384D01*
X568038Y110729D01*
X567986Y111036D01*
X567728Y111343D01*
X567418Y111534D01*
X567108Y111573D01*
X566746Y111496D01*
X566488Y111228D01*
X566385Y110959D01*
Y110614D01*
G01Y110959D02*
X566230Y111189D01*
X565971Y111381D01*
X565661Y111458D01*
X565351Y111381D01*
X565093Y111189D01*
X564938Y110844D01*
X564990Y110499D01*
X565196Y110154D01*
G01X566746Y113063D02*
X566385Y113331D01*
X566178Y113561D01*
X566075Y113868D01*
X566178Y114136D01*
X566385Y114328D01*
X566695Y114481D01*
X567056Y114519D01*
X567366Y114481D01*
X567676Y114328D01*
X567935Y114098D01*
X568038Y113829D01*
X567935Y113523D01*
X567625Y113254D01*
X567160Y113101D01*
X566643Y113063D01*
X565971Y113139D01*
X565610Y113254D01*
X565248Y113446D01*
X564990Y113714D01*
X564938Y113983D01*
X565041Y114251D01*
X565300Y114443D01*
G01X564338Y104723D02*
X567538D01*
G01Y101973D02*
X564338D01*
G01Y98523D02*
Y104723D01*
G01X567538D02*
Y98523D01*
G01D02*
X564338D01*
G01X567538Y101273D02*
X564338D01*
G01X570046Y123399D02*
Y125899D01*
X569726Y125399D01*
G01Y123399D02*
X570366D01*
G01X572246Y125899D02*
X572033Y125816D01*
X571873Y125607D01*
X571766Y125357D01*
X571686Y125024D01*
X571659Y124649D01*
X571686Y124274D01*
X571766Y123941D01*
X571873Y123691D01*
X572033Y123482D01*
X572246Y123399D01*
X572459Y123482D01*
X572619Y123691D01*
X572726Y123941D01*
X572806Y124274D01*
X572833Y124649D01*
X572806Y125024D01*
X572726Y125357D01*
X572619Y125607D01*
X572459Y125816D01*
X572246Y125899D01*
G01X573859Y123899D02*
X574019Y123607D01*
X574233Y123441D01*
X574473Y123399D01*
X574686Y123441D01*
X574899Y123649D01*
X575033Y123899D01*
X575059Y124149D01*
X575006Y124441D01*
X574819Y124649D01*
X574633Y124732D01*
X574393D01*
G01X574633D02*
X574793Y124857D01*
X574926Y125066D01*
X574979Y125316D01*
X574926Y125566D01*
X574793Y125774D01*
X574553Y125899D01*
X574313Y125857D01*
X574073Y125691D01*
G01X566129Y116943D02*
Y119443D01*
X565809Y118943D01*
G01Y116943D02*
X566449D01*
G01X568329Y119443D02*
X568116Y119360D01*
X567956Y119151D01*
X567849Y118901D01*
X567769Y118568D01*
X567742Y118193D01*
X567769Y117818D01*
X567849Y117485D01*
X567956Y117235D01*
X568116Y117026D01*
X568329Y116943D01*
X568542Y117026D01*
X568702Y117235D01*
X568809Y117485D01*
X568889Y117818D01*
X568916Y118193D01*
X568889Y118568D01*
X568809Y118901D01*
X568702Y119151D01*
X568542Y119360D01*
X568329Y119443D01*
G01X570022Y119026D02*
X570182Y119276D01*
X570369Y119401D01*
X570582Y119443D01*
X570849Y119360D01*
X571036Y119151D01*
X571089Y118901D01*
X571062Y118651D01*
X570956Y118443D01*
X570422Y118026D01*
X570182Y117735D01*
X570022Y117318D01*
X569969Y116943D01*
X571089D01*
G01X558638Y108723D02*
X563238D01*
G01X567172Y179881D02*
Y124369D01*
G01X566056Y185788D02*
Y188288D01*
X565736Y187788D01*
G01Y185788D02*
X566376D01*
G01X570481Y178243D02*
Y180743D01*
X570161Y180243D01*
G01Y178243D02*
X570801D01*
G01X572174Y180326D02*
X572334Y180576D01*
X572521Y180701D01*
X572734Y180743D01*
X573001Y180660D01*
X573188Y180451D01*
X573241Y180201D01*
X573214Y179951D01*
X573108Y179743D01*
X572574Y179326D01*
X572334Y179035D01*
X572174Y178618D01*
X572121Y178243D01*
X573241D01*
G01X574881D02*
X575068Y178285D01*
X575281Y178410D01*
X575414Y178618D01*
X575468Y178910D01*
X575414Y179201D01*
X575254Y179451D01*
X575014Y179576D01*
X574748D01*
X574588Y179660D01*
X574454Y179868D01*
X574401Y180160D01*
X574481Y180451D01*
X574668Y180660D01*
X574881Y180743D01*
X575094Y180660D01*
X575281Y180451D01*
X575361Y180160D01*
X575308Y179868D01*
X575174Y179660D01*
X575014Y179576D01*
X574748D01*
X574508Y179451D01*
X574348Y179201D01*
X574294Y178910D01*
X574348Y178618D01*
X574481Y178410D01*
X574694Y178285D01*
X574881Y178243D01*
G01X560309Y199564D02*
Y205764D01*
G01X563509D02*
Y199564D01*
G01D02*
X560309D01*
G01X559509Y205764D02*
Y199564D01*
G01X574575Y195931D02*
X567775D01*
G01D02*
Y210931D01*
G01X560309Y205764D02*
X563509D01*
G01X568171Y212891D02*
Y215991D01*
X569130D01*
X569436Y215836D01*
X569628Y215629D01*
X569705Y215216D01*
X569628Y214803D01*
X569398Y214544D01*
X569130Y214389D01*
X568171D01*
G01X569130D02*
X569705Y212891D01*
G01X572038D02*
Y215991D01*
X571578Y215371D01*
G01Y212891D02*
X572498D01*
G01X575138Y215991D02*
X574831Y215888D01*
X574601Y215629D01*
X574448Y215319D01*
X574333Y214906D01*
X574295Y214441D01*
X574333Y213976D01*
X574448Y213563D01*
X574601Y213253D01*
X574831Y212994D01*
X575138Y212891D01*
X575445Y212994D01*
X575675Y213253D01*
X575828Y213563D01*
X575943Y213976D01*
X575981Y214441D01*
X575943Y214906D01*
X575828Y215319D01*
X575675Y215629D01*
X575445Y215888D01*
X575138Y215991D01*
G01X578238Y212891D02*
Y215991D01*
X577778Y215371D01*
G01Y212891D02*
X578698D01*
G01X580610Y214183D02*
X580878Y214544D01*
X581108Y214751D01*
X581415Y214854D01*
X581683Y214751D01*
X581875Y214544D01*
X582028Y214234D01*
X582066Y213873D01*
X582028Y213563D01*
X581875Y213253D01*
X581645Y212994D01*
X581376Y212891D01*
X581070Y212994D01*
X580801Y213304D01*
X580648Y213769D01*
X580610Y214286D01*
X580686Y214958D01*
X580801Y215319D01*
X580993Y215681D01*
X581261Y215939D01*
X581530Y215991D01*
X581798Y215888D01*
X581990Y215629D01*
G01X566509Y209082D02*
X560309D01*
G01Y212282D02*
X566509D01*
G01D02*
Y209082D01*
G01X560309D02*
Y212282D01*
G01X568125Y216917D02*
Y220017D01*
X569084D01*
X569390Y219862D01*
X569582Y219655D01*
X569659Y219242D01*
X569582Y218829D01*
X569352Y218570D01*
X569084Y218415D01*
X568125D01*
G01X569084D02*
X569659Y216917D01*
G01X571992D02*
Y220017D01*
X571532Y219397D01*
G01Y216917D02*
X572452D01*
G01X575092Y220017D02*
X574785Y219914D01*
X574555Y219655D01*
X574402Y219345D01*
X574287Y218932D01*
X574249Y218467D01*
X574287Y218002D01*
X574402Y217589D01*
X574555Y217279D01*
X574785Y217020D01*
X575092Y216917D01*
X575399Y217020D01*
X575629Y217279D01*
X575782Y217589D01*
X575897Y218002D01*
X575935Y218467D01*
X575897Y218932D01*
X575782Y219345D01*
X575629Y219655D01*
X575399Y219914D01*
X575092Y220017D01*
G01X578192Y216917D02*
Y220017D01*
X577732Y219397D01*
G01Y216917D02*
X578652D01*
G01X580449Y217382D02*
X580679Y217124D01*
X580947Y216969D01*
X581292Y216917D01*
X581637Y217020D01*
X581905Y217227D01*
X582097Y217589D01*
X582135Y218002D01*
X582059Y218415D01*
X581867Y218674D01*
X581599Y218880D01*
X581330Y218932D01*
X581062Y218880D01*
X580717Y218674D01*
X580832Y220017D01*
X581867D01*
G01X566509Y213082D02*
X560309D01*
G01Y216282D02*
X566509D01*
G01D02*
Y213082D01*
G01X560309D02*
Y216282D01*
G01X567775Y210931D02*
X574575D01*
G01X571373Y228847D02*
Y232847D01*
G01X563513Y230680D02*
Y232680D01*
G01X567238Y225933D02*
Y219133D01*
G01X569929Y279602D02*
Y277380D01*
X570082Y276915D01*
X570389Y276605D01*
X570772Y276502D01*
X571155Y276605D01*
X571462Y276915D01*
X571615Y277380D01*
Y279602D01*
G01X573029Y277122D02*
X573259Y276760D01*
X573565Y276554D01*
X573910Y276502D01*
X574217Y276554D01*
X574524Y276812D01*
X574715Y277122D01*
X574754Y277432D01*
X574677Y277794D01*
X574409Y278052D01*
X574140Y278155D01*
X573795D01*
G01X574140D02*
X574370Y278310D01*
X574562Y278569D01*
X574639Y278879D01*
X574562Y279189D01*
X574370Y279447D01*
X574025Y279602D01*
X573680Y279550D01*
X573335Y279344D01*
G01X576972Y279602D02*
X576665Y279499D01*
X576435Y279240D01*
X576282Y278930D01*
X576167Y278517D01*
X576129Y278052D01*
X576167Y277587D01*
X576282Y277174D01*
X576435Y276864D01*
X576665Y276605D01*
X576972Y276502D01*
X577279Y276605D01*
X577509Y276864D01*
X577662Y277174D01*
X577777Y277587D01*
X577815Y278052D01*
X577777Y278517D01*
X577662Y278930D01*
X577509Y279240D01*
X577279Y279499D01*
X576972Y279602D01*
G01X568224Y274094D02*
Y278094D01*
G01X560417Y274027D02*
Y276027D01*
G01X559515Y279790D02*
X561161D01*
G01X570750Y281094D02*
X567650D01*
Y282053D01*
X567805Y282359D01*
X568012Y282551D01*
X568425Y282628D01*
X568838Y282551D01*
X569097Y282321D01*
X569252Y282053D01*
Y281094D01*
G01Y282053D02*
X570750Y282628D01*
G01X570285Y284118D02*
X570543Y284348D01*
X570698Y284616D01*
X570750Y284961D01*
X570647Y285306D01*
X570440Y285574D01*
X570078Y285766D01*
X569665Y285804D01*
X569252Y285728D01*
X568993Y285536D01*
X568787Y285268D01*
X568735Y284999D01*
X568787Y284731D01*
X568993Y284386D01*
X567650Y284501D01*
Y285536D01*
G01X570750Y288061D02*
X567650D01*
X568270Y287601D01*
G01X570750D02*
Y288521D01*
G01X570130Y290318D02*
X570492Y290548D01*
X570698Y290854D01*
X570750Y291199D01*
X570698Y291506D01*
X570440Y291813D01*
X570130Y292004D01*
X569820Y292043D01*
X569458Y291966D01*
X569200Y291698D01*
X569097Y291429D01*
Y291084D01*
G01Y291429D02*
X568942Y291659D01*
X568683Y291851D01*
X568373Y291928D01*
X568063Y291851D01*
X567805Y291659D01*
X567650Y291314D01*
X567702Y290969D01*
X567908Y290624D01*
G01X565954Y287802D02*
Y281602D01*
G01D02*
X562754D01*
G01D02*
Y287802D01*
G01D02*
X565954D01*
G01X558782Y429066D02*
Y432166D01*
X559741D01*
X560047Y432011D01*
X560239Y431804D01*
X560316Y431391D01*
X560239Y430978D01*
X560009Y430719D01*
X559741Y430564D01*
X558782D01*
G01X559741D02*
X560316Y429066D01*
G01X561921Y431649D02*
X562151Y431959D01*
X562419Y432114D01*
X562726Y432166D01*
X563109Y432063D01*
X563377Y431804D01*
X563454Y431494D01*
X563416Y431184D01*
X563262Y430926D01*
X562496Y430409D01*
X562151Y430048D01*
X561921Y429531D01*
X561844Y429066D01*
X563454D01*
G01X566209D02*
Y432166D01*
X564791Y429944D01*
X566707D01*
G01X558782Y425286D02*
Y428386D01*
X559741D01*
X560047Y428231D01*
X560239Y428024D01*
X560316Y427611D01*
X560239Y427198D01*
X560009Y426939D01*
X559741Y426784D01*
X558782D01*
G01X559741D02*
X560316Y425286D01*
G01X561921Y427869D02*
X562151Y428179D01*
X562419Y428334D01*
X562726Y428386D01*
X563109Y428283D01*
X563377Y428024D01*
X563454Y427714D01*
X563416Y427404D01*
X563262Y427146D01*
X562496Y426629D01*
X562151Y426268D01*
X561921Y425751D01*
X561844Y425286D01*
X563454D01*
G01X565749Y428386D02*
X565442Y428283D01*
X565212Y428024D01*
X565059Y427714D01*
X564944Y427301D01*
X564906Y426836D01*
X564944Y426371D01*
X565059Y425958D01*
X565212Y425648D01*
X565442Y425389D01*
X565749Y425286D01*
X566056Y425389D01*
X566286Y425648D01*
X566439Y425958D01*
X566554Y426371D01*
X566592Y426836D01*
X566554Y427301D01*
X566439Y427714D01*
X566286Y428024D01*
X566056Y428283D01*
X565749Y428386D01*
G01X568279Y455178D02*
Y458278D01*
X569238D01*
X569544Y458123D01*
X569736Y457916D01*
X569813Y457503D01*
X569736Y457090D01*
X569506Y456831D01*
X569238Y456676D01*
X568279D01*
G01X569238D02*
X569813Y455178D01*
G01X572146D02*
Y458278D01*
X571686Y457658D01*
G01Y455178D02*
X572606D01*
G01X574403Y455798D02*
X574633Y455436D01*
X574939Y455230D01*
X575284Y455178D01*
X575591Y455230D01*
X575898Y455488D01*
X576089Y455798D01*
X576128Y456108D01*
X576051Y456470D01*
X575783Y456728D01*
X575514Y456831D01*
X575169D01*
G01X575514D02*
X575744Y456986D01*
X575936Y457245D01*
X576013Y457555D01*
X575936Y457865D01*
X575744Y458123D01*
X575399Y458278D01*
X575054Y458226D01*
X574709Y458020D01*
G01X558840Y454556D02*
Y457756D01*
G01X565040Y454556D02*
X558840D01*
G01X565040Y457756D02*
Y454556D01*
G01X568999Y442853D02*
X565899D01*
Y443812D01*
X566054Y444118D01*
X566261Y444310D01*
X566674Y444387D01*
X567087Y444310D01*
X567346Y444080D01*
X567501Y443812D01*
Y442853D01*
G01Y443812D02*
X568999Y444387D01*
G01X566416Y445992D02*
X566106Y446222D01*
X565951Y446490D01*
X565899Y446797D01*
X566002Y447180D01*
X566261Y447448D01*
X566571Y447525D01*
X566881Y447487D01*
X567139Y447333D01*
X567656Y446567D01*
X568017Y446222D01*
X568534Y445992D01*
X568999Y445915D01*
Y447525D01*
G01Y449820D02*
X565899D01*
X566519Y449360D01*
G01X568999D02*
Y450280D01*
G01X564802Y442853D02*
X561702D01*
Y443812D01*
X561857Y444118D01*
X562064Y444310D01*
X562477Y444387D01*
X562890Y444310D01*
X563149Y444080D01*
X563304Y443812D01*
Y442853D01*
G01Y443812D02*
X564802Y444387D01*
G01X562219Y445992D02*
X561909Y446222D01*
X561754Y446490D01*
X561702Y446797D01*
X561805Y447180D01*
X562064Y447448D01*
X562374Y447525D01*
X562684Y447487D01*
X562942Y447333D01*
X563459Y446567D01*
X563820Y446222D01*
X564337Y445992D01*
X564802Y445915D01*
Y447525D01*
G01X564337Y448977D02*
X564595Y449207D01*
X564750Y449475D01*
X564802Y449820D01*
X564699Y450165D01*
X564492Y450433D01*
X564130Y450625D01*
X563717Y450663D01*
X563304Y450587D01*
X563045Y450395D01*
X562839Y450127D01*
X562787Y449858D01*
X562839Y449590D01*
X563045Y449245D01*
X561702Y449360D01*
Y450395D01*
G01X572943Y442853D02*
X569843D01*
Y443812D01*
X569998Y444118D01*
X570205Y444310D01*
X570618Y444387D01*
X571031Y444310D01*
X571290Y444080D01*
X571445Y443812D01*
Y442853D01*
G01Y443812D02*
X572943Y444387D01*
G01Y446720D02*
X569843D01*
X570463Y446260D01*
G01X572943D02*
Y447180D01*
G01X572323Y448977D02*
X572685Y449207D01*
X572891Y449513D01*
X572943Y449858D01*
X572891Y450165D01*
X572633Y450472D01*
X572323Y450663D01*
X572013Y450702D01*
X571651Y450625D01*
X571393Y450357D01*
X571290Y450088D01*
Y449743D01*
G01Y450088D02*
X571135Y450318D01*
X570876Y450510D01*
X570566Y450587D01*
X570256Y450510D01*
X569998Y450318D01*
X569843Y449973D01*
X569895Y449628D01*
X570101Y449283D01*
G01X572478Y452077D02*
X572736Y452307D01*
X572891Y452575D01*
X572943Y452920D01*
X572840Y453265D01*
X572633Y453533D01*
X572271Y453725D01*
X571858Y453763D01*
X571445Y453687D01*
X571186Y453495D01*
X570980Y453227D01*
X570928Y452958D01*
X570980Y452690D01*
X571186Y452345D01*
X569843Y452460D01*
Y453495D01*
G01X560740Y453427D02*
Y447227D01*
G01X567173Y594163D02*
X565742D01*
Y537794D01*
X567053D01*
Y519143D01*
X565981D01*
Y467261D01*
X578673D01*
Y490005D01*
X580580D01*
Y528141D01*
X574502D01*
Y594163D01*
X567173D01*
G01X558140Y485156D02*
Y470156D01*
G01X568279Y459171D02*
Y462271D01*
X569238D01*
X569544Y462116D01*
X569736Y461909D01*
X569813Y461496D01*
X569736Y461083D01*
X569506Y460824D01*
X569238Y460669D01*
X568279D01*
G01X569238D02*
X569813Y459171D01*
G01X572146D02*
Y462271D01*
X571686Y461651D01*
G01Y459171D02*
X572606D01*
G01X574518Y461754D02*
X574748Y462064D01*
X575016Y462219D01*
X575323Y462271D01*
X575706Y462168D01*
X575974Y461909D01*
X576051Y461599D01*
X576013Y461289D01*
X575859Y461031D01*
X575093Y460514D01*
X574748Y460153D01*
X574518Y459636D01*
X574441Y459171D01*
X576051D01*
G01X565140Y462556D02*
Y459356D01*
G01D02*
X558940D01*
G01D02*
Y462556D01*
G01D02*
X565140D01*
G01X558840Y457756D02*
X565040D01*
G01X567022Y476344D02*
Y479444D01*
X567981D01*
X568287Y479289D01*
X568479Y479082D01*
X568556Y478669D01*
X568479Y478256D01*
X568249Y477997D01*
X567981Y477842D01*
X567022D01*
G01X567981D02*
X568556Y476344D01*
G01X570161Y478927D02*
X570391Y479237D01*
X570659Y479392D01*
X570966Y479444D01*
X571349Y479341D01*
X571617Y479082D01*
X571694Y478772D01*
X571656Y478462D01*
X571502Y478204D01*
X570736Y477687D01*
X570391Y477326D01*
X570161Y476809D01*
X570084Y476344D01*
X571694D01*
G01X573989D02*
X574257Y476396D01*
X574564Y476551D01*
X574756Y476809D01*
X574832Y477171D01*
X574756Y477532D01*
X574526Y477842D01*
X574181Y477997D01*
X573797D01*
X573567Y478101D01*
X573376Y478359D01*
X573299Y478721D01*
X573414Y479082D01*
X573682Y479341D01*
X573989Y479444D01*
X574296Y479341D01*
X574564Y479082D01*
X574679Y478721D01*
X574602Y478359D01*
X574411Y478101D01*
X574181Y477997D01*
X573797D01*
X573452Y477842D01*
X573222Y477532D01*
X573146Y477171D01*
X573222Y476809D01*
X573414Y476551D01*
X573721Y476396D01*
X573989Y476344D01*
G01X577089D02*
X577357Y476396D01*
X577664Y476551D01*
X577856Y476809D01*
X577932Y477171D01*
X577856Y477532D01*
X577626Y477842D01*
X577281Y477997D01*
X576897D01*
X576667Y478101D01*
X576476Y478359D01*
X576399Y478721D01*
X576514Y479082D01*
X576782Y479341D01*
X577089Y479444D01*
X577396Y479341D01*
X577664Y479082D01*
X577779Y478721D01*
X577702Y478359D01*
X577511Y478101D01*
X577281Y477997D01*
X576897D01*
X576552Y477842D01*
X576322Y477532D01*
X576246Y477171D01*
X576322Y476809D01*
X576514Y476551D01*
X576821Y476396D01*
X577089Y476344D01*
G01X567022Y480344D02*
Y483444D01*
X567981D01*
X568287Y483289D01*
X568479Y483082D01*
X568556Y482669D01*
X568479Y482256D01*
X568249Y481997D01*
X567981Y481842D01*
X567022D01*
G01X567981D02*
X568556Y480344D01*
G01X570161Y482927D02*
X570391Y483237D01*
X570659Y483392D01*
X570966Y483444D01*
X571349Y483341D01*
X571617Y483082D01*
X571694Y482772D01*
X571656Y482462D01*
X571502Y482204D01*
X570736Y481687D01*
X570391Y481326D01*
X570161Y480809D01*
X570084Y480344D01*
X571694D01*
G01X573989D02*
X574257Y480396D01*
X574564Y480551D01*
X574756Y480809D01*
X574832Y481171D01*
X574756Y481532D01*
X574526Y481842D01*
X574181Y481997D01*
X573797D01*
X573567Y482101D01*
X573376Y482359D01*
X573299Y482721D01*
X573414Y483082D01*
X573682Y483341D01*
X573989Y483444D01*
X574296Y483341D01*
X574564Y483082D01*
X574679Y482721D01*
X574602Y482359D01*
X574411Y482101D01*
X574181Y481997D01*
X573797D01*
X573452Y481842D01*
X573222Y481532D01*
X573146Y481171D01*
X573222Y480809D01*
X573414Y480551D01*
X573721Y480396D01*
X573989Y480344D01*
G01X576361Y481636D02*
X576629Y481997D01*
X576859Y482204D01*
X577166Y482307D01*
X577434Y482204D01*
X577626Y481997D01*
X577779Y481687D01*
X577817Y481326D01*
X577779Y481016D01*
X577626Y480706D01*
X577396Y480447D01*
X577127Y480344D01*
X576821Y480447D01*
X576552Y480757D01*
X576399Y481222D01*
X576361Y481739D01*
X576437Y482411D01*
X576552Y482772D01*
X576744Y483134D01*
X577012Y483392D01*
X577281Y483444D01*
X577549Y483341D01*
X577741Y483082D01*
G01X567022Y472094D02*
Y475194D01*
X567981D01*
X568287Y475039D01*
X568479Y474832D01*
X568556Y474419D01*
X568479Y474006D01*
X568249Y473747D01*
X567981Y473592D01*
X567022D01*
G01X567981D02*
X568556Y472094D01*
G01X570161Y474677D02*
X570391Y474987D01*
X570659Y475142D01*
X570966Y475194D01*
X571349Y475091D01*
X571617Y474832D01*
X571694Y474522D01*
X571656Y474212D01*
X571502Y473954D01*
X570736Y473437D01*
X570391Y473076D01*
X570161Y472559D01*
X570084Y472094D01*
X571694D01*
G01X573261Y473386D02*
X573529Y473747D01*
X573759Y473954D01*
X574066Y474057D01*
X574334Y473954D01*
X574526Y473747D01*
X574679Y473437D01*
X574717Y473076D01*
X574679Y472766D01*
X574526Y472456D01*
X574296Y472197D01*
X574027Y472094D01*
X573721Y472197D01*
X573452Y472507D01*
X573299Y472972D01*
X573261Y473489D01*
X573337Y474161D01*
X573452Y474522D01*
X573644Y474884D01*
X573912Y475142D01*
X574181Y475194D01*
X574449Y475091D01*
X574641Y474832D01*
G01X576246Y472714D02*
X576476Y472352D01*
X576782Y472146D01*
X577127Y472094D01*
X577434Y472146D01*
X577741Y472404D01*
X577932Y472714D01*
X577971Y473024D01*
X577894Y473386D01*
X577626Y473644D01*
X577357Y473747D01*
X577012D01*
G01X577357D02*
X577587Y473902D01*
X577779Y474161D01*
X577856Y474471D01*
X577779Y474781D01*
X577587Y475039D01*
X577242Y475194D01*
X576897Y475142D01*
X576552Y474936D01*
G01X567022Y484594D02*
Y487694D01*
X567981D01*
X568287Y487539D01*
X568479Y487332D01*
X568556Y486919D01*
X568479Y486506D01*
X568249Y486247D01*
X567981Y486092D01*
X567022D01*
G01X567981D02*
X568556Y484594D01*
G01X570161Y487177D02*
X570391Y487487D01*
X570659Y487642D01*
X570966Y487694D01*
X571349Y487591D01*
X571617Y487332D01*
X571694Y487022D01*
X571656Y486712D01*
X571502Y486454D01*
X570736Y485937D01*
X570391Y485576D01*
X570161Y485059D01*
X570084Y484594D01*
X571694D01*
G01X573146Y485214D02*
X573376Y484852D01*
X573682Y484646D01*
X574027Y484594D01*
X574334Y484646D01*
X574641Y484904D01*
X574832Y485214D01*
X574871Y485524D01*
X574794Y485886D01*
X574526Y486144D01*
X574257Y486247D01*
X573912D01*
G01X574257D02*
X574487Y486402D01*
X574679Y486661D01*
X574756Y486971D01*
X574679Y487281D01*
X574487Y487539D01*
X574142Y487694D01*
X573797Y487642D01*
X573452Y487436D01*
G01X576361Y487177D02*
X576591Y487487D01*
X576859Y487642D01*
X577166Y487694D01*
X577549Y487591D01*
X577817Y487332D01*
X577894Y487022D01*
X577856Y486712D01*
X577702Y486454D01*
X576936Y485937D01*
X576591Y485576D01*
X576361Y485059D01*
X576284Y484594D01*
X577894D01*
G01X563644Y486393D02*
X560544D01*
Y487352D01*
X560699Y487658D01*
X560906Y487850D01*
X561319Y487927D01*
X561732Y487850D01*
X561991Y487620D01*
X562146Y487352D01*
Y486393D01*
G01Y487352D02*
X563644Y487927D01*
G01X561061Y489532D02*
X560751Y489762D01*
X560596Y490030D01*
X560544Y490337D01*
X560647Y490720D01*
X560906Y490988D01*
X561216Y491065D01*
X561526Y491027D01*
X561784Y490873D01*
X562301Y490107D01*
X562662Y489762D01*
X563179Y489532D01*
X563644Y489455D01*
Y491065D01*
G01X564640Y483256D02*
Y473056D01*
G01D02*
X560040D01*
G01D02*
Y483256D01*
G01D02*
X564640D01*
G01X568149Y493158D02*
Y496258D01*
X569108D01*
X569414Y496103D01*
X569606Y495896D01*
X569683Y495483D01*
X569606Y495070D01*
X569376Y494811D01*
X569108Y494656D01*
X568149D01*
G01X569108D02*
X569683Y493158D01*
G01X571288Y495741D02*
X571518Y496051D01*
X571786Y496206D01*
X572093Y496258D01*
X572476Y496155D01*
X572744Y495896D01*
X572821Y495586D01*
X572783Y495276D01*
X572629Y495018D01*
X571863Y494501D01*
X571518Y494140D01*
X571288Y493623D01*
X571211Y493158D01*
X572821D01*
G01X575039D02*
X575116Y493830D01*
X575231Y494398D01*
X575384Y494915D01*
X575576Y495483D01*
X575883Y496258D01*
X574349D01*
G01X577488Y494450D02*
X577756Y494811D01*
X577986Y495018D01*
X578293Y495121D01*
X578561Y495018D01*
X578753Y494811D01*
X578906Y494501D01*
X578944Y494140D01*
X578906Y493830D01*
X578753Y493520D01*
X578523Y493261D01*
X578254Y493158D01*
X577948Y493261D01*
X577679Y493571D01*
X577526Y494036D01*
X577488Y494553D01*
X577564Y495225D01*
X577679Y495586D01*
X577871Y495948D01*
X578139Y496206D01*
X578408Y496258D01*
X578676Y496155D01*
X578868Y495896D01*
G01X568149Y497258D02*
Y500358D01*
X569108D01*
X569414Y500203D01*
X569606Y499996D01*
X569683Y499583D01*
X569606Y499170D01*
X569376Y498911D01*
X569108Y498756D01*
X568149D01*
G01X569108D02*
X569683Y497258D01*
G01X571288Y499841D02*
X571518Y500151D01*
X571786Y500306D01*
X572093Y500358D01*
X572476Y500255D01*
X572744Y499996D01*
X572821Y499686D01*
X572783Y499376D01*
X572629Y499118D01*
X571863Y498601D01*
X571518Y498240D01*
X571288Y497723D01*
X571211Y497258D01*
X572821D01*
G01X575039D02*
X575116Y497930D01*
X575231Y498498D01*
X575384Y499015D01*
X575576Y499583D01*
X575883Y500358D01*
X574349D01*
G01X578139Y497258D02*
X578216Y497930D01*
X578331Y498498D01*
X578484Y499015D01*
X578676Y499583D01*
X578983Y500358D01*
X577449D01*
G01X568149Y501158D02*
Y504258D01*
X569108D01*
X569414Y504103D01*
X569606Y503896D01*
X569683Y503483D01*
X569606Y503070D01*
X569376Y502811D01*
X569108Y502656D01*
X568149D01*
G01X569108D02*
X569683Y501158D01*
G01X571173Y501778D02*
X571403Y501416D01*
X571709Y501210D01*
X572054Y501158D01*
X572361Y501210D01*
X572668Y501468D01*
X572859Y501778D01*
X572898Y502088D01*
X572821Y502450D01*
X572553Y502708D01*
X572284Y502811D01*
X571939D01*
G01X572284D02*
X572514Y502966D01*
X572706Y503225D01*
X572783Y503535D01*
X572706Y503845D01*
X572514Y504103D01*
X572169Y504258D01*
X571824Y504206D01*
X571479Y504000D01*
G01X575116Y504258D02*
X574809Y504155D01*
X574579Y503896D01*
X574426Y503586D01*
X574311Y503173D01*
X574273Y502708D01*
X574311Y502243D01*
X574426Y501830D01*
X574579Y501520D01*
X574809Y501261D01*
X575116Y501158D01*
X575423Y501261D01*
X575653Y501520D01*
X575806Y501830D01*
X575921Y502243D01*
X575959Y502708D01*
X575921Y503173D01*
X575806Y503586D01*
X575653Y503896D01*
X575423Y504155D01*
X575116Y504258D01*
G01X578216Y501158D02*
X578484Y501210D01*
X578791Y501365D01*
X578983Y501623D01*
X579059Y501985D01*
X578983Y502346D01*
X578753Y502656D01*
X578408Y502811D01*
X578024D01*
X577794Y502915D01*
X577603Y503173D01*
X577526Y503535D01*
X577641Y503896D01*
X577909Y504155D01*
X578216Y504258D01*
X578523Y504155D01*
X578791Y503896D01*
X578906Y503535D01*
X578829Y503173D01*
X578638Y502915D01*
X578408Y502811D01*
X578024D01*
X577679Y502656D01*
X577449Y502346D01*
X577373Y501985D01*
X577449Y501623D01*
X577641Y501365D01*
X577948Y501210D01*
X578216Y501158D01*
G01X567022Y488594D02*
Y491694D01*
X567981D01*
X568287Y491539D01*
X568479Y491332D01*
X568556Y490919D01*
X568479Y490506D01*
X568249Y490247D01*
X567981Y490092D01*
X567022D01*
G01X567981D02*
X568556Y488594D01*
G01X570161Y491177D02*
X570391Y491487D01*
X570659Y491642D01*
X570966Y491694D01*
X571349Y491591D01*
X571617Y491332D01*
X571694Y491022D01*
X571656Y490712D01*
X571502Y490454D01*
X570736Y489937D01*
X570391Y489576D01*
X570161Y489059D01*
X570084Y488594D01*
X571694D01*
G01X573146Y489214D02*
X573376Y488852D01*
X573682Y488646D01*
X574027Y488594D01*
X574334Y488646D01*
X574641Y488904D01*
X574832Y489214D01*
X574871Y489524D01*
X574794Y489886D01*
X574526Y490144D01*
X574257Y490247D01*
X573912D01*
G01X574257D02*
X574487Y490402D01*
X574679Y490661D01*
X574756Y490971D01*
X574679Y491281D01*
X574487Y491539D01*
X574142Y491694D01*
X573797Y491642D01*
X573452Y491436D01*
G01X576246Y489214D02*
X576476Y488852D01*
X576782Y488646D01*
X577127Y488594D01*
X577434Y488646D01*
X577741Y488904D01*
X577932Y489214D01*
X577971Y489524D01*
X577894Y489886D01*
X577626Y490144D01*
X577357Y490247D01*
X577012D01*
G01X577357D02*
X577587Y490402D01*
X577779Y490661D01*
X577856Y490971D01*
X577779Y491281D01*
X577587Y491539D01*
X577242Y491694D01*
X576897Y491642D01*
X576552Y491436D01*
G01X569162Y513294D02*
Y516394D01*
X570121D01*
X570427Y516239D01*
X570619Y516032D01*
X570696Y515619D01*
X570619Y515206D01*
X570389Y514947D01*
X570121Y514792D01*
X569162D01*
G01X570121D02*
X570696Y513294D01*
G01X572186Y513914D02*
X572416Y513552D01*
X572722Y513346D01*
X573067Y513294D01*
X573374Y513346D01*
X573681Y513604D01*
X573872Y513914D01*
X573911Y514224D01*
X573834Y514586D01*
X573566Y514844D01*
X573297Y514947D01*
X572952D01*
G01X573297D02*
X573527Y515102D01*
X573719Y515361D01*
X573796Y515671D01*
X573719Y515981D01*
X573527Y516239D01*
X573182Y516394D01*
X572837Y516342D01*
X572492Y516136D01*
G01X576129Y516394D02*
X575822Y516291D01*
X575592Y516032D01*
X575439Y515722D01*
X575324Y515309D01*
X575286Y514844D01*
X575324Y514379D01*
X575439Y513966D01*
X575592Y513656D01*
X575822Y513397D01*
X576129Y513294D01*
X576436Y513397D01*
X576666Y513656D01*
X576819Y513966D01*
X576934Y514379D01*
X576972Y514844D01*
X576934Y515309D01*
X576819Y515722D01*
X576666Y516032D01*
X576436Y516291D01*
X576129Y516394D01*
G01X579152Y513294D02*
X579229Y513966D01*
X579344Y514534D01*
X579497Y515051D01*
X579689Y515619D01*
X579996Y516394D01*
X578462D01*
G01X568149Y505158D02*
Y508258D01*
X569108D01*
X569414Y508103D01*
X569606Y507896D01*
X569683Y507483D01*
X569606Y507070D01*
X569376Y506811D01*
X569108Y506656D01*
X568149D01*
G01X569108D02*
X569683Y505158D01*
G01X571173Y505778D02*
X571403Y505416D01*
X571709Y505210D01*
X572054Y505158D01*
X572361Y505210D01*
X572668Y505468D01*
X572859Y505778D01*
X572898Y506088D01*
X572821Y506450D01*
X572553Y506708D01*
X572284Y506811D01*
X571939D01*
G01X572284D02*
X572514Y506966D01*
X572706Y507225D01*
X572783Y507535D01*
X572706Y507845D01*
X572514Y508103D01*
X572169Y508258D01*
X571824Y508206D01*
X571479Y508000D01*
G01X575116Y508258D02*
X574809Y508155D01*
X574579Y507896D01*
X574426Y507586D01*
X574311Y507173D01*
X574273Y506708D01*
X574311Y506243D01*
X574426Y505830D01*
X574579Y505520D01*
X574809Y505261D01*
X575116Y505158D01*
X575423Y505261D01*
X575653Y505520D01*
X575806Y505830D01*
X575921Y506243D01*
X575959Y506708D01*
X575921Y507173D01*
X575806Y507586D01*
X575653Y507896D01*
X575423Y508155D01*
X575116Y508258D01*
G01X577488Y506450D02*
X577756Y506811D01*
X577986Y507018D01*
X578293Y507121D01*
X578561Y507018D01*
X578753Y506811D01*
X578906Y506501D01*
X578944Y506140D01*
X578906Y505830D01*
X578753Y505520D01*
X578523Y505261D01*
X578254Y505158D01*
X577948Y505261D01*
X577679Y505571D01*
X577526Y506036D01*
X577488Y506553D01*
X577564Y507225D01*
X577679Y507586D01*
X577871Y507948D01*
X578139Y508206D01*
X578408Y508258D01*
X578676Y508155D01*
X578868Y507896D01*
G01X569162Y517794D02*
Y520894D01*
X570121D01*
X570427Y520739D01*
X570619Y520532D01*
X570696Y520119D01*
X570619Y519706D01*
X570389Y519447D01*
X570121Y519292D01*
X569162D01*
G01X570121D02*
X570696Y517794D01*
G01X572301Y520377D02*
X572531Y520687D01*
X572799Y520842D01*
X573106Y520894D01*
X573489Y520791D01*
X573757Y520532D01*
X573834Y520222D01*
X573796Y519912D01*
X573642Y519654D01*
X572876Y519137D01*
X572531Y518776D01*
X572301Y518259D01*
X572224Y517794D01*
X573834D01*
G01X576129D02*
X576397Y517846D01*
X576704Y518001D01*
X576896Y518259D01*
X576972Y518621D01*
X576896Y518982D01*
X576666Y519292D01*
X576321Y519447D01*
X575937D01*
X575707Y519551D01*
X575516Y519809D01*
X575439Y520171D01*
X575554Y520532D01*
X575822Y520791D01*
X576129Y520894D01*
X576436Y520791D01*
X576704Y520532D01*
X576819Y520171D01*
X576742Y519809D01*
X576551Y519551D01*
X576321Y519447D01*
X575937D01*
X575592Y519292D01*
X575362Y518982D01*
X575286Y518621D01*
X575362Y518259D01*
X575554Y518001D01*
X575861Y517846D01*
X576129Y517794D01*
G01X578386Y518259D02*
X578616Y518001D01*
X578884Y517846D01*
X579229Y517794D01*
X579574Y517897D01*
X579842Y518104D01*
X580034Y518466D01*
X580072Y518879D01*
X579996Y519292D01*
X579804Y519551D01*
X579536Y519757D01*
X579267Y519809D01*
X578999Y519757D01*
X578654Y519551D01*
X578769Y520894D01*
X579804D01*
G01X565738Y529925D02*
Y526725D01*
G01X559538Y529925D02*
X565738D01*
G01X559538Y526725D02*
Y529925D01*
G01X565738Y526725D02*
X559538D01*
G01X569162Y522044D02*
Y525144D01*
X570121D01*
X570427Y524989D01*
X570619Y524782D01*
X570696Y524369D01*
X570619Y523956D01*
X570389Y523697D01*
X570121Y523542D01*
X569162D01*
G01X570121D02*
X570696Y522044D01*
G01X572301Y524627D02*
X572531Y524937D01*
X572799Y525092D01*
X573106Y525144D01*
X573489Y525041D01*
X573757Y524782D01*
X573834Y524472D01*
X573796Y524162D01*
X573642Y523904D01*
X572876Y523387D01*
X572531Y523026D01*
X572301Y522509D01*
X572224Y522044D01*
X573834D01*
G01X576052D02*
X576129Y522716D01*
X576244Y523284D01*
X576397Y523801D01*
X576589Y524369D01*
X576896Y525144D01*
X575362D01*
G01X579229Y522044D02*
X579497Y522096D01*
X579804Y522251D01*
X579996Y522509D01*
X580072Y522871D01*
X579996Y523232D01*
X579766Y523542D01*
X579421Y523697D01*
X579037D01*
X578807Y523801D01*
X578616Y524059D01*
X578539Y524421D01*
X578654Y524782D01*
X578922Y525041D01*
X579229Y525144D01*
X579536Y525041D01*
X579804Y524782D01*
X579919Y524421D01*
X579842Y524059D01*
X579651Y523801D01*
X579421Y523697D01*
X579037D01*
X578692Y523542D01*
X578462Y523232D01*
X578386Y522871D01*
X578462Y522509D01*
X578654Y522251D01*
X578961Y522096D01*
X579229Y522044D01*
G01X565738Y533825D02*
Y530625D01*
G01X559538D02*
Y533825D01*
G01X565738Y530625D02*
X559538D01*
G01Y522725D02*
Y525925D01*
G01X565738Y522725D02*
X559538D01*
G01X565738Y525925D02*
Y522725D01*
G01X559538Y525925D02*
X565738D01*
G01X559538Y533825D02*
X565738D01*
G01X567438Y543825D02*
Y547025D01*
G01X573638Y543825D02*
X567438D01*
G01Y547025D02*
X573638D01*
G01Y539225D02*
X567438D01*
G01Y542425D02*
X573638D01*
G01X567438Y539225D02*
Y542425D01*
G01Y550425D02*
Y553625D01*
G01X573638Y550425D02*
X567438D01*
G01Y553625D02*
X573638D01*
G01X573738Y558225D02*
X567538D01*
G01Y561425D02*
X573738D01*
G01X567538Y558225D02*
Y561425D01*
G01X567438Y557525D02*
X573638D01*
G01Y554325D02*
X567438D01*
G01D02*
Y557525D01*
G01Y566125D02*
Y569325D01*
G01X573638Y566125D02*
X567438D01*
G01Y569325D02*
X573638D01*
G01X567438Y570125D02*
Y573325D01*
G01X573638Y570125D02*
X567438D01*
G01Y573325D02*
X573638D01*
G01X566738Y574025D02*
Y577225D01*
G01X572938Y574025D02*
X566738D01*
G01X572938Y577225D02*
Y574025D01*
G01X566738Y577225D02*
X572938D01*
G01X566738Y577925D02*
Y581125D01*
G01X572938Y577925D02*
X566738D01*
G01X572938Y581125D02*
Y577925D01*
G01X558097Y592697D02*
X558257Y592405D01*
X558471Y592239D01*
X558711Y592197D01*
X558924Y592239D01*
X559137Y592447D01*
X559271Y592697D01*
X559297Y592947D01*
X559244Y593239D01*
X559057Y593447D01*
X558871Y593530D01*
X558631D01*
G01X558871D02*
X559031Y593655D01*
X559164Y593864D01*
X559217Y594114D01*
X559164Y594364D01*
X559031Y594572D01*
X558791Y594697D01*
X558551Y594655D01*
X558311Y594489D01*
G01X560377Y594280D02*
X560537Y594530D01*
X560724Y594655D01*
X560937Y594697D01*
X561204Y594614D01*
X561391Y594405D01*
X561444Y594155D01*
X561417Y593905D01*
X561311Y593697D01*
X560777Y593280D01*
X560537Y592989D01*
X560377Y592572D01*
X560324Y592197D01*
X561444D01*
G01X569486Y598316D02*
Y596094D01*
X569639Y595629D01*
X569946Y595319D01*
X570329Y595216D01*
X570712Y595319D01*
X571019Y595629D01*
X571172Y596094D01*
Y598316D01*
G01X573429Y595216D02*
Y598316D01*
X572969Y597696D01*
G01Y595216D02*
X573889D01*
G01X575686Y595836D02*
X575916Y595474D01*
X576222Y595268D01*
X576567Y595216D01*
X576874Y595268D01*
X577181Y595526D01*
X577372Y595836D01*
X577411Y596146D01*
X577334Y596508D01*
X577066Y596766D01*
X576797Y596869D01*
X576452D01*
G01X576797D02*
X577027Y597024D01*
X577219Y597283D01*
X577296Y597593D01*
X577219Y597903D01*
X577027Y598161D01*
X576682Y598316D01*
X576337Y598264D01*
X575992Y598058D01*
G01X566938Y589725D02*
Y592925D01*
G01X573138Y589725D02*
X566938D01*
G01X573138Y592925D02*
Y589725D01*
G01X566938Y592925D02*
X573138D01*
G01X566838Y581925D02*
Y585125D01*
G01X573038Y581925D02*
X566838D01*
G01X573038Y585125D02*
Y581925D01*
G01X566838Y585125D02*
X573038D01*
G01X566738Y581125D02*
X572938D01*
G01X566838Y585825D02*
Y589025D01*
G01X573038Y585825D02*
X566838D01*
G01X573038Y589025D02*
Y585825D01*
G01X566838Y589025D02*
X573038D01*
G01X575199Y598804D02*
X563999D01*
G01D02*
Y618604D01*
G01X566241Y619913D02*
X563707D01*
Y624913D01*
X566241D01*
G01X565227Y622496D02*
X563707D01*
G01X560354Y622362D02*
Y634052D01*
G01X567099Y616204D02*
G02I-1000J0D01*
G01X571399Y618604D02*
X575199D01*
G01X569599Y616804D02*
X571399Y618604D01*
G01X567799D02*
X569599Y616804D01*
G01X563999Y618604D02*
X567799D01*
G01X561212Y625984D02*
Y632184D01*
G01X564412Y625984D02*
X561212D01*
G01X564412Y632184D02*
Y625984D01*
G01X575936Y638860D02*
X575556Y639110D01*
X575113Y639277D01*
X574606D01*
X574036Y639027D01*
X573593Y638610D01*
X573276Y638110D01*
X573023Y637277D01*
X572960Y636527D01*
X573086Y635777D01*
X573276Y635277D01*
X573656Y634777D01*
X574100Y634444D01*
X574543Y634277D01*
X574986D01*
X575430Y634444D01*
X575810Y634694D01*
X576126Y635027D01*
G01X578376Y634277D02*
Y639277D01*
X579896D01*
X580403Y639027D01*
X580783Y638444D01*
X580910Y637777D01*
X580783Y637110D01*
X580466Y636610D01*
X579896Y636360D01*
X578376D01*
G01X583476Y639277D02*
Y634277D01*
X586010D01*
G01X588450D02*
Y639277D01*
X589716D01*
X590223Y639027D01*
X590603Y638694D01*
X590920Y638194D01*
X591173Y637610D01*
X591236Y636777D01*
X591173Y635944D01*
X590920Y635360D01*
X590603Y634860D01*
X590223Y634527D01*
X589716Y634277D01*
X588450D01*
G01X593550Y635277D02*
X593930Y634694D01*
X594436Y634360D01*
X595006Y634277D01*
X595513Y634360D01*
X596020Y634777D01*
X596336Y635277D01*
X596400Y635777D01*
X596273Y636360D01*
X595830Y636777D01*
X595386Y636944D01*
X594816D01*
G01X595386D02*
X595766Y637194D01*
X596083Y637610D01*
X596210Y638110D01*
X596083Y638610D01*
X595766Y639027D01*
X595196Y639277D01*
X594626Y639194D01*
X594056Y638860D01*
G01X563210Y634740D02*
Y634670D01*
G01X567990Y634740D02*
X563210D01*
G01X574793Y640396D02*
X597705D01*
Y632737D01*
X572502D01*
Y640396D01*
X574793D01*
G01X567687Y640701D02*
X567740Y641243D01*
X567820Y641701D01*
X567927Y642118D01*
X568060Y642576D01*
X568273Y643201D01*
X567207D01*
G01X569353Y641076D02*
X569513Y640868D01*
X569700Y640743D01*
X569940Y640701D01*
X570180Y640784D01*
X570367Y640951D01*
X570500Y641243D01*
X570527Y641576D01*
X570473Y641909D01*
X570340Y642118D01*
X570153Y642284D01*
X569967Y642326D01*
X569780Y642284D01*
X569540Y642118D01*
X569620Y643201D01*
X570340D01*
G01X565140Y634356D02*
Y639356D01*
G01X561212Y632184D02*
X564412D01*
G01X575297Y641624D02*
Y648307D01*
X575318D01*
X577511Y646114D01*
X577490Y646093D01*
X572662D01*
X574897Y648328D01*
X575234D01*
G01X566240Y697156D02*
Y648856D01*
G01X570372Y698867D02*
Y701967D01*
X569912Y701347D01*
G01Y698867D02*
X570832D01*
G01X573472Y701967D02*
X573165Y701864D01*
X572935Y701605D01*
X572782Y701295D01*
X572667Y700882D01*
X572629Y700417D01*
X572667Y699952D01*
X572782Y699539D01*
X572935Y699229D01*
X573165Y698970D01*
X573472Y698867D01*
X573779Y698970D01*
X574009Y699229D01*
X574162Y699539D01*
X574277Y699952D01*
X574315Y700417D01*
X574277Y700882D01*
X574162Y701295D01*
X574009Y701605D01*
X573779Y701864D01*
X573472Y701967D01*
G01X576572D02*
X576265Y701864D01*
X576035Y701605D01*
X575882Y701295D01*
X575767Y700882D01*
X575729Y700417D01*
X575767Y699952D01*
X575882Y699539D01*
X576035Y699229D01*
X576265Y698970D01*
X576572Y698867D01*
X576879Y698970D01*
X577109Y699229D01*
X577262Y699539D01*
X577377Y699952D01*
X577415Y700417D01*
X577377Y700882D01*
X577262Y701295D01*
X577109Y701605D01*
X576879Y701864D01*
X576572Y701967D01*
G01X568474Y704910D02*
Y708010D01*
X568014Y707390D01*
G01Y704910D02*
X568934D01*
G01X564940Y698456D02*
X566240Y697156D01*
G01X574704Y708833D02*
X571604D01*
Y709792D01*
X571759Y710098D01*
X571966Y710290D01*
X572379Y710367D01*
X572792Y710290D01*
X573051Y710060D01*
X573206Y709792D01*
Y708833D01*
G01Y709792D02*
X574704Y710367D01*
G01Y712700D02*
X574652Y712968D01*
X574497Y713275D01*
X574239Y713467D01*
X573877Y713543D01*
X573516Y713467D01*
X573206Y713237D01*
X573051Y712892D01*
Y712508D01*
X572947Y712278D01*
X572689Y712087D01*
X572327Y712010D01*
X571966Y712125D01*
X571707Y712393D01*
X571604Y712700D01*
X571707Y713007D01*
X571966Y713275D01*
X572327Y713390D01*
X572689Y713313D01*
X572947Y713122D01*
X573051Y712892D01*
Y712508D01*
X573206Y712163D01*
X573516Y711933D01*
X573877Y711857D01*
X574239Y711933D01*
X574497Y712125D01*
X574652Y712432D01*
X574704Y712700D01*
G01X571604Y715800D02*
X571707Y715493D01*
X571966Y715263D01*
X572276Y715110D01*
X572689Y714995D01*
X573154Y714957D01*
X573619Y714995D01*
X574032Y715110D01*
X574342Y715263D01*
X574601Y715493D01*
X574704Y715800D01*
X574601Y716107D01*
X574342Y716337D01*
X574032Y716490D01*
X573619Y716605D01*
X573154Y716643D01*
X572689Y716605D01*
X572276Y716490D01*
X571966Y716337D01*
X571707Y716107D01*
X571604Y715800D01*
G01X574704Y718823D02*
X574032Y718900D01*
X573464Y719015D01*
X572947Y719168D01*
X572379Y719360D01*
X571604Y719667D01*
Y718133D01*
G01X563474Y717693D02*
X566674D01*
G01X563474Y711493D02*
Y717693D01*
G01X566674Y711493D02*
X563474D01*
G01X566674Y717693D02*
Y711493D01*
G01X566040Y726056D02*
X562840D01*
G01X566040Y732256D02*
Y726056D01*
G01X562840Y732256D02*
X566040D01*
G01X562840Y726056D02*
Y732256D01*
G01X565940Y729156D02*
X562940D01*
G01X570540Y737556D02*
X567340D01*
G01X570540Y743756D02*
Y737556D01*
G01X567340D02*
Y743756D01*
G01X575040Y726056D02*
X571840D01*
G01Y732256D02*
X575040D01*
G01X571840Y726056D02*
Y732256D01*
G01X574940Y729156D02*
X571940D01*
G01X561540Y737556D02*
X558340D01*
G01D02*
Y743756D01*
G01X561540D02*
Y737556D01*
G01X571840D02*
Y743756D01*
G01X575040Y737556D02*
X571840D01*
G01X567340Y732256D02*
X570540D01*
G01X567340Y726056D02*
Y732256D01*
G01X570540Y726056D02*
X567340D01*
G01X570540Y732256D02*
Y726056D01*
G01X562840Y737556D02*
Y743756D01*
G01X566040Y737556D02*
X562840D01*
G01X566040Y743756D02*
Y737556D01*
G01X558340Y732256D02*
X561540D01*
G01X558340Y726056D02*
Y732256D01*
G01X561540Y726056D02*
X558340D01*
G01X561540Y732256D02*
Y726056D01*
G01X560851Y749921D02*
X560696Y749691D01*
X560593Y749423D01*
Y749116D01*
X560748Y748771D01*
X561006Y748503D01*
X561316Y748311D01*
X561833Y748158D01*
X562298Y748120D01*
X562763Y748196D01*
X563073Y748311D01*
X563383Y748541D01*
X563590Y748810D01*
X563693Y749078D01*
Y749346D01*
X563590Y749615D01*
X563435Y749845D01*
X563228Y750036D01*
G01X563693Y752101D02*
X563021Y752178D01*
X562453Y752293D01*
X561936Y752446D01*
X561368Y752638D01*
X560593Y752945D01*
Y751411D01*
G01X562401Y754550D02*
X562040Y754818D01*
X561833Y755048D01*
X561730Y755355D01*
X561833Y755623D01*
X562040Y755815D01*
X562350Y755968D01*
X562711Y756006D01*
X563021Y755968D01*
X563331Y755815D01*
X563590Y755585D01*
X563693Y755316D01*
X563590Y755010D01*
X563280Y754741D01*
X562815Y754588D01*
X562298Y754550D01*
X561626Y754626D01*
X561265Y754741D01*
X560903Y754933D01*
X560645Y755201D01*
X560593Y755470D01*
X560696Y755738D01*
X560955Y755930D01*
G01X561110Y757650D02*
X560800Y757880D01*
X560645Y758148D01*
X560593Y758455D01*
X560696Y758838D01*
X560955Y759106D01*
X561265Y759183D01*
X561575Y759145D01*
X561833Y758991D01*
X562350Y758225D01*
X562711Y757880D01*
X563228Y757650D01*
X563693Y757573D01*
Y759183D01*
G01X567340Y743756D02*
X570540D01*
G01X570440Y740656D02*
X567440D01*
G01X569851Y749921D02*
X569696Y749691D01*
X569593Y749423D01*
Y749116D01*
X569748Y748771D01*
X570006Y748503D01*
X570316Y748311D01*
X570833Y748158D01*
X571298Y748120D01*
X571763Y748196D01*
X572073Y748311D01*
X572383Y748541D01*
X572590Y748810D01*
X572693Y749078D01*
Y749346D01*
X572590Y749615D01*
X572435Y749845D01*
X572228Y750036D01*
G01X572693Y752101D02*
X572021Y752178D01*
X571453Y752293D01*
X570936Y752446D01*
X570368Y752638D01*
X569593Y752945D01*
Y751411D01*
G01X572228Y754435D02*
X572486Y754665D01*
X572641Y754933D01*
X572693Y755278D01*
X572590Y755623D01*
X572383Y755891D01*
X572021Y756083D01*
X571608Y756121D01*
X571195Y756045D01*
X570936Y755853D01*
X570730Y755585D01*
X570678Y755316D01*
X570730Y755048D01*
X570936Y754703D01*
X569593Y754818D01*
Y755853D01*
G01X571401Y757650D02*
X571040Y757918D01*
X570833Y758148D01*
X570730Y758455D01*
X570833Y758723D01*
X571040Y758915D01*
X571350Y759068D01*
X571711Y759106D01*
X572021Y759068D01*
X572331Y758915D01*
X572590Y758685D01*
X572693Y758416D01*
X572590Y758110D01*
X572280Y757841D01*
X571815Y757688D01*
X571298Y757650D01*
X570626Y757726D01*
X570265Y757841D01*
X569903Y758033D01*
X569645Y758301D01*
X569593Y758570D01*
X569696Y758838D01*
X569955Y759030D01*
G01X558340Y743756D02*
X561540D01*
G01X561440Y740656D02*
X558440D01*
G01X571840Y743756D02*
X575040D01*
G01X568227Y748311D02*
X565127D01*
Y749270D01*
X565282Y749576D01*
X565489Y749768D01*
X565902Y749845D01*
X566315Y749768D01*
X566574Y749538D01*
X566729Y749270D01*
Y748311D01*
G01Y749270D02*
X568227Y749845D01*
G01X567865Y751526D02*
X568124Y751795D01*
X568227Y752101D01*
X568124Y752408D01*
X567814Y752676D01*
X567349Y752868D01*
X566884Y752945D01*
X566315D01*
X565850Y752868D01*
X565437Y752676D01*
X565230Y752446D01*
X565127Y752178D01*
X565230Y751871D01*
X565437Y751641D01*
X565747Y751488D01*
X566160Y751411D01*
X566522Y751488D01*
X566884Y751680D01*
X567090Y751910D01*
X567142Y752178D01*
X567039Y752485D01*
X566780Y752715D01*
X566315Y752945D01*
G01X567865Y754626D02*
X568124Y754895D01*
X568227Y755201D01*
X568124Y755508D01*
X567814Y755776D01*
X567349Y755968D01*
X566884Y756045D01*
X566315D01*
X565850Y755968D01*
X565437Y755776D01*
X565230Y755546D01*
X565127Y755278D01*
X565230Y754971D01*
X565437Y754741D01*
X565747Y754588D01*
X566160Y754511D01*
X566522Y754588D01*
X566884Y754780D01*
X567090Y755010D01*
X567142Y755278D01*
X567039Y755585D01*
X566780Y755815D01*
X566315Y756045D01*
G01X566935Y757650D02*
X566574Y757918D01*
X566367Y758148D01*
X566264Y758455D01*
X566367Y758723D01*
X566574Y758915D01*
X566884Y759068D01*
X567245Y759106D01*
X567555Y759068D01*
X567865Y758915D01*
X568124Y758685D01*
X568227Y758416D01*
X568124Y758110D01*
X567814Y757841D01*
X567349Y757688D01*
X566832Y757650D01*
X566160Y757726D01*
X565799Y757841D01*
X565437Y758033D01*
X565179Y758301D01*
X565127Y758570D01*
X565230Y758838D01*
X565489Y759030D01*
G01X562840Y743756D02*
X566040D01*
G01X563935Y764380D02*
X563780Y764150D01*
X563677Y763882D01*
Y763575D01*
X563832Y763230D01*
X564090Y762962D01*
X564400Y762770D01*
X564917Y762617D01*
X565382Y762579D01*
X565847Y762655D01*
X566157Y762770D01*
X566467Y763000D01*
X566674Y763269D01*
X566777Y763537D01*
Y763805D01*
X566674Y764074D01*
X566519Y764304D01*
X566312Y764495D01*
G01X566777Y766560D02*
X566105Y766637D01*
X565537Y766752D01*
X565020Y766905D01*
X564452Y767097D01*
X563677Y767404D01*
Y765870D01*
G01X566312Y768894D02*
X566570Y769124D01*
X566725Y769392D01*
X566777Y769737D01*
X566674Y770082D01*
X566467Y770350D01*
X566105Y770542D01*
X565692Y770580D01*
X565279Y770504D01*
X565020Y770312D01*
X564814Y770044D01*
X564762Y769775D01*
X564814Y769507D01*
X565020Y769162D01*
X563677Y769277D01*
Y770312D01*
G01X566415Y772185D02*
X566674Y772454D01*
X566777Y772760D01*
X566674Y773067D01*
X566364Y773335D01*
X565899Y773527D01*
X565434Y773604D01*
X564865D01*
X564400Y773527D01*
X563987Y773335D01*
X563780Y773105D01*
X563677Y772837D01*
X563780Y772530D01*
X563987Y772300D01*
X564297Y772147D01*
X564710Y772070D01*
X565072Y772147D01*
X565434Y772339D01*
X565640Y772569D01*
X565692Y772837D01*
X565589Y773144D01*
X565330Y773374D01*
X564865Y773604D01*
G01X571935Y764380D02*
X571780Y764150D01*
X571677Y763882D01*
Y763575D01*
X571832Y763230D01*
X572090Y762962D01*
X572400Y762770D01*
X572917Y762617D01*
X573382Y762579D01*
X573847Y762655D01*
X574157Y762770D01*
X574467Y763000D01*
X574674Y763269D01*
X574777Y763537D01*
Y763805D01*
X574674Y764074D01*
X574519Y764304D01*
X574312Y764495D01*
G01X574777Y766560D02*
X574105Y766637D01*
X573537Y766752D01*
X573020Y766905D01*
X572452Y767097D01*
X571677Y767404D01*
Y765870D01*
G01X574312Y768894D02*
X574570Y769124D01*
X574725Y769392D01*
X574777Y769737D01*
X574674Y770082D01*
X574467Y770350D01*
X574105Y770542D01*
X573692Y770580D01*
X573279Y770504D01*
X573020Y770312D01*
X572814Y770044D01*
X572762Y769775D01*
X572814Y769507D01*
X573020Y769162D01*
X571677Y769277D01*
Y770312D01*
G01X574157Y771994D02*
X574519Y772224D01*
X574725Y772530D01*
X574777Y772875D01*
X574725Y773182D01*
X574467Y773489D01*
X574157Y773680D01*
X573847Y773719D01*
X573485Y773642D01*
X573227Y773374D01*
X573124Y773105D01*
Y772760D01*
G01Y773105D02*
X572969Y773335D01*
X572710Y773527D01*
X572400Y773604D01*
X572090Y773527D01*
X571832Y773335D01*
X571677Y772990D01*
X571729Y772645D01*
X571935Y772300D01*
G01X570777Y762770D02*
X567677D01*
Y763729D01*
X567832Y764035D01*
X568039Y764227D01*
X568452Y764304D01*
X568865Y764227D01*
X569124Y763997D01*
X569279Y763729D01*
Y762770D01*
G01Y763729D02*
X570777Y764304D01*
G01X570415Y765985D02*
X570674Y766254D01*
X570777Y766560D01*
X570674Y766867D01*
X570364Y767135D01*
X569899Y767327D01*
X569434Y767404D01*
X568865D01*
X568400Y767327D01*
X567987Y767135D01*
X567780Y766905D01*
X567677Y766637D01*
X567780Y766330D01*
X567987Y766100D01*
X568297Y765947D01*
X568710Y765870D01*
X569072Y765947D01*
X569434Y766139D01*
X569640Y766369D01*
X569692Y766637D01*
X569589Y766944D01*
X569330Y767174D01*
X568865Y767404D01*
G01X570415Y769085D02*
X570674Y769354D01*
X570777Y769660D01*
X570674Y769967D01*
X570364Y770235D01*
X569899Y770427D01*
X569434Y770504D01*
X568865D01*
X568400Y770427D01*
X567987Y770235D01*
X567780Y770005D01*
X567677Y769737D01*
X567780Y769430D01*
X567987Y769200D01*
X568297Y769047D01*
X568710Y768970D01*
X569072Y769047D01*
X569434Y769239D01*
X569640Y769469D01*
X569692Y769737D01*
X569589Y770044D01*
X569330Y770274D01*
X568865Y770504D01*
G01X570157Y771994D02*
X570519Y772224D01*
X570725Y772530D01*
X570777Y772875D01*
X570725Y773182D01*
X570467Y773489D01*
X570157Y773680D01*
X569847Y773719D01*
X569485Y773642D01*
X569227Y773374D01*
X569124Y773105D01*
Y772760D01*
G01Y773105D02*
X568969Y773335D01*
X568710Y773527D01*
X568400Y773604D01*
X568090Y773527D01*
X567832Y773335D01*
X567677Y772990D01*
X567729Y772645D01*
X567935Y772300D01*
G01X562813Y762770D02*
X559713D01*
Y763729D01*
X559868Y764035D01*
X560075Y764227D01*
X560488Y764304D01*
X560901Y764227D01*
X561160Y763997D01*
X561315Y763729D01*
Y762770D01*
G01Y763729D02*
X562813Y764304D01*
G01X562451Y765985D02*
X562710Y766254D01*
X562813Y766560D01*
X562710Y766867D01*
X562400Y767135D01*
X561935Y767327D01*
X561470Y767404D01*
X560901D01*
X560436Y767327D01*
X560023Y767135D01*
X559816Y766905D01*
X559713Y766637D01*
X559816Y766330D01*
X560023Y766100D01*
X560333Y765947D01*
X560746Y765870D01*
X561108Y765947D01*
X561470Y766139D01*
X561676Y766369D01*
X561728Y766637D01*
X561625Y766944D01*
X561366Y767174D01*
X560901Y767404D01*
G01X562451Y769085D02*
X562710Y769354D01*
X562813Y769660D01*
X562710Y769967D01*
X562400Y770235D01*
X561935Y770427D01*
X561470Y770504D01*
X560901D01*
X560436Y770427D01*
X560023Y770235D01*
X559816Y770005D01*
X559713Y769737D01*
X559816Y769430D01*
X560023Y769200D01*
X560333Y769047D01*
X560746Y768970D01*
X561108Y769047D01*
X561470Y769239D01*
X561676Y769469D01*
X561728Y769737D01*
X561625Y770044D01*
X561366Y770274D01*
X560901Y770504D01*
G01X562451Y772185D02*
X562710Y772454D01*
X562813Y772760D01*
X562710Y773067D01*
X562400Y773335D01*
X561935Y773527D01*
X561470Y773604D01*
X560901D01*
X560436Y773527D01*
X560023Y773335D01*
X559816Y773105D01*
X559713Y772837D01*
X559816Y772530D01*
X560023Y772300D01*
X560333Y772147D01*
X560746Y772070D01*
X561108Y772147D01*
X561470Y772339D01*
X561676Y772569D01*
X561728Y772837D01*
X561625Y773144D01*
X561366Y773374D01*
X560901Y773604D01*
G01X578440Y58670D02*
Y59240D01*
G01X575186Y61364D02*
X575031Y61134D01*
X574928Y60866D01*
Y60559D01*
X575083Y60214D01*
X575341Y59946D01*
X575651Y59754D01*
X576168Y59601D01*
X576633Y59563D01*
X577098Y59639D01*
X577408Y59754D01*
X577718Y59984D01*
X577925Y60253D01*
X578028Y60521D01*
Y60789D01*
X577925Y61058D01*
X577770Y61288D01*
X577563Y61479D01*
G01X578028Y64081D02*
X574928D01*
X577150Y62663D01*
Y64579D01*
G01X578028Y66721D02*
X577976Y66989D01*
X577821Y67296D01*
X577563Y67488D01*
X577201Y67564D01*
X576840Y67488D01*
X576530Y67258D01*
X576375Y66913D01*
Y66529D01*
X576271Y66299D01*
X576013Y66108D01*
X575651Y66031D01*
X575290Y66146D01*
X575031Y66414D01*
X574928Y66721D01*
X575031Y67028D01*
X575290Y67296D01*
X575651Y67411D01*
X576013Y67334D01*
X576271Y67143D01*
X576375Y66913D01*
Y66529D01*
X576530Y66184D01*
X576840Y65954D01*
X577201Y65878D01*
X577563Y65954D01*
X577821Y66146D01*
X577976Y66453D01*
X578028Y66721D01*
G01X577408Y68978D02*
X577770Y69208D01*
X577976Y69514D01*
X578028Y69859D01*
X577976Y70166D01*
X577718Y70473D01*
X577408Y70664D01*
X577098Y70703D01*
X576736Y70626D01*
X576478Y70358D01*
X576375Y70089D01*
Y69744D01*
G01Y70089D02*
X576220Y70319D01*
X575961Y70511D01*
X575651Y70588D01*
X575341Y70511D01*
X575083Y70319D01*
X574928Y69974D01*
X574980Y69629D01*
X575186Y69284D01*
G01X585717Y58183D02*
Y61283D01*
X584299Y59061D01*
X586215D01*
G01X578190Y74730D02*
Y72870D01*
G01X595724Y63261D02*
X581157D01*
G01X587456Y61293D02*
X597692D01*
G01X581157Y71578D02*
Y98695D01*
G01X579188Y100663D02*
Y61293D01*
G01X581157Y63261D02*
Y66778D01*
G01X579188Y61293D02*
X587456D01*
G01X585717Y111052D02*
X585487Y111207D01*
X585219Y111310D01*
X584912D01*
X584567Y111155D01*
X584299Y110897D01*
X584107Y110587D01*
X583954Y110070D01*
X583916Y109605D01*
X583992Y109140D01*
X584107Y108830D01*
X584337Y108520D01*
X584606Y108313D01*
X584874Y108210D01*
X585142D01*
X585411Y108313D01*
X585641Y108468D01*
X585832Y108675D01*
G01X587131D02*
X587361Y108417D01*
X587629Y108262D01*
X587974Y108210D01*
X588319Y108313D01*
X588587Y108520D01*
X588779Y108882D01*
X588817Y109295D01*
X588741Y109708D01*
X588549Y109967D01*
X588281Y110173D01*
X588012Y110225D01*
X587744Y110173D01*
X587399Y109967D01*
X587514Y111310D01*
X588549D01*
G01X590231Y108830D02*
X590461Y108468D01*
X590767Y108262D01*
X591112Y108210D01*
X591419Y108262D01*
X591726Y108520D01*
X591917Y108830D01*
X591956Y109140D01*
X591879Y109502D01*
X591611Y109760D01*
X591342Y109863D01*
X590997D01*
G01X591342D02*
X591572Y110018D01*
X591764Y110277D01*
X591841Y110587D01*
X591764Y110897D01*
X591572Y111155D01*
X591227Y111310D01*
X590882Y111258D01*
X590537Y111052D01*
G01X594174Y108210D02*
Y111310D01*
X593714Y110690D01*
G01Y108210D02*
X594634D01*
G01X577038Y104723D02*
Y101523D01*
G01X574288D02*
Y104723D01*
G01X577316Y96893D02*
Y99993D01*
X576856Y99373D01*
G01Y96893D02*
X577776D01*
G01X581157Y98695D02*
X595724D01*
G01X597692Y100663D02*
X579188D01*
G01X591718Y116132D02*
X585518D01*
G01D02*
Y119332D01*
G01D02*
X591718D01*
G01X588618Y119232D02*
Y116232D01*
G01X585717Y114948D02*
X585487Y115103D01*
X585219Y115206D01*
X584912D01*
X584567Y115051D01*
X584299Y114793D01*
X584107Y114483D01*
X583954Y113966D01*
X583916Y113501D01*
X583992Y113036D01*
X584107Y112726D01*
X584337Y112416D01*
X584606Y112209D01*
X584874Y112106D01*
X585142D01*
X585411Y112209D01*
X585641Y112364D01*
X585832Y112571D01*
G01X587131D02*
X587361Y112313D01*
X587629Y112158D01*
X587974Y112106D01*
X588319Y112209D01*
X588587Y112416D01*
X588779Y112778D01*
X588817Y113191D01*
X588741Y113604D01*
X588549Y113863D01*
X588281Y114069D01*
X588012Y114121D01*
X587744Y114069D01*
X587399Y113863D01*
X587514Y115206D01*
X588549D01*
G01X590231Y112726D02*
X590461Y112364D01*
X590767Y112158D01*
X591112Y112106D01*
X591419Y112158D01*
X591726Y112416D01*
X591917Y112726D01*
X591956Y113036D01*
X591879Y113398D01*
X591611Y113656D01*
X591342Y113759D01*
X590997D01*
G01X591342D02*
X591572Y113914D01*
X591764Y114173D01*
X591841Y114483D01*
X591764Y114793D01*
X591572Y115051D01*
X591227Y115206D01*
X590882Y115154D01*
X590537Y114948D01*
G01X594174Y115206D02*
X593867Y115103D01*
X593637Y114844D01*
X593484Y114534D01*
X593369Y114121D01*
X593331Y113656D01*
X593369Y113191D01*
X593484Y112778D01*
X593637Y112468D01*
X593867Y112209D01*
X594174Y112106D01*
X594481Y112209D01*
X594711Y112468D01*
X594864Y112778D01*
X594979Y113191D01*
X595017Y113656D01*
X594979Y114121D01*
X594864Y114534D01*
X594711Y114844D01*
X594481Y115103D01*
X594174Y115206D01*
G01X585790Y123436D02*
X591990D01*
G01Y120236D02*
X585790D01*
G01D02*
Y123436D01*
G01X588890Y120336D02*
Y123336D01*
G01X577260Y131675D02*
X580260D01*
G01X591718Y130632D02*
X585518D01*
G01D02*
Y133832D01*
G01D02*
X591718D01*
G01Y126632D02*
X585518D01*
G01D02*
Y129832D01*
G01D02*
X591718D01*
G01X577205Y141525D02*
X583205D01*
G01X577105Y151125D02*
X580105D01*
G01X589242Y154274D02*
Y160474D01*
G01X592442Y154274D02*
X589242D01*
G01X585242D02*
Y160474D01*
G01X588442D02*
Y154274D01*
G01D02*
X585242D01*
G01X584357Y145425D02*
Y148525D01*
X585316D01*
X585622Y148370D01*
X585814Y148163D01*
X585891Y147750D01*
X585814Y147337D01*
X585584Y147078D01*
X585316Y146923D01*
X584357D01*
G01X585316D02*
X585891Y145425D01*
G01X587496Y146717D02*
X587764Y147078D01*
X587994Y147285D01*
X588301Y147388D01*
X588569Y147285D01*
X588761Y147078D01*
X588914Y146768D01*
X588952Y146407D01*
X588914Y146097D01*
X588761Y145787D01*
X588531Y145528D01*
X588262Y145425D01*
X587956Y145528D01*
X587687Y145838D01*
X587534Y146303D01*
X587496Y146820D01*
X587572Y147492D01*
X587687Y147853D01*
X587879Y148215D01*
X588147Y148473D01*
X588416Y148525D01*
X588684Y148422D01*
X588876Y148163D01*
G01X590481Y145890D02*
X590711Y145632D01*
X590979Y145477D01*
X591324Y145425D01*
X591669Y145528D01*
X591937Y145735D01*
X592129Y146097D01*
X592167Y146510D01*
X592091Y146923D01*
X591899Y147182D01*
X591631Y147388D01*
X591362Y147440D01*
X591094Y147388D01*
X590749Y147182D01*
X590864Y148525D01*
X591899D01*
G01X594424D02*
X594117Y148422D01*
X593887Y148163D01*
X593734Y147853D01*
X593619Y147440D01*
X593581Y146975D01*
X593619Y146510D01*
X593734Y146097D01*
X593887Y145787D01*
X594117Y145528D01*
X594424Y145425D01*
X594731Y145528D01*
X594961Y145787D01*
X595114Y146097D01*
X595229Y146510D01*
X595267Y146975D01*
X595229Y147440D01*
X595114Y147853D01*
X594961Y148163D01*
X594731Y148422D01*
X594424Y148525D01*
G01X584357Y141425D02*
Y144525D01*
X585316D01*
X585622Y144370D01*
X585814Y144163D01*
X585891Y143750D01*
X585814Y143337D01*
X585584Y143078D01*
X585316Y142923D01*
X584357D01*
G01X585316D02*
X585891Y141425D01*
G01X587496Y142717D02*
X587764Y143078D01*
X587994Y143285D01*
X588301Y143388D01*
X588569Y143285D01*
X588761Y143078D01*
X588914Y142768D01*
X588952Y142407D01*
X588914Y142097D01*
X588761Y141787D01*
X588531Y141528D01*
X588262Y141425D01*
X587956Y141528D01*
X587687Y141838D01*
X587534Y142303D01*
X587496Y142820D01*
X587572Y143492D01*
X587687Y143853D01*
X587879Y144215D01*
X588147Y144473D01*
X588416Y144525D01*
X588684Y144422D01*
X588876Y144163D01*
G01X591784Y141425D02*
Y144525D01*
X590366Y142303D01*
X592282D01*
G01X593772Y141787D02*
X594041Y141528D01*
X594347Y141425D01*
X594654Y141528D01*
X594922Y141838D01*
X595114Y142303D01*
X595191Y142768D01*
Y143337D01*
X595114Y143802D01*
X594922Y144215D01*
X594692Y144422D01*
X594424Y144525D01*
X594117Y144422D01*
X593887Y144215D01*
X593734Y143905D01*
X593657Y143492D01*
X593734Y143130D01*
X593926Y142768D01*
X594156Y142562D01*
X594424Y142510D01*
X594731Y142613D01*
X594961Y142872D01*
X595191Y143337D01*
G01X577205Y170925D02*
X580205D01*
G01X577205Y161125D02*
X583205D01*
G01X592369Y161786D02*
X589169D01*
G01D02*
Y167986D01*
G01D02*
X592369D01*
G01X589242Y160474D02*
X592442D01*
G01X588369Y167986D02*
Y161786D01*
G01D02*
X585169D01*
G01D02*
Y167986D01*
G01D02*
X588369D01*
G01X591336Y170306D02*
X585136D01*
G01D02*
Y173506D01*
G01X585242Y160474D02*
X588442D01*
G01X585061Y181555D02*
X591261D01*
G01Y178355D02*
X585061D01*
G01D02*
Y181555D01*
G01X579419Y186173D02*
Y189273D01*
X580378D01*
X580684Y189118D01*
X580876Y188911D01*
X580953Y188498D01*
X580876Y188085D01*
X580646Y187826D01*
X580378Y187671D01*
X579419D01*
G01X580378D02*
X580953Y186173D01*
G01X583286D02*
Y189273D01*
X582826Y188653D01*
G01Y186173D02*
X583746D01*
G01X586386Y189273D02*
X586079Y189170D01*
X585849Y188911D01*
X585696Y188601D01*
X585581Y188188D01*
X585543Y187723D01*
X585581Y187258D01*
X585696Y186845D01*
X585849Y186535D01*
X586079Y186276D01*
X586386Y186173D01*
X586693Y186276D01*
X586923Y186535D01*
X587076Y186845D01*
X587191Y187258D01*
X587229Y187723D01*
X587191Y188188D01*
X587076Y188601D01*
X586923Y188911D01*
X586693Y189170D01*
X586386Y189273D01*
G01X589486Y186173D02*
Y189273D01*
X589026Y188653D01*
G01Y186173D02*
X589946D01*
G01X592586Y189273D02*
X592279Y189170D01*
X592049Y188911D01*
X591896Y188601D01*
X591781Y188188D01*
X591743Y187723D01*
X591781Y187258D01*
X591896Y186845D01*
X592049Y186535D01*
X592279Y186276D01*
X592586Y186173D01*
X592893Y186276D01*
X593123Y186535D01*
X593276Y186845D01*
X593391Y187258D01*
X593429Y187723D01*
X593391Y188188D01*
X593276Y188601D01*
X593123Y188911D01*
X592893Y189170D01*
X592586Y189273D01*
G01X585136Y177506D02*
X591336D01*
G01Y174306D02*
X585136D01*
G01D02*
Y177506D01*
G01X579419Y182173D02*
Y185273D01*
X580378D01*
X580684Y185118D01*
X580876Y184911D01*
X580953Y184498D01*
X580876Y184085D01*
X580646Y183826D01*
X580378Y183671D01*
X579419D01*
G01X580378D02*
X580953Y182173D01*
G01X583286D02*
Y185273D01*
X582826Y184653D01*
G01Y182173D02*
X583746D01*
G01X586386Y185273D02*
X586079Y185170D01*
X585849Y184911D01*
X585696Y184601D01*
X585581Y184188D01*
X585543Y183723D01*
X585581Y183258D01*
X585696Y182845D01*
X585849Y182535D01*
X586079Y182276D01*
X586386Y182173D01*
X586693Y182276D01*
X586923Y182535D01*
X587076Y182845D01*
X587191Y183258D01*
X587229Y183723D01*
X587191Y184188D01*
X587076Y184601D01*
X586923Y184911D01*
X586693Y185170D01*
X586386Y185273D01*
G01X589486D02*
X589179Y185170D01*
X588949Y184911D01*
X588796Y184601D01*
X588681Y184188D01*
X588643Y183723D01*
X588681Y183258D01*
X588796Y182845D01*
X588949Y182535D01*
X589179Y182276D01*
X589486Y182173D01*
X589793Y182276D01*
X590023Y182535D01*
X590176Y182845D01*
X590291Y183258D01*
X590329Y183723D01*
X590291Y184188D01*
X590176Y184601D01*
X590023Y184911D01*
X589793Y185170D01*
X589486Y185273D01*
G01X591934Y182535D02*
X592203Y182276D01*
X592509Y182173D01*
X592816Y182276D01*
X593084Y182586D01*
X593276Y183051D01*
X593353Y183516D01*
Y184085D01*
X593276Y184550D01*
X593084Y184963D01*
X592854Y185170D01*
X592586Y185273D01*
X592279Y185170D01*
X592049Y184963D01*
X591896Y184653D01*
X591819Y184240D01*
X591896Y183878D01*
X592088Y183516D01*
X592318Y183310D01*
X592586Y183258D01*
X592893Y183361D01*
X593123Y183620D01*
X593353Y184085D01*
G01X585136Y173506D02*
X591336D01*
G01X588998Y200782D02*
Y206982D01*
G01X592198Y200782D02*
X588998D01*
G01X583505Y199206D02*
Y209406D01*
G01X588105Y199206D02*
X583505D01*
G01X588105Y209406D02*
Y199206D01*
G01X579344Y190222D02*
Y193322D01*
X580303D01*
X580609Y193167D01*
X580801Y192960D01*
X580878Y192547D01*
X580801Y192134D01*
X580571Y191875D01*
X580303Y191720D01*
X579344D01*
G01X580303D02*
X580878Y190222D01*
G01X582483Y191514D02*
X582751Y191875D01*
X582981Y192082D01*
X583288Y192185D01*
X583556Y192082D01*
X583748Y191875D01*
X583901Y191565D01*
X583939Y191204D01*
X583901Y190894D01*
X583748Y190584D01*
X583518Y190325D01*
X583249Y190222D01*
X582943Y190325D01*
X582674Y190635D01*
X582521Y191100D01*
X582483Y191617D01*
X582559Y192289D01*
X582674Y192650D01*
X582866Y193012D01*
X583134Y193270D01*
X583403Y193322D01*
X583671Y193219D01*
X583863Y192960D01*
G01X585583Y192805D02*
X585813Y193115D01*
X586081Y193270D01*
X586388Y193322D01*
X586771Y193219D01*
X587039Y192960D01*
X587116Y192650D01*
X587078Y192340D01*
X586924Y192082D01*
X586158Y191565D01*
X585813Y191204D01*
X585583Y190687D01*
X585506Y190222D01*
X587116D01*
G01X588683Y191514D02*
X588951Y191875D01*
X589181Y192082D01*
X589488Y192185D01*
X589756Y192082D01*
X589948Y191875D01*
X590101Y191565D01*
X590139Y191204D01*
X590101Y190894D01*
X589948Y190584D01*
X589718Y190325D01*
X589449Y190222D01*
X589143Y190325D01*
X588874Y190635D01*
X588721Y191100D01*
X588683Y191617D01*
X588759Y192289D01*
X588874Y192650D01*
X589066Y193012D01*
X589334Y193270D01*
X589603Y193322D01*
X589871Y193219D01*
X590063Y192960D01*
G01X582575Y195931D02*
X575775D01*
G01D02*
Y210931D01*
G01X582575D02*
Y195931D01*
G01X574575Y210931D02*
Y195931D01*
G01X588998Y206982D02*
X592198D01*
G01X592098Y203882D02*
X589098D01*
G01X583505Y204306D02*
X588105D01*
G01X583505Y209406D02*
X588105D01*
G01X575775Y210931D02*
X582575D01*
G01X586900Y229440D02*
X589660D01*
G01X586983Y232105D02*
Y234605D01*
X586663Y234105D01*
G01Y232105D02*
X587303D01*
G01X588730Y232397D02*
X588916Y232188D01*
X589130Y232105D01*
X589343Y232188D01*
X589530Y232438D01*
X589663Y232813D01*
X589716Y233188D01*
Y233647D01*
X589663Y234022D01*
X589530Y234355D01*
X589370Y234522D01*
X589183Y234605D01*
X588970Y234522D01*
X588810Y234355D01*
X588703Y234105D01*
X588650Y233772D01*
X588703Y233480D01*
X588836Y233188D01*
X588996Y233022D01*
X589183Y232980D01*
X589396Y233063D01*
X589556Y233272D01*
X589716Y233647D01*
G01X579232Y230732D02*
Y232732D01*
G01X589307Y228493D02*
Y222293D01*
G01D02*
X586107D01*
G01D02*
Y228493D01*
G01D02*
X589307D01*
G01X581307D02*
Y222293D01*
G01D02*
X578107D01*
G01D02*
Y228493D01*
G01D02*
X581307D01*
G01X585307D02*
Y222293D01*
G01D02*
X582107D01*
G01D02*
Y228493D01*
G01D02*
X585307D01*
G01X586403Y235661D02*
X589097D01*
G01D02*
Y238355D01*
G01X586506Y272432D02*
X586666Y272140D01*
X586880Y271974D01*
X587120Y271932D01*
X587333Y271974D01*
X587546Y272182D01*
X587680Y272432D01*
X587706Y272682D01*
X587653Y272974D01*
X587466Y273182D01*
X587280Y273265D01*
X587040D01*
G01X587280D02*
X587440Y273390D01*
X587573Y273599D01*
X587626Y273849D01*
X587573Y274099D01*
X587440Y274307D01*
X587200Y274432D01*
X586960Y274390D01*
X586720Y274224D01*
G01X588840Y272224D02*
X589026Y272015D01*
X589240Y271932D01*
X589453Y272015D01*
X589640Y272265D01*
X589773Y272640D01*
X589826Y273015D01*
Y273474D01*
X589773Y273849D01*
X589640Y274182D01*
X589480Y274349D01*
X589293Y274432D01*
X589080Y274349D01*
X588920Y274182D01*
X588813Y273932D01*
X588760Y273599D01*
X588813Y273307D01*
X588946Y273015D01*
X589106Y272849D01*
X589293Y272807D01*
X589506Y272890D01*
X589666Y273099D01*
X589826Y273474D01*
G01X583969Y274042D02*
Y278042D01*
G01X576135Y274131D02*
Y276131D01*
G01X589097Y268401D02*
Y271095D01*
G01D02*
X586403D01*
G01X590607Y291093D02*
X587607D01*
G01X587507Y287993D02*
Y294193D01*
G01D02*
X590707D01*
G01Y287993D02*
X587507D01*
G01X584033Y449676D02*
X583653Y449926D01*
X583210Y450093D01*
X582703D01*
X582133Y449843D01*
X581690Y449426D01*
X581373Y448926D01*
X581120Y448093D01*
X581057Y447343D01*
X581183Y446593D01*
X581373Y446093D01*
X581753Y445593D01*
X582197Y445260D01*
X582640Y445093D01*
X583083D01*
X583527Y445260D01*
X583907Y445510D01*
X584223Y445843D01*
G01X586270Y452010D02*
Y443130D01*
G01X579650Y452010D02*
X586270D01*
G01X579510Y443160D02*
Y481289D01*
G01X620520Y443160D02*
X579510D01*
G01X583707Y466569D02*
X580607D01*
Y467528D01*
X580762Y467834D01*
X580969Y468026D01*
X581382Y468103D01*
X581795Y468026D01*
X582054Y467796D01*
X582209Y467528D01*
Y466569D01*
G01Y467528D02*
X583707Y468103D01*
G01Y470436D02*
X580607D01*
X581227Y469976D01*
G01X583707D02*
Y470896D01*
G01X580607Y473536D02*
X580710Y473229D01*
X580969Y472999D01*
X581279Y472846D01*
X581692Y472731D01*
X582157Y472693D01*
X582622Y472731D01*
X583035Y472846D01*
X583345Y472999D01*
X583604Y473229D01*
X583707Y473536D01*
X583604Y473843D01*
X583345Y474073D01*
X583035Y474226D01*
X582622Y474341D01*
X582157Y474379D01*
X581692Y474341D01*
X581279Y474226D01*
X580969Y474073D01*
X580710Y473843D01*
X580607Y473536D01*
G01X583242Y475793D02*
X583500Y476023D01*
X583655Y476291D01*
X583707Y476636D01*
X583604Y476981D01*
X583397Y477249D01*
X583035Y477441D01*
X582622Y477479D01*
X582209Y477403D01*
X581950Y477211D01*
X581744Y476943D01*
X581692Y476674D01*
X581744Y476406D01*
X581950Y476061D01*
X580607Y476176D01*
Y477211D01*
G01X583707Y479736D02*
X583655Y480004D01*
X583500Y480311D01*
X583242Y480503D01*
X582880Y480579D01*
X582519Y480503D01*
X582209Y480273D01*
X582054Y479928D01*
Y479544D01*
X581950Y479314D01*
X581692Y479123D01*
X581330Y479046D01*
X580969Y479161D01*
X580710Y479429D01*
X580607Y479736D01*
X580710Y480043D01*
X580969Y480311D01*
X581330Y480426D01*
X581692Y480349D01*
X581950Y480158D01*
X582054Y479928D01*
Y479544D01*
X582209Y479199D01*
X582519Y478969D01*
X582880Y478893D01*
X583242Y478969D01*
X583500Y479161D01*
X583655Y479468D01*
X583707Y479736D01*
G01X592047Y466446D02*
X588947D01*
Y467405D01*
X589102Y467711D01*
X589309Y467903D01*
X589722Y467980D01*
X590135Y467903D01*
X590394Y467673D01*
X590549Y467405D01*
Y466446D01*
G01Y467405D02*
X592047Y467980D01*
G01Y470313D02*
X591995Y470581D01*
X591840Y470888D01*
X591582Y471080D01*
X591220Y471156D01*
X590859Y471080D01*
X590549Y470850D01*
X590394Y470505D01*
Y470121D01*
X590290Y469891D01*
X590032Y469700D01*
X589670Y469623D01*
X589309Y469738D01*
X589050Y470006D01*
X588947Y470313D01*
X589050Y470620D01*
X589309Y470888D01*
X589670Y471003D01*
X590032Y470926D01*
X590290Y470735D01*
X590394Y470505D01*
Y470121D01*
X590549Y469776D01*
X590859Y469546D01*
X591220Y469470D01*
X591582Y469546D01*
X591840Y469738D01*
X591995Y470045D01*
X592047Y470313D01*
G01X588947Y473413D02*
X589050Y473106D01*
X589309Y472876D01*
X589619Y472723D01*
X590032Y472608D01*
X590497Y472570D01*
X590962Y472608D01*
X591375Y472723D01*
X591685Y472876D01*
X591944Y473106D01*
X592047Y473413D01*
X591944Y473720D01*
X591685Y473950D01*
X591375Y474103D01*
X590962Y474218D01*
X590497Y474256D01*
X590032Y474218D01*
X589619Y474103D01*
X589309Y473950D01*
X589050Y473720D01*
X588947Y473413D01*
G01X591582Y475670D02*
X591840Y475900D01*
X591995Y476168D01*
X592047Y476513D01*
X591944Y476858D01*
X591737Y477126D01*
X591375Y477318D01*
X590962Y477356D01*
X590549Y477280D01*
X590290Y477088D01*
X590084Y476820D01*
X590032Y476551D01*
X590084Y476283D01*
X590290Y475938D01*
X588947Y476053D01*
Y477088D01*
G01X587707Y466569D02*
X584607D01*
Y467528D01*
X584762Y467834D01*
X584969Y468026D01*
X585382Y468103D01*
X585795Y468026D01*
X586054Y467796D01*
X586209Y467528D01*
Y466569D01*
G01Y467528D02*
X587707Y468103D01*
G01Y470436D02*
X584607D01*
X585227Y469976D01*
G01X587707D02*
Y470896D01*
G01X584607Y473536D02*
X584710Y473229D01*
X584969Y472999D01*
X585279Y472846D01*
X585692Y472731D01*
X586157Y472693D01*
X586622Y472731D01*
X587035Y472846D01*
X587345Y472999D01*
X587604Y473229D01*
X587707Y473536D01*
X587604Y473843D01*
X587345Y474073D01*
X587035Y474226D01*
X586622Y474341D01*
X586157Y474379D01*
X585692Y474341D01*
X585279Y474226D01*
X584969Y474073D01*
X584710Y473843D01*
X584607Y473536D01*
G01X587707Y477096D02*
X584607D01*
X586829Y475678D01*
Y477594D01*
G01X587707Y479736D02*
X587655Y480004D01*
X587500Y480311D01*
X587242Y480503D01*
X586880Y480579D01*
X586519Y480503D01*
X586209Y480273D01*
X586054Y479928D01*
Y479544D01*
X585950Y479314D01*
X585692Y479123D01*
X585330Y479046D01*
X584969Y479161D01*
X584710Y479429D01*
X584607Y479736D01*
X584710Y480043D01*
X584969Y480311D01*
X585330Y480426D01*
X585692Y480349D01*
X585950Y480158D01*
X586054Y479928D01*
Y479544D01*
X586209Y479199D01*
X586519Y478969D01*
X586880Y478893D01*
X587242Y478969D01*
X587500Y479161D01*
X587655Y479468D01*
X587707Y479736D01*
G01X586414Y482464D02*
X581414D01*
Y484048D01*
X581664Y484554D01*
X581997Y484871D01*
X582664Y484998D01*
X583331Y484871D01*
X583747Y484491D01*
X583997Y484048D01*
Y482464D01*
G01Y484048D02*
X586414Y484998D01*
G01X585747Y487501D02*
X586164Y488008D01*
X586414Y488578D01*
Y489084D01*
X586164Y489591D01*
X585747Y489971D01*
X585164Y490161D01*
X584581Y490034D01*
X584081Y489718D01*
X583747Y489148D01*
X583581Y488388D01*
X583247Y487944D01*
X582664Y487754D01*
X582081Y487881D01*
X581664Y488198D01*
X581414Y488641D01*
Y489084D01*
X581581Y489528D01*
X581997Y489908D01*
G01X581414Y493931D02*
X586414D01*
G01X581414Y492474D02*
Y495388D01*
G01X588081Y497131D02*
Y500931D01*
G01X583747Y504638D02*
X583497Y504891D01*
X583081Y505081D01*
X582497Y505208D01*
X581997Y505081D01*
X581664Y504828D01*
X581414Y504384D01*
Y502674D01*
X586414D01*
Y504764D01*
X586081Y505208D01*
X585581Y505461D01*
X584997Y505588D01*
X584414Y505461D01*
X583914Y505081D01*
X583747Y504638D01*
Y502674D01*
G01X581414Y509231D02*
X586414D01*
G01X581414Y507774D02*
Y510688D01*
G01X586414Y512874D02*
X581414D01*
X586414Y515788D01*
X581414D01*
G01X589002Y481224D02*
X604800D01*
Y493820D01*
G01X580580Y490005D02*
Y481637D01*
X589171D01*
Y497068D01*
G01X581582Y516800D02*
X588201D01*
Y502718D01*
X588159D01*
G01X582960Y525909D02*
X582730Y526064D01*
X582462Y526167D01*
X582155D01*
X581810Y526012D01*
X581542Y525754D01*
X581350Y525444D01*
X581197Y524927D01*
X581159Y524462D01*
X581235Y523997D01*
X581350Y523687D01*
X581580Y523377D01*
X581849Y523170D01*
X582117Y523067D01*
X582385D01*
X582654Y523170D01*
X582884Y523325D01*
X583075Y523532D01*
G01X585217Y523067D02*
X585485Y523119D01*
X585792Y523274D01*
X585984Y523532D01*
X586060Y523894D01*
X585984Y524255D01*
X585754Y524565D01*
X585409Y524720D01*
X585025D01*
X584795Y524824D01*
X584604Y525082D01*
X584527Y525444D01*
X584642Y525805D01*
X584910Y526064D01*
X585217Y526167D01*
X585524Y526064D01*
X585792Y525805D01*
X585907Y525444D01*
X585830Y525082D01*
X585639Y524824D01*
X585409Y524720D01*
X585025D01*
X584680Y524565D01*
X584450Y524255D01*
X584374Y523894D01*
X584450Y523532D01*
X584642Y523274D01*
X584949Y523119D01*
X585217Y523067D01*
G01X588317Y526167D02*
X588010Y526064D01*
X587780Y525805D01*
X587627Y525495D01*
X587512Y525082D01*
X587474Y524617D01*
X587512Y524152D01*
X587627Y523739D01*
X587780Y523429D01*
X588010Y523170D01*
X588317Y523067D01*
X588624Y523170D01*
X588854Y523429D01*
X589007Y523739D01*
X589122Y524152D01*
X589160Y524617D01*
X589122Y525082D01*
X589007Y525495D01*
X588854Y525805D01*
X588624Y526064D01*
X588317Y526167D01*
G01X591417Y523067D02*
Y526167D01*
X590957Y525547D01*
G01Y523067D02*
X591877D01*
G01X581350Y530976D02*
Y534076D01*
X582309D01*
X582615Y533921D01*
X582807Y533714D01*
X582884Y533301D01*
X582807Y532888D01*
X582577Y532629D01*
X582309Y532474D01*
X581350D01*
G01X582309D02*
X582884Y530976D01*
G01X585217D02*
Y534076D01*
X584757Y533456D01*
G01Y530976D02*
X585677D01*
G01X588317Y534076D02*
X588010Y533973D01*
X587780Y533714D01*
X587627Y533404D01*
X587512Y532991D01*
X587474Y532526D01*
X587512Y532061D01*
X587627Y531648D01*
X587780Y531338D01*
X588010Y531079D01*
X588317Y530976D01*
X588624Y531079D01*
X588854Y531338D01*
X589007Y531648D01*
X589122Y532061D01*
X589160Y532526D01*
X589122Y532991D01*
X589007Y533404D01*
X588854Y533714D01*
X588624Y533973D01*
X588317Y534076D01*
G01X590689Y532268D02*
X590957Y532629D01*
X591187Y532836D01*
X591494Y532939D01*
X591762Y532836D01*
X591954Y532629D01*
X592107Y532319D01*
X592145Y531958D01*
X592107Y531648D01*
X591954Y531338D01*
X591724Y531079D01*
X591455Y530976D01*
X591149Y531079D01*
X590880Y531389D01*
X590727Y531854D01*
X590689Y532371D01*
X590765Y533043D01*
X590880Y533404D01*
X591072Y533766D01*
X591340Y534024D01*
X591609Y534076D01*
X591877Y533973D01*
X592069Y533714D01*
G01X593674Y531596D02*
X593904Y531234D01*
X594210Y531028D01*
X594555Y530976D01*
X594862Y531028D01*
X595169Y531286D01*
X595360Y531596D01*
X595399Y531906D01*
X595322Y532268D01*
X595054Y532526D01*
X594785Y532629D01*
X594440D01*
G01X594785D02*
X595015Y532784D01*
X595207Y533043D01*
X595284Y533353D01*
X595207Y533663D01*
X595015Y533921D01*
X594670Y534076D01*
X594325Y534024D01*
X593980Y533818D01*
G01X581350Y527030D02*
Y530130D01*
X582309D01*
X582615Y529975D01*
X582807Y529768D01*
X582884Y529355D01*
X582807Y528942D01*
X582577Y528683D01*
X582309Y528528D01*
X581350D01*
G01X582309D02*
X582884Y527030D01*
G01X585217D02*
Y530130D01*
X584757Y529510D01*
G01Y527030D02*
X585677D01*
G01X588317Y530130D02*
X588010Y530027D01*
X587780Y529768D01*
X587627Y529458D01*
X587512Y529045D01*
X587474Y528580D01*
X587512Y528115D01*
X587627Y527702D01*
X587780Y527392D01*
X588010Y527133D01*
X588317Y527030D01*
X588624Y527133D01*
X588854Y527392D01*
X589007Y527702D01*
X589122Y528115D01*
X589160Y528580D01*
X589122Y529045D01*
X589007Y529458D01*
X588854Y529768D01*
X588624Y530027D01*
X588317Y530130D01*
G01X590689Y528322D02*
X590957Y528683D01*
X591187Y528890D01*
X591494Y528993D01*
X591762Y528890D01*
X591954Y528683D01*
X592107Y528373D01*
X592145Y528012D01*
X592107Y527702D01*
X591954Y527392D01*
X591724Y527133D01*
X591455Y527030D01*
X591149Y527133D01*
X590880Y527443D01*
X590727Y527908D01*
X590689Y528425D01*
X590765Y529097D01*
X590880Y529458D01*
X591072Y529820D01*
X591340Y530078D01*
X591609Y530130D01*
X591877Y530027D01*
X592069Y529768D01*
G01X593789Y529613D02*
X594019Y529923D01*
X594287Y530078D01*
X594594Y530130D01*
X594977Y530027D01*
X595245Y529768D01*
X595322Y529458D01*
X595284Y529148D01*
X595130Y528890D01*
X594364Y528373D01*
X594019Y528012D01*
X593789Y527495D01*
X593712Y527030D01*
X595322D01*
G01X581350Y535014D02*
Y538114D01*
X582309D01*
X582615Y537959D01*
X582807Y537752D01*
X582884Y537339D01*
X582807Y536926D01*
X582577Y536667D01*
X582309Y536512D01*
X581350D01*
G01X582309D02*
X582884Y535014D01*
G01X585217D02*
Y538114D01*
X584757Y537494D01*
G01Y535014D02*
X585677D01*
G01X588317Y538114D02*
X588010Y538011D01*
X587780Y537752D01*
X587627Y537442D01*
X587512Y537029D01*
X587474Y536564D01*
X587512Y536099D01*
X587627Y535686D01*
X587780Y535376D01*
X588010Y535117D01*
X588317Y535014D01*
X588624Y535117D01*
X588854Y535376D01*
X589007Y535686D01*
X589122Y536099D01*
X589160Y536564D01*
X589122Y537029D01*
X589007Y537442D01*
X588854Y537752D01*
X588624Y538011D01*
X588317Y538114D01*
G01X590689Y536306D02*
X590957Y536667D01*
X591187Y536874D01*
X591494Y536977D01*
X591762Y536874D01*
X591954Y536667D01*
X592107Y536357D01*
X592145Y535996D01*
X592107Y535686D01*
X591954Y535376D01*
X591724Y535117D01*
X591455Y535014D01*
X591149Y535117D01*
X590880Y535427D01*
X590727Y535892D01*
X590689Y536409D01*
X590765Y537081D01*
X590880Y537442D01*
X591072Y537804D01*
X591340Y538062D01*
X591609Y538114D01*
X591877Y538011D01*
X592069Y537752D01*
G01X594440Y535014D02*
X594517Y535686D01*
X594632Y536254D01*
X594785Y536771D01*
X594977Y537339D01*
X595284Y538114D01*
X593750D01*
G01X587444Y539851D02*
Y542351D01*
X588110D01*
X588324Y542226D01*
X588457Y542059D01*
X588510Y541726D01*
X588457Y541393D01*
X588297Y541184D01*
X588110Y541059D01*
X587444D01*
G01X588110D02*
X588510Y539851D01*
G01X590177D02*
Y542351D01*
X589857Y541851D01*
G01Y539851D02*
X590497D01*
G01X591870Y541934D02*
X592030Y542184D01*
X592217Y542309D01*
X592430Y542351D01*
X592697Y542268D01*
X592884Y542059D01*
X592937Y541809D01*
X592910Y541559D01*
X592804Y541351D01*
X592270Y540934D01*
X592030Y540643D01*
X591870Y540226D01*
X591817Y539851D01*
X592937D01*
G01X594070Y541934D02*
X594230Y542184D01*
X594417Y542309D01*
X594630Y542351D01*
X594897Y542268D01*
X595084Y542059D01*
X595137Y541809D01*
X595110Y541559D01*
X595004Y541351D01*
X594470Y540934D01*
X594230Y540643D01*
X594070Y540226D01*
X594017Y539851D01*
X595137D01*
G01X596324Y540143D02*
X596510Y539934D01*
X596724Y539851D01*
X596937Y539934D01*
X597124Y540184D01*
X597257Y540559D01*
X597310Y540934D01*
Y541393D01*
X597257Y541768D01*
X597124Y542101D01*
X596964Y542268D01*
X596777Y542351D01*
X596564Y542268D01*
X596404Y542101D01*
X596297Y541851D01*
X596244Y541518D01*
X596297Y541226D01*
X596430Y540934D01*
X596590Y540768D01*
X596777Y540726D01*
X596990Y540809D01*
X597150Y541018D01*
X597310Y541393D01*
G01X586538Y542225D02*
Y539025D01*
G01X580338Y542225D02*
X586538D01*
G01X580338Y539025D02*
Y542225D01*
G01X586538Y539025D02*
X580338D01*
G01X573638Y547025D02*
Y543825D01*
G01X587531Y543664D02*
Y546164D01*
X588197D01*
X588411Y546039D01*
X588544Y545872D01*
X588597Y545539D01*
X588544Y545206D01*
X588384Y544997D01*
X588197Y544872D01*
X587531D01*
G01X588197D02*
X588597Y543664D01*
G01X589757Y545747D02*
X589917Y545997D01*
X590104Y546122D01*
X590317Y546164D01*
X590584Y546081D01*
X590771Y545872D01*
X590824Y545622D01*
X590797Y545372D01*
X590691Y545164D01*
X590157Y544747D01*
X589917Y544456D01*
X589757Y544039D01*
X589704Y543664D01*
X590824D01*
G01X592464D02*
X592651Y543706D01*
X592864Y543831D01*
X592997Y544039D01*
X593051Y544331D01*
X592997Y544622D01*
X592837Y544872D01*
X592597Y544997D01*
X592331D01*
X592171Y545081D01*
X592037Y545289D01*
X591984Y545581D01*
X592064Y545872D01*
X592251Y546081D01*
X592464Y546164D01*
X592677Y546081D01*
X592864Y545872D01*
X592944Y545581D01*
X592891Y545289D01*
X592757Y545081D01*
X592597Y544997D01*
X592331D01*
X592091Y544872D01*
X591931Y544622D01*
X591877Y544331D01*
X591931Y544039D01*
X592064Y543831D01*
X592277Y543706D01*
X592464Y543664D01*
G01X594984D02*
Y546164D01*
X593997Y544372D01*
X595331D01*
G01X580338Y543625D02*
Y546825D01*
G01X586538Y543625D02*
X580338D01*
G01X586538Y546825D02*
Y543625D01*
G01X580338Y546825D02*
X586538D01*
G01X573638Y542425D02*
Y539225D01*
G01X589259Y553705D02*
Y556205D01*
X589925D01*
X590139Y556080D01*
X590272Y555913D01*
X590325Y555580D01*
X590272Y555247D01*
X590112Y555038D01*
X589925Y554913D01*
X589259D01*
G01X589925D02*
X590325Y553705D01*
G01X591405Y554205D02*
X591565Y553913D01*
X591779Y553747D01*
X592019Y553705D01*
X592232Y553747D01*
X592445Y553955D01*
X592579Y554205D01*
X592605Y554455D01*
X592552Y554747D01*
X592365Y554955D01*
X592179Y555038D01*
X591939D01*
G01X592179D02*
X592339Y555163D01*
X592472Y555372D01*
X592525Y555622D01*
X592472Y555872D01*
X592339Y556080D01*
X592099Y556205D01*
X591859Y556163D01*
X591619Y555997D01*
G01X594192Y553705D02*
Y556205D01*
X593872Y555705D01*
G01Y553705D02*
X594512D01*
G01X596392Y556205D02*
X596179Y556122D01*
X596019Y555913D01*
X595912Y555663D01*
X595832Y555330D01*
X595805Y554955D01*
X595832Y554580D01*
X595912Y554247D01*
X596019Y553997D01*
X596179Y553788D01*
X596392Y553705D01*
X596605Y553788D01*
X596765Y553997D01*
X596872Y554247D01*
X596952Y554580D01*
X596979Y554955D01*
X596952Y555330D01*
X596872Y555663D01*
X596765Y555913D01*
X596605Y556122D01*
X596392Y556205D01*
G01X585938Y561045D02*
Y557845D01*
G01X579738Y561045D02*
X585938D01*
G01X579738Y557845D02*
Y561045D01*
G01X585938Y557845D02*
X579738D01*
G01X589259Y550398D02*
Y552898D01*
X589925D01*
X590139Y552773D01*
X590272Y552606D01*
X590325Y552273D01*
X590272Y551940D01*
X590112Y551731D01*
X589925Y551606D01*
X589259D01*
G01X589925D02*
X590325Y550398D01*
G01X591405Y550898D02*
X591565Y550606D01*
X591779Y550440D01*
X592019Y550398D01*
X592232Y550440D01*
X592445Y550648D01*
X592579Y550898D01*
X592605Y551148D01*
X592552Y551440D01*
X592365Y551648D01*
X592179Y551731D01*
X591939D01*
G01X592179D02*
X592339Y551856D01*
X592472Y552065D01*
X592525Y552315D01*
X592472Y552565D01*
X592339Y552773D01*
X592099Y552898D01*
X591859Y552856D01*
X591619Y552690D01*
G01X594192Y552898D02*
X593979Y552815D01*
X593819Y552606D01*
X593712Y552356D01*
X593632Y552023D01*
X593605Y551648D01*
X593632Y551273D01*
X593712Y550940D01*
X593819Y550690D01*
X593979Y550481D01*
X594192Y550398D01*
X594405Y550481D01*
X594565Y550690D01*
X594672Y550940D01*
X594752Y551273D01*
X594779Y551648D01*
X594752Y552023D01*
X594672Y552356D01*
X594565Y552606D01*
X594405Y552815D01*
X594192Y552898D01*
G01X595939Y550690D02*
X596125Y550481D01*
X596339Y550398D01*
X596552Y550481D01*
X596739Y550731D01*
X596872Y551106D01*
X596925Y551481D01*
Y551940D01*
X596872Y552315D01*
X596739Y552648D01*
X596579Y552815D01*
X596392Y552898D01*
X596179Y552815D01*
X596019Y552648D01*
X595912Y552398D01*
X595859Y552065D01*
X595912Y551773D01*
X596045Y551481D01*
X596205Y551315D01*
X596392Y551273D01*
X596605Y551356D01*
X596765Y551565D01*
X596925Y551940D01*
G01X586008Y556835D02*
Y553635D01*
G01X579808Y556835D02*
X586008D01*
G01X579808Y553635D02*
Y556835D01*
G01X586008Y553635D02*
X579808D01*
G01X590037Y559445D02*
X586837D01*
G01D02*
Y565645D01*
G01X575621Y561905D02*
Y564405D01*
X576287D01*
X576501Y564280D01*
X576634Y564113D01*
X576687Y563780D01*
X576634Y563447D01*
X576474Y563238D01*
X576287Y563113D01*
X575621D01*
G01X576287D02*
X576687Y561905D01*
G01X577847Y563988D02*
X578007Y564238D01*
X578194Y564363D01*
X578407Y564405D01*
X578674Y564322D01*
X578861Y564113D01*
X578914Y563863D01*
X578887Y563613D01*
X578781Y563405D01*
X578247Y562988D01*
X578007Y562697D01*
X577847Y562280D01*
X577794Y561905D01*
X578914D01*
G01X580501D02*
X580554Y562447D01*
X580634Y562905D01*
X580741Y563322D01*
X580874Y563780D01*
X581087Y564405D01*
X580021D01*
G01X582167Y562280D02*
X582327Y562072D01*
X582514Y561947D01*
X582754Y561905D01*
X582994Y561988D01*
X583181Y562155D01*
X583314Y562447D01*
X583341Y562780D01*
X583287Y563113D01*
X583154Y563322D01*
X582967Y563488D01*
X582781Y563530D01*
X582594Y563488D01*
X582354Y563322D01*
X582434Y564405D01*
X583154D01*
G01X573638Y553625D02*
Y550425D01*
G01X573738Y561425D02*
Y558225D01*
G01X573638Y557525D02*
Y554325D01*
G01X590411Y568463D02*
X587911D01*
Y569129D01*
X588036Y569343D01*
X588203Y569476D01*
X588536Y569529D01*
X588869Y569476D01*
X589078Y569316D01*
X589203Y569129D01*
Y568463D01*
G01Y569129D02*
X590411Y569529D01*
G01X590036Y570609D02*
X590244Y570769D01*
X590369Y570956D01*
X590411Y571196D01*
X590328Y571436D01*
X590161Y571623D01*
X589869Y571756D01*
X589536Y571783D01*
X589203Y571729D01*
X588994Y571596D01*
X588828Y571409D01*
X588786Y571223D01*
X588828Y571036D01*
X588994Y570796D01*
X587911Y570876D01*
Y571596D01*
G01X590119Y572943D02*
X590328Y573129D01*
X590411Y573343D01*
X590328Y573556D01*
X590078Y573743D01*
X589703Y573876D01*
X589328Y573929D01*
X588869D01*
X588494Y573876D01*
X588161Y573743D01*
X587994Y573583D01*
X587911Y573396D01*
X587994Y573183D01*
X588161Y573023D01*
X588411Y572916D01*
X588744Y572863D01*
X589036Y572916D01*
X589328Y573049D01*
X589494Y573209D01*
X589536Y573396D01*
X589453Y573609D01*
X589244Y573769D01*
X588869Y573929D01*
G01X589911Y575009D02*
X590203Y575169D01*
X590369Y575383D01*
X590411Y575623D01*
X590369Y575836D01*
X590161Y576049D01*
X589911Y576183D01*
X589661Y576209D01*
X589369Y576156D01*
X589161Y575969D01*
X589078Y575783D01*
Y575543D01*
G01Y575783D02*
X588953Y575943D01*
X588744Y576076D01*
X588494Y576129D01*
X588244Y576076D01*
X588036Y575943D01*
X587911Y575703D01*
X587953Y575463D01*
X588119Y575223D01*
G01X587104Y568314D02*
X584604D01*
Y568980D01*
X584729Y569194D01*
X584896Y569327D01*
X585229Y569380D01*
X585562Y569327D01*
X585771Y569167D01*
X585896Y568980D01*
Y568314D01*
G01Y568980D02*
X587104Y569380D01*
G01X586729Y570460D02*
X586937Y570620D01*
X587062Y570807D01*
X587104Y571047D01*
X587021Y571287D01*
X586854Y571474D01*
X586562Y571607D01*
X586229Y571634D01*
X585896Y571580D01*
X585687Y571447D01*
X585521Y571260D01*
X585479Y571074D01*
X585521Y570887D01*
X585687Y570647D01*
X584604Y570727D01*
Y571447D01*
G01X587104Y573194D02*
X586562Y573247D01*
X586104Y573327D01*
X585687Y573434D01*
X585229Y573567D01*
X584604Y573780D01*
Y572714D01*
G01Y575447D02*
X584687Y575234D01*
X584896Y575074D01*
X585146Y574967D01*
X585479Y574887D01*
X585854Y574860D01*
X586229Y574887D01*
X586562Y574967D01*
X586812Y575074D01*
X587021Y575234D01*
X587104Y575447D01*
X587021Y575660D01*
X586812Y575820D01*
X586562Y575927D01*
X586229Y576007D01*
X585854Y576034D01*
X585479Y576007D01*
X585146Y575927D01*
X584896Y575820D01*
X584687Y575660D01*
X584604Y575447D01*
G01X586837Y565645D02*
X590037D01*
G01X577348Y565653D02*
Y568853D01*
G01X583548Y565653D02*
X577348D01*
G01Y568853D02*
X583548D01*
G01D02*
Y565653D01*
G01X573638Y569325D02*
Y566125D01*
G01Y573325D02*
Y570125D01*
G01X591981Y580701D02*
X588881D01*
Y581660D01*
X589036Y581966D01*
X589243Y582158D01*
X589656Y582235D01*
X590069Y582158D01*
X590328Y581928D01*
X590483Y581660D01*
Y580701D01*
G01Y581660D02*
X591981Y582235D01*
G01Y584568D02*
X588881D01*
X589501Y584108D01*
G01X591981D02*
Y585028D01*
G01X589398Y586940D02*
X589088Y587170D01*
X588933Y587438D01*
X588881Y587745D01*
X588984Y588128D01*
X589243Y588396D01*
X589553Y588473D01*
X589863Y588435D01*
X590121Y588281D01*
X590638Y587515D01*
X590999Y587170D01*
X591516Y586940D01*
X591981Y586863D01*
Y588473D01*
G01X589398Y590040D02*
X589088Y590270D01*
X588933Y590538D01*
X588881Y590845D01*
X588984Y591228D01*
X589243Y591496D01*
X589553Y591573D01*
X589863Y591535D01*
X590121Y591381D01*
X590638Y590615D01*
X590999Y590270D01*
X591516Y590040D01*
X591981Y589963D01*
Y591573D01*
G01Y593791D02*
X591309Y593868D01*
X590741Y593983D01*
X590224Y594136D01*
X589656Y594328D01*
X588881Y594635D01*
Y593101D01*
G01X579988Y573570D02*
X576888D01*
Y574529D01*
X577043Y574835D01*
X577250Y575027D01*
X577663Y575104D01*
X578076Y575027D01*
X578335Y574797D01*
X578490Y574529D01*
Y573570D01*
G01Y574529D02*
X579988Y575104D01*
G01X579368Y576594D02*
X579730Y576824D01*
X579936Y577130D01*
X579988Y577475D01*
X579936Y577782D01*
X579678Y578089D01*
X579368Y578280D01*
X579058Y578319D01*
X578696Y578242D01*
X578438Y577974D01*
X578335Y577705D01*
Y577360D01*
G01Y577705D02*
X578180Y577935D01*
X577921Y578127D01*
X577611Y578204D01*
X577301Y578127D01*
X577043Y577935D01*
X576888Y577590D01*
X576940Y577245D01*
X577146Y576900D01*
G01X576888Y580537D02*
X576991Y580230D01*
X577250Y580000D01*
X577560Y579847D01*
X577973Y579732D01*
X578438Y579694D01*
X578903Y579732D01*
X579316Y579847D01*
X579626Y580000D01*
X579885Y580230D01*
X579988Y580537D01*
X579885Y580844D01*
X579626Y581074D01*
X579316Y581227D01*
X578903Y581342D01*
X578438Y581380D01*
X577973Y581342D01*
X577560Y581227D01*
X577250Y581074D01*
X576991Y580844D01*
X576888Y580537D01*
G01X579368Y582794D02*
X579730Y583024D01*
X579936Y583330D01*
X579988Y583675D01*
X579936Y583982D01*
X579678Y584289D01*
X579368Y584480D01*
X579058Y584519D01*
X578696Y584442D01*
X578438Y584174D01*
X578335Y583905D01*
Y583560D01*
G01Y583905D02*
X578180Y584135D01*
X577921Y584327D01*
X577611Y584404D01*
X577301Y584327D01*
X577043Y584135D01*
X576888Y583790D01*
X576940Y583445D01*
X577146Y583100D01*
G01X583821Y573570D02*
X580721D01*
Y574529D01*
X580876Y574835D01*
X581083Y575027D01*
X581496Y575104D01*
X581909Y575027D01*
X582168Y574797D01*
X582323Y574529D01*
Y573570D01*
G01Y574529D02*
X583821Y575104D01*
G01X583201Y576594D02*
X583563Y576824D01*
X583769Y577130D01*
X583821Y577475D01*
X583769Y577782D01*
X583511Y578089D01*
X583201Y578280D01*
X582891Y578319D01*
X582529Y578242D01*
X582271Y577974D01*
X582168Y577705D01*
Y577360D01*
G01Y577705D02*
X582013Y577935D01*
X581754Y578127D01*
X581444Y578204D01*
X581134Y578127D01*
X580876Y577935D01*
X580721Y577590D01*
X580773Y577245D01*
X580979Y576900D01*
G01X580721Y580537D02*
X580824Y580230D01*
X581083Y580000D01*
X581393Y579847D01*
X581806Y579732D01*
X582271Y579694D01*
X582736Y579732D01*
X583149Y579847D01*
X583459Y580000D01*
X583718Y580230D01*
X583821Y580537D01*
X583718Y580844D01*
X583459Y581074D01*
X583149Y581227D01*
X582736Y581342D01*
X582271Y581380D01*
X581806Y581342D01*
X581393Y581227D01*
X581083Y581074D01*
X580824Y580844D01*
X580721Y580537D01*
G01X583821Y583637D02*
X580721D01*
X581341Y583177D01*
G01X583821D02*
Y584097D01*
G01X587969Y588492D02*
X584769D01*
G01X587969Y594692D02*
Y588492D01*
G01X584769Y594692D02*
X587969D01*
G01X584769Y588492D02*
Y594692D01*
G01X579999Y588412D02*
X576799D01*
G01X579999Y594612D02*
Y588412D01*
G01X576799Y594612D02*
X579999D01*
G01X576799Y588412D02*
Y594612D01*
G01X583999Y588412D02*
X580799D01*
G01X583999Y594612D02*
Y588412D01*
G01X580799Y594612D02*
X583999D01*
G01X580799Y588412D02*
Y594612D01*
G01X575199Y618604D02*
Y598804D01*
G01X586485Y625289D02*
X586255Y625444D01*
X585987Y625547D01*
X585680D01*
X585335Y625392D01*
X585067Y625134D01*
X584875Y624824D01*
X584722Y624307D01*
X584684Y623842D01*
X584760Y623377D01*
X584875Y623067D01*
X585105Y622757D01*
X585374Y622550D01*
X585642Y622447D01*
X585910D01*
X586179Y622550D01*
X586409Y622705D01*
X586600Y622912D01*
G01X588742Y622447D02*
Y625547D01*
X588282Y624927D01*
G01Y622447D02*
X589202D01*
G01X591190Y622809D02*
X591459Y622550D01*
X591765Y622447D01*
X592072Y622550D01*
X592340Y622860D01*
X592532Y623325D01*
X592609Y623790D01*
Y624359D01*
X592532Y624824D01*
X592340Y625237D01*
X592110Y625444D01*
X591842Y625547D01*
X591535Y625444D01*
X591305Y625237D01*
X591152Y624927D01*
X591075Y624514D01*
X591152Y624152D01*
X591344Y623790D01*
X591574Y623584D01*
X591842Y623532D01*
X592149Y623635D01*
X592379Y623894D01*
X592609Y624359D01*
G01X594942Y622447D02*
Y625547D01*
X594482Y624927D01*
G01Y622447D02*
X595402D01*
G01X581120Y624388D02*
X584120D01*
G01X581020Y627488D02*
X584220D01*
G01X581020Y621288D02*
Y627488D01*
G01X584220D02*
Y621288D01*
G01D02*
X581020D01*
G01X576935Y647873D02*
X576988Y648415D01*
X577068Y648873D01*
X577175Y649290D01*
X577308Y649748D01*
X577521Y650373D01*
X576455D01*
G01X578681Y648915D02*
X578868Y649206D01*
X579028Y649373D01*
X579241Y649456D01*
X579428Y649373D01*
X579561Y649206D01*
X579668Y648956D01*
X579695Y648665D01*
X579668Y648415D01*
X579561Y648165D01*
X579401Y647956D01*
X579215Y647873D01*
X579001Y647956D01*
X578815Y648206D01*
X578708Y648581D01*
X578681Y648998D01*
X578735Y649540D01*
X578815Y649831D01*
X578948Y650123D01*
X579135Y650331D01*
X579321Y650373D01*
X579508Y650290D01*
X579641Y650081D01*
G01X579216Y662948D02*
X578986Y663103D01*
X578718Y663206D01*
X578411D01*
X578066Y663051D01*
X577798Y662793D01*
X577606Y662483D01*
X577453Y661966D01*
X577415Y661501D01*
X577491Y661036D01*
X577606Y660726D01*
X577836Y660416D01*
X578105Y660209D01*
X578373Y660106D01*
X578641D01*
X578910Y660209D01*
X579140Y660364D01*
X579331Y660571D01*
G01X580821Y660468D02*
X581090Y660209D01*
X581396Y660106D01*
X581703Y660209D01*
X581971Y660519D01*
X582163Y660984D01*
X582240Y661449D01*
Y662018D01*
X582163Y662483D01*
X581971Y662896D01*
X581741Y663103D01*
X581473Y663206D01*
X581166Y663103D01*
X580936Y662896D01*
X580783Y662586D01*
X580706Y662173D01*
X580783Y661811D01*
X580975Y661449D01*
X581205Y661243D01*
X581473Y661191D01*
X581780Y661294D01*
X582010Y661553D01*
X582240Y662018D01*
G01X584573Y663206D02*
X584266Y663103D01*
X584036Y662844D01*
X583883Y662534D01*
X583768Y662121D01*
X583730Y661656D01*
X583768Y661191D01*
X583883Y660778D01*
X584036Y660468D01*
X584266Y660209D01*
X584573Y660106D01*
X584880Y660209D01*
X585110Y660468D01*
X585263Y660778D01*
X585378Y661191D01*
X585416Y661656D01*
X585378Y662121D01*
X585263Y662534D01*
X585110Y662844D01*
X584880Y663103D01*
X584573Y663206D01*
G01X587596Y660106D02*
X587673Y660778D01*
X587788Y661346D01*
X587941Y661863D01*
X588133Y662431D01*
X588440Y663206D01*
X586906D01*
G01X586261Y659448D02*
Y656248D01*
G01X580061Y659448D02*
X586261D01*
G01X580061Y656248D02*
Y659448D01*
G01X586261Y656248D02*
X580061D01*
G01X583161Y659348D02*
Y656348D01*
G01X587243Y654985D02*
X593443D01*
G01X587243Y651785D02*
Y654985D01*
G01X593443Y651785D02*
X587243D01*
G01X600898Y666561D02*
X586955D01*
Y680266D01*
X601137D01*
Y663641D01*
X613054D01*
Y648089D01*
X603878D01*
Y663522D01*
X603461D01*
G01X580740Y667856D02*
X575740D01*
G01X581339Y673130D02*
X581184Y672900D01*
X581081Y672632D01*
Y672325D01*
X581236Y671980D01*
X581494Y671712D01*
X581804Y671520D01*
X582321Y671367D01*
X582786Y671329D01*
X583251Y671405D01*
X583561Y671520D01*
X583871Y671750D01*
X584078Y672019D01*
X584181Y672287D01*
Y672555D01*
X584078Y672824D01*
X583923Y673054D01*
X583716Y673245D01*
G01X583819Y674735D02*
X584078Y675004D01*
X584181Y675310D01*
X584078Y675617D01*
X583768Y675885D01*
X583303Y676077D01*
X582838Y676154D01*
X582269D01*
X581804Y676077D01*
X581391Y675885D01*
X581184Y675655D01*
X581081Y675387D01*
X581184Y675080D01*
X581391Y674850D01*
X581701Y674697D01*
X582114Y674620D01*
X582476Y674697D01*
X582838Y674889D01*
X583044Y675119D01*
X583096Y675387D01*
X582993Y675694D01*
X582734Y675924D01*
X582269Y676154D01*
G01X581081Y678487D02*
X581184Y678180D01*
X581443Y677950D01*
X581753Y677797D01*
X582166Y677682D01*
X582631Y677644D01*
X583096Y677682D01*
X583509Y677797D01*
X583819Y677950D01*
X584078Y678180D01*
X584181Y678487D01*
X584078Y678794D01*
X583819Y679024D01*
X583509Y679177D01*
X583096Y679292D01*
X582631Y679330D01*
X582166Y679292D01*
X581753Y679177D01*
X581443Y679024D01*
X581184Y678794D01*
X581081Y678487D01*
G01X584181Y682047D02*
X581081D01*
X583303Y680629D01*
Y682545D01*
G01X588581Y671471D02*
Y674571D01*
X589540D01*
X589846Y674416D01*
X590038Y674209D01*
X590115Y673796D01*
X590038Y673383D01*
X589808Y673124D01*
X589540Y672969D01*
X588581D01*
G01X589540D02*
X590115Y671471D01*
G01X591605Y671936D02*
X591835Y671678D01*
X592103Y671523D01*
X592448Y671471D01*
X592793Y671574D01*
X593061Y671781D01*
X593253Y672143D01*
X593291Y672556D01*
X593215Y672969D01*
X593023Y673228D01*
X592755Y673434D01*
X592486Y673486D01*
X592218Y673434D01*
X591873Y673228D01*
X591988Y674571D01*
X593023D01*
G01X595471Y671471D02*
X595548Y672143D01*
X595663Y672711D01*
X595816Y673228D01*
X596008Y673796D01*
X596315Y674571D01*
X594781D01*
G01X597996Y671833D02*
X598265Y671574D01*
X598571Y671471D01*
X598878Y671574D01*
X599146Y671884D01*
X599338Y672349D01*
X599415Y672814D01*
Y673383D01*
X599338Y673848D01*
X599146Y674261D01*
X598916Y674468D01*
X598648Y674571D01*
X598341Y674468D01*
X598111Y674261D01*
X597958Y673951D01*
X597881Y673538D01*
X597958Y673176D01*
X598150Y672814D01*
X598380Y672608D01*
X598648Y672556D01*
X598955Y672659D01*
X599185Y672918D01*
X599415Y673383D01*
G01X588581Y667262D02*
Y670362D01*
X589540D01*
X589846Y670207D01*
X590038Y670000D01*
X590115Y669587D01*
X590038Y669174D01*
X589808Y668915D01*
X589540Y668760D01*
X588581D01*
G01X589540D02*
X590115Y667262D01*
G01X591605Y667727D02*
X591835Y667469D01*
X592103Y667314D01*
X592448Y667262D01*
X592793Y667365D01*
X593061Y667572D01*
X593253Y667934D01*
X593291Y668347D01*
X593215Y668760D01*
X593023Y669019D01*
X592755Y669225D01*
X592486Y669277D01*
X592218Y669225D01*
X591873Y669019D01*
X591988Y670362D01*
X593023D01*
G01X595548Y667262D02*
X595816Y667314D01*
X596123Y667469D01*
X596315Y667727D01*
X596391Y668089D01*
X596315Y668450D01*
X596085Y668760D01*
X595740Y668915D01*
X595356D01*
X595126Y669019D01*
X594935Y669277D01*
X594858Y669639D01*
X594973Y670000D01*
X595241Y670259D01*
X595548Y670362D01*
X595855Y670259D01*
X596123Y670000D01*
X596238Y669639D01*
X596161Y669277D01*
X595970Y669019D01*
X595740Y668915D01*
X595356D01*
X595011Y668760D01*
X594781Y668450D01*
X594705Y668089D01*
X594781Y667727D01*
X594973Y667469D01*
X595280Y667314D01*
X595548Y667262D01*
G01X597805Y667727D02*
X598035Y667469D01*
X598303Y667314D01*
X598648Y667262D01*
X598993Y667365D01*
X599261Y667572D01*
X599453Y667934D01*
X599491Y668347D01*
X599415Y668760D01*
X599223Y669019D01*
X598955Y669225D01*
X598686Y669277D01*
X598418Y669225D01*
X598073Y669019D01*
X598188Y670362D01*
X599223D01*
G01X588581Y675574D02*
Y678674D01*
X589540D01*
X589846Y678519D01*
X590038Y678312D01*
X590115Y677899D01*
X590038Y677486D01*
X589808Y677227D01*
X589540Y677072D01*
X588581D01*
G01X589540D02*
X590115Y675574D01*
G01X591605Y676039D02*
X591835Y675781D01*
X592103Y675626D01*
X592448Y675574D01*
X592793Y675677D01*
X593061Y675884D01*
X593253Y676246D01*
X593291Y676659D01*
X593215Y677072D01*
X593023Y677331D01*
X592755Y677537D01*
X592486Y677589D01*
X592218Y677537D01*
X591873Y677331D01*
X591988Y678674D01*
X593023D01*
G01X595471Y675574D02*
X595548Y676246D01*
X595663Y676814D01*
X595816Y677331D01*
X596008Y677899D01*
X596315Y678674D01*
X594781D01*
G01X597805Y676194D02*
X598035Y675832D01*
X598341Y675626D01*
X598686Y675574D01*
X598993Y675626D01*
X599300Y675884D01*
X599491Y676194D01*
X599530Y676504D01*
X599453Y676866D01*
X599185Y677124D01*
X598916Y677227D01*
X598571D01*
G01X598916D02*
X599146Y677382D01*
X599338Y677641D01*
X599415Y677951D01*
X599338Y678261D01*
X599146Y678519D01*
X598801Y678674D01*
X598456Y678622D01*
X598111Y678416D01*
G01X580938Y677556D02*
X575640D01*
G01X580640Y687356D02*
X575640D01*
G01X586077Y687626D02*
Y684426D01*
G01X579877Y687626D02*
X586077D01*
G01X579877Y684426D02*
Y687626D01*
G01X586077Y684426D02*
X579877D01*
G01X582977Y687526D02*
Y684526D01*
G01X591400Y682384D02*
X588200D01*
G01Y688584D02*
X591400D01*
G01X588200Y682384D02*
Y688584D01*
G01X586060Y691680D02*
Y688480D01*
G01X579860D02*
Y691680D01*
G01X586060Y688480D02*
X579860D01*
G01X587940Y697356D02*
X575740D01*
G01X579113Y702063D02*
Y705163D01*
X580072D01*
X580378Y705008D01*
X580570Y704801D01*
X580647Y704388D01*
X580570Y703975D01*
X580340Y703716D01*
X580072Y703561D01*
X579113D01*
G01X580072D02*
X580647Y702063D01*
G01X582980D02*
X583248Y702115D01*
X583555Y702270D01*
X583747Y702528D01*
X583823Y702890D01*
X583747Y703251D01*
X583517Y703561D01*
X583172Y703716D01*
X582788D01*
X582558Y703820D01*
X582367Y704078D01*
X582290Y704440D01*
X582405Y704801D01*
X582673Y705060D01*
X582980Y705163D01*
X583287Y705060D01*
X583555Y704801D01*
X583670Y704440D01*
X583593Y704078D01*
X583402Y703820D01*
X583172Y703716D01*
X582788D01*
X582443Y703561D01*
X582213Y703251D01*
X582137Y702890D01*
X582213Y702528D01*
X582405Y702270D01*
X582712Y702115D01*
X582980Y702063D01*
G01X586080Y705163D02*
X585773Y705060D01*
X585543Y704801D01*
X585390Y704491D01*
X585275Y704078D01*
X585237Y703613D01*
X585275Y703148D01*
X585390Y702735D01*
X585543Y702425D01*
X585773Y702166D01*
X586080Y702063D01*
X586387Y702166D01*
X586617Y702425D01*
X586770Y702735D01*
X586885Y703148D01*
X586923Y703613D01*
X586885Y704078D01*
X586770Y704491D01*
X586617Y704801D01*
X586387Y705060D01*
X586080Y705163D01*
G01X588452Y703355D02*
X588720Y703716D01*
X588950Y703923D01*
X589257Y704026D01*
X589525Y703923D01*
X589717Y703716D01*
X589870Y703406D01*
X589908Y703045D01*
X589870Y702735D01*
X589717Y702425D01*
X589487Y702166D01*
X589218Y702063D01*
X588912Y702166D01*
X588643Y702476D01*
X588490Y702941D01*
X588452Y703458D01*
X588528Y704130D01*
X588643Y704491D01*
X588835Y704853D01*
X589103Y705111D01*
X589372Y705163D01*
X589640Y705060D01*
X589832Y704801D01*
G01X586060Y695680D02*
Y692480D01*
G01X579860Y695680D02*
X586060D01*
G01X579860Y692480D02*
Y695680D01*
G01X586060Y692480D02*
X579860D01*
G01X579113Y698063D02*
Y701163D01*
X580072D01*
X580378Y701008D01*
X580570Y700801D01*
X580647Y700388D01*
X580570Y699975D01*
X580340Y699716D01*
X580072Y699561D01*
X579113D01*
G01X580072D02*
X580647Y698063D01*
G01X582903D02*
X582980Y698735D01*
X583095Y699303D01*
X583248Y699820D01*
X583440Y700388D01*
X583747Y701163D01*
X582213D01*
G01X585428Y698425D02*
X585697Y698166D01*
X586003Y698063D01*
X586310Y698166D01*
X586578Y698476D01*
X586770Y698941D01*
X586847Y699406D01*
Y699975D01*
X586770Y700440D01*
X586578Y700853D01*
X586348Y701060D01*
X586080Y701163D01*
X585773Y701060D01*
X585543Y700853D01*
X585390Y700543D01*
X585313Y700130D01*
X585390Y699768D01*
X585582Y699406D01*
X585812Y699200D01*
X586080Y699148D01*
X586387Y699251D01*
X586617Y699510D01*
X586847Y699975D01*
G01X589640Y698063D02*
Y701163D01*
X588222Y698941D01*
X590138D01*
G01X579860Y691680D02*
X586060D01*
G01X575040Y732256D02*
Y726056D01*
G01X585040Y737556D02*
X581840D01*
G01X585040Y743756D02*
Y737556D01*
G01X581840D02*
Y743756D01*
G01X589540Y726056D02*
X586340D01*
G01Y732256D02*
X589540D01*
G01X586340Y726056D02*
Y732256D01*
G01X589440Y729156D02*
X586440D01*
G01X586340Y737556D02*
Y743756D01*
G01X589540Y737556D02*
X586340D01*
G01X581840Y732256D02*
X585040D01*
G01X581840Y726056D02*
Y732256D01*
G01X585040Y726056D02*
X581840D01*
G01X585040Y732256D02*
Y726056D01*
G01X575040Y743756D02*
Y737556D01*
G01X581840Y743756D02*
X585040D01*
G01X584940Y740656D02*
X581940D01*
G01X587481Y749921D02*
X587326Y749691D01*
X587223Y749423D01*
Y749116D01*
X587378Y748771D01*
X587636Y748503D01*
X587946Y748311D01*
X588463Y748158D01*
X588928Y748120D01*
X589393Y748196D01*
X589703Y748311D01*
X590013Y748541D01*
X590220Y748810D01*
X590323Y749078D01*
Y749346D01*
X590220Y749615D01*
X590065Y749845D01*
X589858Y750036D01*
G01X590323Y752101D02*
X589651Y752178D01*
X589083Y752293D01*
X588566Y752446D01*
X587998Y752638D01*
X587223Y752945D01*
Y751411D01*
G01X589858Y754435D02*
X590116Y754665D01*
X590271Y754933D01*
X590323Y755278D01*
X590220Y755623D01*
X590013Y755891D01*
X589651Y756083D01*
X589238Y756121D01*
X588825Y756045D01*
X588566Y755853D01*
X588360Y755585D01*
X588308Y755316D01*
X588360Y755048D01*
X588566Y754703D01*
X587223Y754818D01*
Y755853D01*
G01Y758378D02*
X587326Y758071D01*
X587585Y757841D01*
X587895Y757688D01*
X588308Y757573D01*
X588773Y757535D01*
X589238Y757573D01*
X589651Y757688D01*
X589961Y757841D01*
X590220Y758071D01*
X590323Y758378D01*
X590220Y758685D01*
X589961Y758915D01*
X589651Y759068D01*
X589238Y759183D01*
X588773Y759221D01*
X588308Y759183D01*
X587895Y759068D01*
X587585Y758915D01*
X587326Y758685D01*
X587223Y758378D01*
G01X586340Y743756D02*
X589540D01*
G01X585857Y748311D02*
X582757D01*
Y749270D01*
X582912Y749576D01*
X583119Y749768D01*
X583532Y749845D01*
X583945Y749768D01*
X584204Y749538D01*
X584359Y749270D01*
Y748311D01*
G01Y749270D02*
X585857Y749845D01*
G01X585495Y751526D02*
X585754Y751795D01*
X585857Y752101D01*
X585754Y752408D01*
X585444Y752676D01*
X584979Y752868D01*
X584514Y752945D01*
X583945D01*
X583480Y752868D01*
X583067Y752676D01*
X582860Y752446D01*
X582757Y752178D01*
X582860Y751871D01*
X583067Y751641D01*
X583377Y751488D01*
X583790Y751411D01*
X584152Y751488D01*
X584514Y751680D01*
X584720Y751910D01*
X584772Y752178D01*
X584669Y752485D01*
X584410Y752715D01*
X583945Y752945D01*
G01X585495Y754626D02*
X585754Y754895D01*
X585857Y755201D01*
X585754Y755508D01*
X585444Y755776D01*
X584979Y755968D01*
X584514Y756045D01*
X583945D01*
X583480Y755968D01*
X583067Y755776D01*
X582860Y755546D01*
X582757Y755278D01*
X582860Y754971D01*
X583067Y754741D01*
X583377Y754588D01*
X583790Y754511D01*
X584152Y754588D01*
X584514Y754780D01*
X584720Y755010D01*
X584772Y755278D01*
X584669Y755585D01*
X584410Y755815D01*
X583945Y756045D01*
G01X582757Y758378D02*
X582860Y758071D01*
X583119Y757841D01*
X583429Y757688D01*
X583842Y757573D01*
X584307Y757535D01*
X584772Y757573D01*
X585185Y757688D01*
X585495Y757841D01*
X585754Y758071D01*
X585857Y758378D01*
X585754Y758685D01*
X585495Y758915D01*
X585185Y759068D01*
X584772Y759183D01*
X584307Y759221D01*
X583842Y759183D01*
X583429Y759068D01*
X583119Y758915D01*
X582860Y758685D01*
X582757Y758378D01*
G01X587935Y764380D02*
X587780Y764150D01*
X587677Y763882D01*
Y763575D01*
X587832Y763230D01*
X588090Y762962D01*
X588400Y762770D01*
X588917Y762617D01*
X589382Y762579D01*
X589847Y762655D01*
X590157Y762770D01*
X590467Y763000D01*
X590674Y763269D01*
X590777Y763537D01*
Y763805D01*
X590674Y764074D01*
X590519Y764304D01*
X590312Y764495D01*
G01X589485Y765909D02*
X589124Y766177D01*
X588917Y766407D01*
X588814Y766714D01*
X588917Y766982D01*
X589124Y767174D01*
X589434Y767327D01*
X589795Y767365D01*
X590105Y767327D01*
X590415Y767174D01*
X590674Y766944D01*
X590777Y766675D01*
X590674Y766369D01*
X590364Y766100D01*
X589899Y765947D01*
X589382Y765909D01*
X588710Y765985D01*
X588349Y766100D01*
X587987Y766292D01*
X587729Y766560D01*
X587677Y766829D01*
X587780Y767097D01*
X588039Y767289D01*
G01X589485Y769009D02*
X589124Y769277D01*
X588917Y769507D01*
X588814Y769814D01*
X588917Y770082D01*
X589124Y770274D01*
X589434Y770427D01*
X589795Y770465D01*
X590105Y770427D01*
X590415Y770274D01*
X590674Y770044D01*
X590777Y769775D01*
X590674Y769469D01*
X590364Y769200D01*
X589899Y769047D01*
X589382Y769009D01*
X588710Y769085D01*
X588349Y769200D01*
X587987Y769392D01*
X587729Y769660D01*
X587677Y769929D01*
X587780Y770197D01*
X588039Y770389D01*
G01X589485Y772109D02*
X589124Y772377D01*
X588917Y772607D01*
X588814Y772914D01*
X588917Y773182D01*
X589124Y773374D01*
X589434Y773527D01*
X589795Y773565D01*
X590105Y773527D01*
X590415Y773374D01*
X590674Y773144D01*
X590777Y772875D01*
X590674Y772569D01*
X590364Y772300D01*
X589899Y772147D01*
X589382Y772109D01*
X588710Y772185D01*
X588349Y772300D01*
X587987Y772492D01*
X587729Y772760D01*
X587677Y773029D01*
X587780Y773297D01*
X588039Y773489D01*
G01X579935Y764380D02*
X579780Y764150D01*
X579677Y763882D01*
Y763575D01*
X579832Y763230D01*
X580090Y762962D01*
X580400Y762770D01*
X580917Y762617D01*
X581382Y762579D01*
X581847Y762655D01*
X582157Y762770D01*
X582467Y763000D01*
X582674Y763269D01*
X582777Y763537D01*
Y763805D01*
X582674Y764074D01*
X582519Y764304D01*
X582312Y764495D01*
G01X582777Y766560D02*
X582105Y766637D01*
X581537Y766752D01*
X581020Y766905D01*
X580452Y767097D01*
X579677Y767404D01*
Y765870D01*
G01X582777Y770197D02*
X579677D01*
X581899Y768779D01*
Y770695D01*
G01X582777Y772760D02*
X582105Y772837D01*
X581537Y772952D01*
X581020Y773105D01*
X580452Y773297D01*
X579677Y773604D01*
Y772070D01*
G01X578777Y762770D02*
X575677D01*
Y763729D01*
X575832Y764035D01*
X576039Y764227D01*
X576452Y764304D01*
X576865Y764227D01*
X577124Y763997D01*
X577279Y763729D01*
Y762770D01*
G01Y763729D02*
X578777Y764304D01*
G01X578415Y765985D02*
X578674Y766254D01*
X578777Y766560D01*
X578674Y766867D01*
X578364Y767135D01*
X577899Y767327D01*
X577434Y767404D01*
X576865D01*
X576400Y767327D01*
X575987Y767135D01*
X575780Y766905D01*
X575677Y766637D01*
X575780Y766330D01*
X575987Y766100D01*
X576297Y765947D01*
X576710Y765870D01*
X577072Y765947D01*
X577434Y766139D01*
X577640Y766369D01*
X577692Y766637D01*
X577589Y766944D01*
X577330Y767174D01*
X576865Y767404D01*
G01X578777Y769737D02*
X578725Y770005D01*
X578570Y770312D01*
X578312Y770504D01*
X577950Y770580D01*
X577589Y770504D01*
X577279Y770274D01*
X577124Y769929D01*
Y769545D01*
X577020Y769315D01*
X576762Y769124D01*
X576400Y769047D01*
X576039Y769162D01*
X575780Y769430D01*
X575677Y769737D01*
X575780Y770044D01*
X576039Y770312D01*
X576400Y770427D01*
X576762Y770350D01*
X577020Y770159D01*
X577124Y769929D01*
Y769545D01*
X577279Y769200D01*
X577589Y768970D01*
X577950Y768894D01*
X578312Y768970D01*
X578570Y769162D01*
X578725Y769469D01*
X578777Y769737D01*
G01Y772760D02*
X578105Y772837D01*
X577537Y772952D01*
X577020Y773105D01*
X576452Y773297D01*
X575677Y773604D01*
Y772070D01*
G01X586777Y762770D02*
X583677D01*
Y763729D01*
X583832Y764035D01*
X584039Y764227D01*
X584452Y764304D01*
X584865Y764227D01*
X585124Y763997D01*
X585279Y763729D01*
Y762770D01*
G01Y763729D02*
X586777Y764304D01*
G01X586415Y765985D02*
X586674Y766254D01*
X586777Y766560D01*
X586674Y766867D01*
X586364Y767135D01*
X585899Y767327D01*
X585434Y767404D01*
X584865D01*
X584400Y767327D01*
X583987Y767135D01*
X583780Y766905D01*
X583677Y766637D01*
X583780Y766330D01*
X583987Y766100D01*
X584297Y765947D01*
X584710Y765870D01*
X585072Y765947D01*
X585434Y766139D01*
X585640Y766369D01*
X585692Y766637D01*
X585589Y766944D01*
X585330Y767174D01*
X584865Y767404D01*
G01X586777Y769737D02*
X586725Y770005D01*
X586570Y770312D01*
X586312Y770504D01*
X585950Y770580D01*
X585589Y770504D01*
X585279Y770274D01*
X585124Y769929D01*
Y769545D01*
X585020Y769315D01*
X584762Y769124D01*
X584400Y769047D01*
X584039Y769162D01*
X583780Y769430D01*
X583677Y769737D01*
X583780Y770044D01*
X584039Y770312D01*
X584400Y770427D01*
X584762Y770350D01*
X585020Y770159D01*
X585124Y769929D01*
Y769545D01*
X585279Y769200D01*
X585589Y768970D01*
X585950Y768894D01*
X586312Y768970D01*
X586570Y769162D01*
X586725Y769469D01*
X586777Y769737D01*
G01Y772837D02*
X583677D01*
X584297Y772377D01*
G01X586777D02*
Y773297D01*
G01X600372Y13376D02*
Y20059D01*
X600393D01*
X602586Y17866D01*
X602565Y17845D01*
X597737D01*
X599972Y20080D01*
X600309D01*
G01X591271Y46220D02*
X591463Y45910D01*
X591693Y45703D01*
X591961Y45600D01*
X592268Y45703D01*
X592498Y45910D01*
X592728Y46220D01*
X592805Y46633D01*
Y48700D01*
G01X594410Y48183D02*
X594640Y48493D01*
X594908Y48648D01*
X595215Y48700D01*
X595598Y48597D01*
X595866Y48338D01*
X595943Y48028D01*
X595905Y47718D01*
X595751Y47460D01*
X594985Y46943D01*
X594640Y46582D01*
X594410Y46065D01*
X594333Y45600D01*
X595943D01*
G01X597510Y46892D02*
X597778Y47253D01*
X598008Y47460D01*
X598315Y47563D01*
X598583Y47460D01*
X598775Y47253D01*
X598928Y46943D01*
X598966Y46582D01*
X598928Y46272D01*
X598775Y45962D01*
X598545Y45703D01*
X598276Y45600D01*
X597970Y45703D01*
X597701Y46013D01*
X597548Y46478D01*
X597510Y46995D01*
X597586Y47667D01*
X597701Y48028D01*
X597893Y48390D01*
X598161Y48648D01*
X598430Y48700D01*
X598698Y48597D01*
X598890Y48338D01*
G01X600958Y71687D02*
X601268Y71879D01*
X601475Y72109D01*
X601578Y72377D01*
X601475Y72684D01*
X601268Y72914D01*
X600958Y73144D01*
X600545Y73221D01*
X598478D01*
G01X600286Y74826D02*
X599925Y75094D01*
X599718Y75324D01*
X599615Y75631D01*
X599718Y75899D01*
X599925Y76091D01*
X600235Y76244D01*
X600596Y76282D01*
X600906Y76244D01*
X601216Y76091D01*
X601475Y75861D01*
X601578Y75592D01*
X601475Y75286D01*
X601165Y75017D01*
X600700Y74864D01*
X600183Y74826D01*
X599511Y74902D01*
X599150Y75017D01*
X598788Y75209D01*
X598530Y75477D01*
X598478Y75746D01*
X598581Y76014D01*
X598840Y76206D01*
G01X597692Y61293D02*
Y100663D01*
G01X595724Y73104D02*
Y63261D01*
G01X597692Y73104D02*
X595724D01*
G01X603846Y61293D02*
X612114D01*
G01X603846Y100663D02*
Y61293D01*
G01X595724Y98695D02*
Y88852D01*
G01D02*
X597692D01*
G01X601518Y106332D02*
X607718D01*
G01Y103132D02*
X601518D01*
G01D02*
Y106332D01*
G01X604618Y106232D02*
Y103232D01*
G01X602106Y96107D02*
Y99207D01*
X601646Y98587D01*
G01Y96107D02*
X602566D01*
G01X622350Y100663D02*
X603846D01*
G01X603718Y112432D02*
Y151032D01*
G01X609318Y112432D02*
X603718D01*
G01X591718Y119332D02*
Y116132D01*
G01X591990Y123436D02*
Y120236D01*
G01X591718Y133832D02*
Y130632D01*
G01Y129832D02*
Y126632D01*
G01X603718Y151032D02*
X619518D01*
G01X592442Y160474D02*
Y154274D01*
G01X592369Y167986D02*
Y161786D01*
G01X591336Y173506D02*
Y170306D01*
G01X619576Y158073D02*
X594182D01*
G01Y221065D02*
Y158073D01*
G01X591261Y181555D02*
Y178355D01*
G01X591336Y177506D02*
Y174306D01*
G01X592198Y206982D02*
Y200782D01*
G01X593270Y229440D02*
X597430D01*
G01X596210Y232560D02*
X624450D01*
G01X596210Y229480D02*
Y232560D01*
G01X596170Y229480D02*
X596210D01*
G01X593307Y228493D02*
Y222293D01*
G01D02*
X590107D01*
G01D02*
Y228493D01*
G01D02*
X593307D01*
G01X597307D02*
Y222293D01*
G01D02*
X594107D01*
G01D02*
Y228493D01*
G01D02*
X597307D01*
G01X619576Y221065D02*
X594182D01*
G01X590176Y237670D02*
X590336Y237920D01*
X590523Y238045D01*
X590736Y238087D01*
X591003Y238004D01*
X591190Y237795D01*
X591243Y237545D01*
X591216Y237295D01*
X591110Y237087D01*
X590576Y236670D01*
X590336Y236379D01*
X590176Y235962D01*
X590123Y235587D01*
X591243D01*
G01X592883Y238087D02*
X592670Y238004D01*
X592510Y237795D01*
X592403Y237545D01*
X592323Y237212D01*
X592296Y236837D01*
X592323Y236462D01*
X592403Y236129D01*
X592510Y235879D01*
X592670Y235670D01*
X592883Y235587D01*
X593096Y235670D01*
X593256Y235879D01*
X593363Y236129D01*
X593443Y236462D01*
X593470Y236837D01*
X593443Y237212D01*
X593363Y237545D01*
X593256Y237795D01*
X593096Y238004D01*
X592883Y238087D01*
G01X592040Y239170D02*
X596040D01*
G01X591948Y247081D02*
X593948D01*
G01X596646Y241965D02*
Y245065D01*
X597605D01*
X597911Y244910D01*
X598103Y244703D01*
X598180Y244290D01*
X598103Y243877D01*
X597873Y243618D01*
X597605Y243463D01*
X596646D01*
G01X597605D02*
X598180Y241965D01*
G01X599670Y242430D02*
X599900Y242172D01*
X600168Y242017D01*
X600513Y241965D01*
X600858Y242068D01*
X601126Y242275D01*
X601318Y242637D01*
X601356Y243050D01*
X601280Y243463D01*
X601088Y243722D01*
X600820Y243928D01*
X600551Y243980D01*
X600283Y243928D01*
X599938Y243722D01*
X600053Y245065D01*
X601088D01*
G01X603613D02*
X603306Y244962D01*
X603076Y244703D01*
X602923Y244393D01*
X602808Y243980D01*
X602770Y243515D01*
X602808Y243050D01*
X602923Y242637D01*
X603076Y242327D01*
X603306Y242068D01*
X603613Y241965D01*
X603920Y242068D01*
X604150Y242327D01*
X604303Y242637D01*
X604418Y243050D01*
X604456Y243515D01*
X604418Y243980D01*
X604303Y244393D01*
X604150Y244703D01*
X603920Y244962D01*
X603613Y245065D01*
G01X605870Y242585D02*
X606100Y242223D01*
X606406Y242017D01*
X606751Y241965D01*
X607058Y242017D01*
X607365Y242275D01*
X607556Y242585D01*
X607595Y242895D01*
X607518Y243257D01*
X607250Y243515D01*
X606981Y243618D01*
X606636D01*
G01X606981D02*
X607211Y243773D01*
X607403Y244032D01*
X607480Y244342D01*
X607403Y244652D01*
X607211Y244910D01*
X606866Y245065D01*
X606521Y245013D01*
X606176Y244807D01*
G01X597474Y237895D02*
X603674D01*
G01D02*
Y234695D01*
G01D02*
X597474D01*
G01D02*
Y237895D01*
G01X591911Y254967D02*
X595911D01*
G01X591921Y262905D02*
X593921D01*
G01X590096Y269058D02*
X590256Y268766D01*
X590470Y268600D01*
X590710Y268558D01*
X590923Y268600D01*
X591136Y268808D01*
X591270Y269058D01*
X591296Y269308D01*
X591243Y269600D01*
X591056Y269808D01*
X590870Y269891D01*
X590630D01*
G01X590870D02*
X591030Y270016D01*
X591163Y270225D01*
X591216Y270475D01*
X591163Y270725D01*
X591030Y270933D01*
X590790Y271058D01*
X590550Y271016D01*
X590310Y270850D01*
G01X592883Y268558D02*
X593070Y268600D01*
X593283Y268725D01*
X593416Y268933D01*
X593470Y269225D01*
X593416Y269516D01*
X593256Y269766D01*
X593016Y269891D01*
X592750D01*
X592590Y269975D01*
X592456Y270183D01*
X592403Y270475D01*
X592483Y270766D01*
X592670Y270975D01*
X592883Y271058D01*
X593096Y270975D01*
X593283Y270766D01*
X593363Y270475D01*
X593310Y270183D01*
X593176Y269975D01*
X593016Y269891D01*
X592750D01*
X592510Y269766D01*
X592350Y269516D01*
X592296Y269225D01*
X592350Y268933D01*
X592483Y268725D01*
X592696Y268600D01*
X592883Y268558D01*
G01X594561Y279923D02*
Y283023D01*
X595520D01*
X595826Y282868D01*
X596018Y282661D01*
X596095Y282248D01*
X596018Y281835D01*
X595788Y281576D01*
X595520Y281421D01*
X594561D01*
G01X595520D02*
X596095Y279923D01*
G01X597585Y280388D02*
X597815Y280130D01*
X598083Y279975D01*
X598428Y279923D01*
X598773Y280026D01*
X599041Y280233D01*
X599233Y280595D01*
X599271Y281008D01*
X599195Y281421D01*
X599003Y281680D01*
X598735Y281886D01*
X598466Y281938D01*
X598198Y281886D01*
X597853Y281680D01*
X597968Y283023D01*
X599003D01*
G01X601528D02*
X601221Y282920D01*
X600991Y282661D01*
X600838Y282351D01*
X600723Y281938D01*
X600685Y281473D01*
X600723Y281008D01*
X600838Y280595D01*
X600991Y280285D01*
X601221Y280026D01*
X601528Y279923D01*
X601835Y280026D01*
X602065Y280285D01*
X602218Y280595D01*
X602333Y281008D01*
X602371Y281473D01*
X602333Y281938D01*
X602218Y282351D01*
X602065Y282661D01*
X601835Y282920D01*
X601528Y283023D01*
G01X603785Y280388D02*
X604015Y280130D01*
X604283Y279975D01*
X604628Y279923D01*
X604973Y280026D01*
X605241Y280233D01*
X605433Y280595D01*
X605471Y281008D01*
X605395Y281421D01*
X605203Y281680D01*
X604935Y281886D01*
X604666Y281938D01*
X604398Y281886D01*
X604053Y281680D01*
X604168Y283023D01*
X605203D01*
G01X597607Y273493D02*
X603807D01*
G01D02*
Y270293D01*
G01D02*
X597607D01*
G01D02*
Y273493D01*
G01X603807Y274793D02*
X597607D01*
G01D02*
Y277993D01*
G01D02*
X603807D01*
G01D02*
Y274793D01*
G01X600991Y290015D02*
X600836Y289785D01*
X600733Y289517D01*
Y289210D01*
X600888Y288865D01*
X601146Y288597D01*
X601456Y288405D01*
X601973Y288252D01*
X602438Y288214D01*
X602903Y288290D01*
X603213Y288405D01*
X603523Y288635D01*
X603730Y288904D01*
X603833Y289172D01*
Y289440D01*
X603730Y289709D01*
X603575Y289939D01*
X603368Y290130D01*
G01X603213Y291429D02*
X603575Y291659D01*
X603781Y291965D01*
X603833Y292310D01*
X603781Y292617D01*
X603523Y292924D01*
X603213Y293115D01*
X602903Y293154D01*
X602541Y293077D01*
X602283Y292809D01*
X602180Y292540D01*
Y292195D01*
G01Y292540D02*
X602025Y292770D01*
X601766Y292962D01*
X601456Y293039D01*
X601146Y292962D01*
X600888Y292770D01*
X600733Y292425D01*
X600785Y292080D01*
X600991Y291735D01*
G01X603213Y294529D02*
X603575Y294759D01*
X603781Y295065D01*
X603833Y295410D01*
X603781Y295717D01*
X603523Y296024D01*
X603213Y296215D01*
X602903Y296254D01*
X602541Y296177D01*
X602283Y295909D01*
X602180Y295640D01*
Y295295D01*
G01Y295640D02*
X602025Y295870D01*
X601766Y296062D01*
X601456Y296139D01*
X601146Y296062D01*
X600888Y295870D01*
X600733Y295525D01*
X600785Y295180D01*
X600991Y294835D01*
G01X601250Y297744D02*
X600940Y297974D01*
X600785Y298242D01*
X600733Y298549D01*
X600836Y298932D01*
X601095Y299200D01*
X601405Y299277D01*
X601715Y299239D01*
X601973Y299085D01*
X602490Y298319D01*
X602851Y297974D01*
X603368Y297744D01*
X603833Y297667D01*
Y299277D01*
G01X594707Y294193D02*
Y287993D01*
G01X594607Y291093D02*
X591607D01*
G01X591507Y287993D02*
Y294193D01*
G01D02*
X594707D01*
G01Y287993D02*
X591507D01*
G01X596991Y290015D02*
X596836Y289785D01*
X596733Y289517D01*
Y289210D01*
X596888Y288865D01*
X597146Y288597D01*
X597456Y288405D01*
X597973Y288252D01*
X598438Y288214D01*
X598903Y288290D01*
X599213Y288405D01*
X599523Y288635D01*
X599730Y288904D01*
X599833Y289172D01*
Y289440D01*
X599730Y289709D01*
X599575Y289939D01*
X599368Y290130D01*
G01X599213Y291429D02*
X599575Y291659D01*
X599781Y291965D01*
X599833Y292310D01*
X599781Y292617D01*
X599523Y292924D01*
X599213Y293115D01*
X598903Y293154D01*
X598541Y293077D01*
X598283Y292809D01*
X598180Y292540D01*
Y292195D01*
G01Y292540D02*
X598025Y292770D01*
X597766Y292962D01*
X597456Y293039D01*
X597146Y292962D01*
X596888Y292770D01*
X596733Y292425D01*
X596785Y292080D01*
X596991Y291735D01*
G01X599213Y294529D02*
X599575Y294759D01*
X599781Y295065D01*
X599833Y295410D01*
X599781Y295717D01*
X599523Y296024D01*
X599213Y296215D01*
X598903Y296254D01*
X598541Y296177D01*
X598283Y295909D01*
X598180Y295640D01*
Y295295D01*
G01Y295640D02*
X598025Y295870D01*
X597766Y296062D01*
X597456Y296139D01*
X597146Y296062D01*
X596888Y295870D01*
X596733Y295525D01*
X596785Y295180D01*
X596991Y294835D01*
G01X599213Y297629D02*
X599575Y297859D01*
X599781Y298165D01*
X599833Y298510D01*
X599781Y298817D01*
X599523Y299124D01*
X599213Y299315D01*
X598903Y299354D01*
X598541Y299277D01*
X598283Y299009D01*
X598180Y298740D01*
Y298395D01*
G01Y298740D02*
X598025Y298970D01*
X597766Y299162D01*
X597456Y299239D01*
X597146Y299162D01*
X596888Y298970D01*
X596733Y298625D01*
X596785Y298280D01*
X596991Y297935D01*
G01X590707Y294193D02*
Y287993D01*
G01X594561Y283923D02*
Y287023D01*
X595520D01*
X595826Y286868D01*
X596018Y286661D01*
X596095Y286248D01*
X596018Y285835D01*
X595788Y285576D01*
X595520Y285421D01*
X594561D01*
G01X595520D02*
X596095Y283923D01*
G01X597585Y284388D02*
X597815Y284130D01*
X598083Y283975D01*
X598428Y283923D01*
X598773Y284026D01*
X599041Y284233D01*
X599233Y284595D01*
X599271Y285008D01*
X599195Y285421D01*
X599003Y285680D01*
X598735Y285886D01*
X598466Y285938D01*
X598198Y285886D01*
X597853Y285680D01*
X597968Y287023D01*
X599003D01*
G01X601528D02*
X601221Y286920D01*
X600991Y286661D01*
X600838Y286351D01*
X600723Y285938D01*
X600685Y285473D01*
X600723Y285008D01*
X600838Y284595D01*
X600991Y284285D01*
X601221Y284026D01*
X601528Y283923D01*
X601835Y284026D01*
X602065Y284285D01*
X602218Y284595D01*
X602333Y285008D01*
X602371Y285473D01*
X602333Y285938D01*
X602218Y286351D01*
X602065Y286661D01*
X601835Y286920D01*
X601528Y287023D01*
G01X605088Y283923D02*
Y287023D01*
X603670Y284801D01*
X605586D01*
G01X590199Y341575D02*
Y344675D01*
X591158D01*
X591464Y344520D01*
X591656Y344313D01*
X591733Y343900D01*
X591656Y343487D01*
X591426Y343228D01*
X591158Y343073D01*
X590199D01*
G01X591158D02*
X591733Y341575D01*
G01X593223Y342040D02*
X593453Y341782D01*
X593721Y341627D01*
X594066Y341575D01*
X594411Y341678D01*
X594679Y341885D01*
X594871Y342247D01*
X594909Y342660D01*
X594833Y343073D01*
X594641Y343332D01*
X594373Y343538D01*
X594104Y343590D01*
X593836Y343538D01*
X593491Y343332D01*
X593606Y344675D01*
X594641D01*
G01X596438Y344158D02*
X596668Y344468D01*
X596936Y344623D01*
X597243Y344675D01*
X597626Y344572D01*
X597894Y344313D01*
X597971Y344003D01*
X597933Y343693D01*
X597779Y343435D01*
X597013Y342918D01*
X596668Y342557D01*
X596438Y342040D01*
X596361Y341575D01*
X597971D01*
G01X600266D02*
X600534Y341627D01*
X600841Y341782D01*
X601033Y342040D01*
X601109Y342402D01*
X601033Y342763D01*
X600803Y343073D01*
X600458Y343228D01*
X600074D01*
X599844Y343332D01*
X599653Y343590D01*
X599576Y343952D01*
X599691Y344313D01*
X599959Y344572D01*
X600266Y344675D01*
X600573Y344572D01*
X600841Y344313D01*
X600956Y343952D01*
X600879Y343590D01*
X600688Y343332D01*
X600458Y343228D01*
X600074D01*
X599729Y343073D01*
X599499Y342763D01*
X599423Y342402D01*
X599499Y342040D01*
X599691Y341782D01*
X599998Y341627D01*
X600266Y341575D01*
G01X602738Y340085D02*
Y346285D01*
G01X605938Y340085D02*
X602738D01*
G01X590952Y351505D02*
Y354605D01*
X591911D01*
X592217Y354450D01*
X592409Y354243D01*
X592486Y353830D01*
X592409Y353417D01*
X592179Y353158D01*
X591911Y353003D01*
X590952D01*
G01X591911D02*
X592486Y351505D01*
G01X593976Y351970D02*
X594206Y351712D01*
X594474Y351557D01*
X594819Y351505D01*
X595164Y351608D01*
X595432Y351815D01*
X595624Y352177D01*
X595662Y352590D01*
X595586Y353003D01*
X595394Y353262D01*
X595126Y353468D01*
X594857Y353520D01*
X594589Y353468D01*
X594244Y353262D01*
X594359Y354605D01*
X595394D01*
G01X597076Y352125D02*
X597306Y351763D01*
X597612Y351557D01*
X597957Y351505D01*
X598264Y351557D01*
X598571Y351815D01*
X598762Y352125D01*
X598801Y352435D01*
X598724Y352797D01*
X598456Y353055D01*
X598187Y353158D01*
X597842D01*
G01X598187D02*
X598417Y353313D01*
X598609Y353572D01*
X598686Y353882D01*
X598609Y354192D01*
X598417Y354450D01*
X598072Y354605D01*
X597727Y354553D01*
X597382Y354347D01*
G01X601019Y354605D02*
X600712Y354502D01*
X600482Y354243D01*
X600329Y353933D01*
X600214Y353520D01*
X600176Y353055D01*
X600214Y352590D01*
X600329Y352177D01*
X600482Y351867D01*
X600712Y351608D01*
X601019Y351505D01*
X601326Y351608D01*
X601556Y351867D01*
X601709Y352177D01*
X601824Y352590D01*
X601862Y353055D01*
X601824Y353520D01*
X601709Y353933D01*
X601556Y354243D01*
X601326Y354502D01*
X601019Y354605D01*
G01X602491Y354279D02*
X605691D01*
G01X602491Y348079D02*
Y354279D01*
G01X605691Y348079D02*
X602491D01*
G01X591454Y359792D02*
Y362892D01*
X592413D01*
X592719Y362737D01*
X592911Y362530D01*
X592988Y362117D01*
X592911Y361704D01*
X592681Y361445D01*
X592413Y361290D01*
X591454D01*
G01X592413D02*
X592988Y359792D01*
G01X594478Y360257D02*
X594708Y359999D01*
X594976Y359844D01*
X595321Y359792D01*
X595666Y359895D01*
X595934Y360102D01*
X596126Y360464D01*
X596164Y360877D01*
X596088Y361290D01*
X595896Y361549D01*
X595628Y361755D01*
X595359Y361807D01*
X595091Y361755D01*
X594746Y361549D01*
X594861Y362892D01*
X595896D01*
G01X597578Y360412D02*
X597808Y360050D01*
X598114Y359844D01*
X598459Y359792D01*
X598766Y359844D01*
X599073Y360102D01*
X599264Y360412D01*
X599303Y360722D01*
X599226Y361084D01*
X598958Y361342D01*
X598689Y361445D01*
X598344D01*
G01X598689D02*
X598919Y361600D01*
X599111Y361859D01*
X599188Y362169D01*
X599111Y362479D01*
X598919Y362737D01*
X598574Y362892D01*
X598229Y362840D01*
X597884Y362634D01*
G01X601521Y359792D02*
Y362892D01*
X601061Y362272D01*
G01Y359792D02*
X601981D01*
G01X602893Y356465D02*
Y362665D01*
G01X606093Y356465D02*
X602893D01*
G01X602738Y346285D02*
X605938D01*
G01X602893Y362665D02*
X606093D01*
G01X605038Y406651D02*
X601938D01*
Y407610D01*
X602093Y407916D01*
X602300Y408108D01*
X602713Y408185D01*
X603126Y408108D01*
X603385Y407878D01*
X603540Y407610D01*
Y406651D01*
G01Y407610D02*
X605038Y408185D01*
G01X604573Y409675D02*
X604831Y409905D01*
X604986Y410173D01*
X605038Y410518D01*
X604935Y410863D01*
X604728Y411131D01*
X604366Y411323D01*
X603953Y411361D01*
X603540Y411285D01*
X603281Y411093D01*
X603075Y410825D01*
X603023Y410556D01*
X603075Y410288D01*
X603281Y409943D01*
X601938Y410058D01*
Y411093D01*
G01X602455Y412890D02*
X602145Y413120D01*
X601990Y413388D01*
X601938Y413695D01*
X602041Y414078D01*
X602300Y414346D01*
X602610Y414423D01*
X602920Y414385D01*
X603178Y414231D01*
X603695Y413465D01*
X604056Y413120D01*
X604573Y412890D01*
X605038Y412813D01*
Y414423D01*
G01X601938Y416718D02*
X602041Y416411D01*
X602300Y416181D01*
X602610Y416028D01*
X603023Y415913D01*
X603488Y415875D01*
X603953Y415913D01*
X604366Y416028D01*
X604676Y416181D01*
X604935Y416411D01*
X605038Y416718D01*
X604935Y417025D01*
X604676Y417255D01*
X604366Y417408D01*
X603953Y417523D01*
X603488Y417561D01*
X603023Y417523D01*
X602610Y417408D01*
X602300Y417255D01*
X602041Y417025D01*
X601938Y416718D01*
G01X595803Y448717D02*
Y451817D01*
X596762D01*
X597068Y451662D01*
X597260Y451455D01*
X597337Y451042D01*
X597260Y450629D01*
X597030Y450370D01*
X596762Y450215D01*
X595803D01*
G01X596762D02*
X597337Y448717D01*
G01X598942Y450009D02*
X599210Y450370D01*
X599440Y450577D01*
X599747Y450680D01*
X600015Y450577D01*
X600207Y450370D01*
X600360Y450060D01*
X600398Y449699D01*
X600360Y449389D01*
X600207Y449079D01*
X599977Y448820D01*
X599708Y448717D01*
X599402Y448820D01*
X599133Y449130D01*
X598980Y449595D01*
X598942Y450112D01*
X599018Y450784D01*
X599133Y451145D01*
X599325Y451507D01*
X599593Y451765D01*
X599862Y451817D01*
X600130Y451714D01*
X600322Y451455D01*
G01X603230Y448717D02*
Y451817D01*
X601812Y449595D01*
X603728D01*
G01X605027Y449337D02*
X605257Y448975D01*
X605563Y448769D01*
X605908Y448717D01*
X606215Y448769D01*
X606522Y449027D01*
X606713Y449337D01*
X606752Y449647D01*
X606675Y450009D01*
X606407Y450267D01*
X606138Y450370D01*
X605793D01*
G01X606138D02*
X606368Y450525D01*
X606560Y450784D01*
X606637Y451094D01*
X606560Y451404D01*
X606368Y451662D01*
X606023Y451817D01*
X605678Y451765D01*
X605333Y451559D01*
G01X604541Y455194D02*
Y458294D01*
X605500D01*
X605806Y458139D01*
X605998Y457932D01*
X606075Y457519D01*
X605998Y457106D01*
X605768Y456847D01*
X605500Y456692D01*
X604541D01*
G01X605500D02*
X606075Y455194D01*
G01X608408D02*
Y458294D01*
X607948Y457674D01*
G01Y455194D02*
X608868D01*
G01X610780Y457777D02*
X611010Y458087D01*
X611278Y458242D01*
X611585Y458294D01*
X611968Y458191D01*
X612236Y457932D01*
X612313Y457622D01*
X612275Y457312D01*
X612121Y457054D01*
X611355Y456537D01*
X611010Y456176D01*
X610780Y455659D01*
X610703Y455194D01*
X612313D01*
G01X615068D02*
Y458294D01*
X613650Y456072D01*
X615566D01*
G01X617708Y455194D02*
X617976Y455246D01*
X618283Y455401D01*
X618475Y455659D01*
X618551Y456021D01*
X618475Y456382D01*
X618245Y456692D01*
X617900Y456847D01*
X617516D01*
X617286Y456951D01*
X617095Y457209D01*
X617018Y457571D01*
X617133Y457932D01*
X617401Y458191D01*
X617708Y458294D01*
X618015Y458191D01*
X618283Y457932D01*
X618398Y457571D01*
X618321Y457209D01*
X618130Y456951D01*
X617900Y456847D01*
X617516D01*
X617171Y456692D01*
X616941Y456382D01*
X616865Y456021D01*
X616941Y455659D01*
X617133Y455401D01*
X617440Y455246D01*
X617708Y455194D01*
G01X589747Y465737D02*
Y463515D01*
X589900Y463050D01*
X590207Y462740D01*
X590590Y462637D01*
X590973Y462740D01*
X591280Y463050D01*
X591433Y463515D01*
Y465737D01*
G01X592962Y463929D02*
X593230Y464290D01*
X593460Y464497D01*
X593767Y464600D01*
X594035Y464497D01*
X594227Y464290D01*
X594380Y463980D01*
X594418Y463619D01*
X594380Y463309D01*
X594227Y462999D01*
X593997Y462740D01*
X593728Y462637D01*
X593422Y462740D01*
X593153Y463050D01*
X593000Y463515D01*
X592962Y464032D01*
X593038Y464704D01*
X593153Y465065D01*
X593345Y465427D01*
X593613Y465685D01*
X593882Y465737D01*
X594150Y465634D01*
X594342Y465375D01*
G01X596790Y465737D02*
X596483Y465634D01*
X596253Y465375D01*
X596100Y465065D01*
X595985Y464652D01*
X595947Y464187D01*
X595985Y463722D01*
X596100Y463309D01*
X596253Y462999D01*
X596483Y462740D01*
X596790Y462637D01*
X597097Y462740D01*
X597327Y462999D01*
X597480Y463309D01*
X597595Y463722D01*
X597633Y464187D01*
X597595Y464652D01*
X597480Y465065D01*
X597327Y465375D01*
X597097Y465634D01*
X596790Y465737D01*
G01X590347Y460177D02*
Y457955D01*
X590500Y457490D01*
X590807Y457180D01*
X591190Y457077D01*
X591573Y457180D01*
X591880Y457490D01*
X592033Y457955D01*
Y460177D01*
G01X593562Y458369D02*
X593830Y458730D01*
X594060Y458937D01*
X594367Y459040D01*
X594635Y458937D01*
X594827Y458730D01*
X594980Y458420D01*
X595018Y458059D01*
X594980Y457749D01*
X594827Y457439D01*
X594597Y457180D01*
X594328Y457077D01*
X594022Y457180D01*
X593753Y457490D01*
X593600Y457955D01*
X593562Y458472D01*
X593638Y459144D01*
X593753Y459505D01*
X593945Y459867D01*
X594213Y460125D01*
X594482Y460177D01*
X594750Y460074D01*
X594942Y459815D01*
G01X597390Y457077D02*
Y460177D01*
X596930Y459557D01*
G01Y457077D02*
X597850D01*
G01X606290Y462196D02*
X606060Y462351D01*
X605792Y462454D01*
X605485D01*
X605140Y462299D01*
X604872Y462041D01*
X604680Y461731D01*
X604527Y461214D01*
X604489Y460749D01*
X604565Y460284D01*
X604680Y459974D01*
X604910Y459664D01*
X605179Y459457D01*
X605447Y459354D01*
X605715D01*
X605984Y459457D01*
X606214Y459612D01*
X606405Y459819D01*
G01X607704D02*
X607934Y459561D01*
X608202Y459406D01*
X608547Y459354D01*
X608892Y459457D01*
X609160Y459664D01*
X609352Y460026D01*
X609390Y460439D01*
X609314Y460852D01*
X609122Y461111D01*
X608854Y461317D01*
X608585Y461369D01*
X608317Y461317D01*
X607972Y461111D01*
X608087Y462454D01*
X609122D01*
G01X610919Y460646D02*
X611187Y461007D01*
X611417Y461214D01*
X611724Y461317D01*
X611992Y461214D01*
X612184Y461007D01*
X612337Y460697D01*
X612375Y460336D01*
X612337Y460026D01*
X612184Y459716D01*
X611954Y459457D01*
X611685Y459354D01*
X611379Y459457D01*
X611110Y459767D01*
X610957Y460232D01*
X610919Y460749D01*
X610995Y461421D01*
X611110Y461782D01*
X611302Y462144D01*
X611570Y462402D01*
X611839Y462454D01*
X612107Y462351D01*
X612299Y462092D01*
G01X614670Y459354D02*
X614747Y460026D01*
X614862Y460594D01*
X615015Y461111D01*
X615207Y461679D01*
X615514Y462454D01*
X613980D01*
G01X596547Y466446D02*
X593447D01*
Y467405D01*
X593602Y467711D01*
X593809Y467903D01*
X594222Y467980D01*
X594635Y467903D01*
X594894Y467673D01*
X595049Y467405D01*
Y466446D01*
G01Y467405D02*
X596547Y467980D01*
G01Y470236D02*
X595875Y470313D01*
X595307Y470428D01*
X594790Y470581D01*
X594222Y470773D01*
X593447Y471080D01*
Y469546D01*
G01X596185Y472761D02*
X596444Y473030D01*
X596547Y473336D01*
X596444Y473643D01*
X596134Y473911D01*
X595669Y474103D01*
X595204Y474180D01*
X594635D01*
X594170Y474103D01*
X593757Y473911D01*
X593550Y473681D01*
X593447Y473413D01*
X593550Y473106D01*
X593757Y472876D01*
X594067Y472723D01*
X594480Y472646D01*
X594842Y472723D01*
X595204Y472915D01*
X595410Y473145D01*
X595462Y473413D01*
X595359Y473720D01*
X595100Y473950D01*
X594635Y474180D01*
G01X596547Y476513D02*
X596495Y476781D01*
X596340Y477088D01*
X596082Y477280D01*
X595720Y477356D01*
X595359Y477280D01*
X595049Y477050D01*
X594894Y476705D01*
Y476321D01*
X594790Y476091D01*
X594532Y475900D01*
X594170Y475823D01*
X593809Y475938D01*
X593550Y476206D01*
X593447Y476513D01*
X593550Y476820D01*
X593809Y477088D01*
X594170Y477203D01*
X594532Y477126D01*
X594790Y476935D01*
X594894Y476705D01*
Y476321D01*
X595049Y475976D01*
X595359Y475746D01*
X595720Y475670D01*
X596082Y475746D01*
X596340Y475938D01*
X596495Y476245D01*
X596547Y476513D01*
G01X600432Y466585D02*
X597332D01*
Y467544D01*
X597487Y467850D01*
X597694Y468042D01*
X598107Y468119D01*
X598520Y468042D01*
X598779Y467812D01*
X598934Y467544D01*
Y466585D01*
G01Y467544D02*
X600432Y468119D01*
G01Y470375D02*
X599760Y470452D01*
X599192Y470567D01*
X598675Y470720D01*
X598107Y470912D01*
X597332Y471219D01*
Y469685D01*
G01X600070Y472900D02*
X600329Y473169D01*
X600432Y473475D01*
X600329Y473782D01*
X600019Y474050D01*
X599554Y474242D01*
X599089Y474319D01*
X598520D01*
X598055Y474242D01*
X597642Y474050D01*
X597435Y473820D01*
X597332Y473552D01*
X597435Y473245D01*
X597642Y473015D01*
X597952Y472862D01*
X598365Y472785D01*
X598727Y472862D01*
X599089Y473054D01*
X599295Y473284D01*
X599347Y473552D01*
X599244Y473859D01*
X598985Y474089D01*
X598520Y474319D01*
G01X600432Y476575D02*
X599760Y476652D01*
X599192Y476767D01*
X598675Y476920D01*
X598107Y477112D01*
X597332Y477419D01*
Y475885D01*
G01X604432Y466585D02*
X601332D01*
Y467544D01*
X601487Y467850D01*
X601694Y468042D01*
X602107Y468119D01*
X602520Y468042D01*
X602779Y467812D01*
X602934Y467544D01*
Y466585D01*
G01Y467544D02*
X604432Y468119D01*
G01Y470375D02*
X603760Y470452D01*
X603192Y470567D01*
X602675Y470720D01*
X602107Y470912D01*
X601332Y471219D01*
Y469685D01*
G01X604070Y472900D02*
X604329Y473169D01*
X604432Y473475D01*
X604329Y473782D01*
X604019Y474050D01*
X603554Y474242D01*
X603089Y474319D01*
X602520D01*
X602055Y474242D01*
X601642Y474050D01*
X601435Y473820D01*
X601332Y473552D01*
X601435Y473245D01*
X601642Y473015D01*
X601952Y472862D01*
X602365Y472785D01*
X602727Y472862D01*
X603089Y473054D01*
X603295Y473284D01*
X603347Y473552D01*
X603244Y473859D01*
X602985Y474089D01*
X602520Y474319D01*
G01X603140Y475924D02*
X602779Y476192D01*
X602572Y476422D01*
X602469Y476729D01*
X602572Y476997D01*
X602779Y477189D01*
X603089Y477342D01*
X603450Y477380D01*
X603760Y477342D01*
X604070Y477189D01*
X604329Y476959D01*
X604432Y476690D01*
X604329Y476384D01*
X604019Y476115D01*
X603554Y475962D01*
X603037Y475924D01*
X602365Y476000D01*
X602004Y476115D01*
X601642Y476307D01*
X601384Y476575D01*
X601332Y476844D01*
X601435Y477112D01*
X601694Y477304D01*
G01X604800Y493820D02*
X620520D01*
G01X589465Y487160D02*
X593049D01*
Y493948D01*
X593070D01*
X595263Y491755D01*
X595242Y491734D01*
X590414D01*
X592649Y493969D01*
X592986D01*
G01X592392Y495631D02*
X592552Y495339D01*
X592766Y495173D01*
X593006Y495131D01*
X593219Y495173D01*
X593432Y495381D01*
X593566Y495631D01*
X593592Y495881D01*
X593539Y496173D01*
X593352Y496381D01*
X593166Y496464D01*
X592926D01*
G01X593166D02*
X593326Y496589D01*
X593459Y496798D01*
X593512Y497048D01*
X593459Y497298D01*
X593326Y497506D01*
X593086Y497631D01*
X592846Y497589D01*
X592606Y497423D01*
G01X596645Y491418D02*
X596952Y491160D01*
X597297Y491005D01*
X597603D01*
X597910Y491160D01*
X598140Y491418D01*
X598255Y491780D01*
X598178Y492142D01*
X597987Y492452D01*
X597642Y492658D01*
X597182Y492762D01*
X596913Y492968D01*
X596798Y493330D01*
X596875Y493692D01*
X597067Y493950D01*
X597335Y494105D01*
X597603D01*
X597872Y494002D01*
X598102Y493743D01*
G01X599707Y491625D02*
X599937Y491263D01*
X600243Y491057D01*
X600588Y491005D01*
X600895Y491057D01*
X601202Y491315D01*
X601393Y491625D01*
X601432Y491935D01*
X601355Y492297D01*
X601087Y492555D01*
X600818Y492658D01*
X600473D01*
G01X600818D02*
X601048Y492813D01*
X601240Y493072D01*
X601317Y493382D01*
X601240Y493692D01*
X601048Y493950D01*
X600703Y494105D01*
X600358Y494053D01*
X600013Y493847D01*
G01X596613Y498712D02*
Y496912D01*
G01D02*
X621013D01*
G01X591430Y510625D02*
Y513125D01*
X591110Y512625D01*
G01Y510625D02*
X591750D01*
G01X596613Y514412D02*
Y503912D01*
G01Y519612D02*
Y521312D01*
G01D02*
X621013D01*
G01X604501Y533708D02*
Y530508D01*
G01X598301D02*
Y533708D01*
G01X604501Y530508D02*
X598301D01*
G01X601401Y533608D02*
Y530608D01*
G01X598301Y533708D02*
X604501D01*
G01X596087Y525703D02*
X595857Y525858D01*
X595589Y525961D01*
X595282D01*
X594937Y525806D01*
X594669Y525548D01*
X594477Y525238D01*
X594324Y524721D01*
X594286Y524256D01*
X594362Y523791D01*
X594477Y523481D01*
X594707Y523171D01*
X594976Y522964D01*
X595244Y522861D01*
X595512D01*
X595781Y522964D01*
X596011Y523119D01*
X596202Y523326D01*
G01X598344Y522861D02*
X598612Y522913D01*
X598919Y523068D01*
X599111Y523326D01*
X599187Y523688D01*
X599111Y524049D01*
X598881Y524359D01*
X598536Y524514D01*
X598152D01*
X597922Y524618D01*
X597731Y524876D01*
X597654Y525238D01*
X597769Y525599D01*
X598037Y525858D01*
X598344Y525961D01*
X598651Y525858D01*
X598919Y525599D01*
X599034Y525238D01*
X598957Y524876D01*
X598766Y524618D01*
X598536Y524514D01*
X598152D01*
X597807Y524359D01*
X597577Y524049D01*
X597501Y523688D01*
X597577Y523326D01*
X597769Y523068D01*
X598076Y522913D01*
X598344Y522861D01*
G01X601444Y525961D02*
X601137Y525858D01*
X600907Y525599D01*
X600754Y525289D01*
X600639Y524876D01*
X600601Y524411D01*
X600639Y523946D01*
X600754Y523533D01*
X600907Y523223D01*
X601137Y522964D01*
X601444Y522861D01*
X601751Y522964D01*
X601981Y523223D01*
X602134Y523533D01*
X602249Y523946D01*
X602287Y524411D01*
X602249Y524876D01*
X602134Y525289D01*
X601981Y525599D01*
X601751Y525858D01*
X601444Y525961D01*
G01X603816Y525444D02*
X604046Y525754D01*
X604314Y525909D01*
X604621Y525961D01*
X605004Y525858D01*
X605272Y525599D01*
X605349Y525289D01*
X605311Y524979D01*
X605157Y524721D01*
X604391Y524204D01*
X604046Y523843D01*
X603816Y523326D01*
X603739Y522861D01*
X605349D01*
G01X604621Y529147D02*
X604781Y528855D01*
X604995Y528689D01*
X605235Y528647D01*
X605448Y528689D01*
X605661Y528897D01*
X605795Y529147D01*
X605821Y529397D01*
X605768Y529689D01*
X605581Y529897D01*
X605395Y529980D01*
X605155D01*
G01X605395D02*
X605555Y530105D01*
X605688Y530314D01*
X605741Y530564D01*
X605688Y530814D01*
X605555Y531022D01*
X605315Y531147D01*
X605075Y531105D01*
X604835Y530939D01*
G01X598301Y542508D02*
Y545708D01*
G01X604501Y542508D02*
X598301D01*
G01X604501Y545708D02*
Y542508D01*
G01X598301Y545708D02*
X604501D01*
G01Y538508D02*
X598301D01*
G01X604501Y541708D02*
Y538508D01*
G01X598301Y541708D02*
X604501D01*
G01X598301Y538508D02*
Y541708D01*
G01Y534508D02*
Y537708D01*
G01X604501Y534508D02*
X598301D01*
G01Y537708D02*
X604501D01*
G01D02*
Y534508D01*
G01X598037Y565645D02*
Y559445D01*
G01D02*
X594837D01*
G01D02*
Y565645D01*
G01X602037D02*
Y559445D01*
G01D02*
X598837D01*
G01D02*
Y565645D01*
G01X606037Y559445D02*
X602837D01*
G01D02*
Y565645D01*
G01X594037D02*
Y559445D01*
G01D02*
X590837D01*
G01D02*
Y565645D01*
G01X590037D02*
Y559445D01*
G01X604861Y576346D02*
X607244D01*
Y580905D01*
G01X601065Y577403D02*
Y580403D01*
G01X597965Y580503D02*
X604165D01*
G01D02*
Y577303D01*
G01D02*
X597965D01*
G01D02*
Y580503D01*
G01X604165Y573303D02*
X597965D01*
G01X601065Y573403D02*
Y576403D01*
G01X597965Y576503D02*
X604165D01*
G01D02*
Y573303D01*
G01X597965D02*
Y576503D01*
G01X593599Y568553D02*
X591099D01*
Y569219D01*
X591224Y569433D01*
X591391Y569566D01*
X591724Y569619D01*
X592057Y569566D01*
X592266Y569406D01*
X592391Y569219D01*
Y568553D01*
G01Y569219D02*
X593599Y569619D01*
G01X593224Y570699D02*
X593432Y570859D01*
X593557Y571046D01*
X593599Y571286D01*
X593516Y571526D01*
X593349Y571713D01*
X593057Y571846D01*
X592724Y571873D01*
X592391Y571819D01*
X592182Y571686D01*
X592016Y571499D01*
X591974Y571313D01*
X592016Y571126D01*
X592182Y570886D01*
X591099Y570966D01*
Y571686D01*
G01X592557Y572979D02*
X592266Y573166D01*
X592099Y573326D01*
X592016Y573539D01*
X592099Y573726D01*
X592266Y573859D01*
X592516Y573966D01*
X592807Y573993D01*
X593057Y573966D01*
X593307Y573859D01*
X593516Y573699D01*
X593599Y573513D01*
X593516Y573299D01*
X593266Y573113D01*
X592891Y573006D01*
X592474Y572979D01*
X591932Y573033D01*
X591641Y573113D01*
X591349Y573246D01*
X591141Y573433D01*
X591099Y573619D01*
X591182Y573806D01*
X591391Y573939D01*
G01X593307Y575233D02*
X593516Y575419D01*
X593599Y575633D01*
X593516Y575846D01*
X593266Y576033D01*
X592891Y576166D01*
X592516Y576219D01*
X592057D01*
X591682Y576166D01*
X591349Y576033D01*
X591182Y575873D01*
X591099Y575686D01*
X591182Y575473D01*
X591349Y575313D01*
X591599Y575206D01*
X591932Y575153D01*
X592224Y575206D01*
X592516Y575339D01*
X592682Y575499D01*
X592724Y575686D01*
X592641Y575899D01*
X592432Y576059D01*
X592057Y576219D01*
G01X594837Y565645D02*
X598037D01*
G01X596799Y568551D02*
X594299D01*
Y569217D01*
X594424Y569431D01*
X594591Y569564D01*
X594924Y569617D01*
X595257Y569564D01*
X595466Y569404D01*
X595591Y569217D01*
Y568551D01*
G01Y569217D02*
X596799Y569617D01*
G01X596424Y570697D02*
X596632Y570857D01*
X596757Y571044D01*
X596799Y571284D01*
X596716Y571524D01*
X596549Y571711D01*
X596257Y571844D01*
X595924Y571871D01*
X595591Y571817D01*
X595382Y571684D01*
X595216Y571497D01*
X595174Y571311D01*
X595216Y571124D01*
X595382Y570884D01*
X594299Y570964D01*
Y571684D01*
G01X596507Y573031D02*
X596716Y573217D01*
X596799Y573431D01*
X596716Y573644D01*
X596466Y573831D01*
X596091Y573964D01*
X595716Y574017D01*
X595257D01*
X594882Y573964D01*
X594549Y573831D01*
X594382Y573671D01*
X594299Y573484D01*
X594382Y573271D01*
X594549Y573111D01*
X594799Y573004D01*
X595132Y572951D01*
X595424Y573004D01*
X595716Y573137D01*
X595882Y573297D01*
X595924Y573484D01*
X595841Y573697D01*
X595632Y573857D01*
X595257Y574017D01*
G01X596799Y575684D02*
X594299D01*
X594799Y575364D01*
G01X596799D02*
Y576004D01*
G01X598837Y565645D02*
X602037D01*
G01X602837D02*
X606037D01*
G01X590837D02*
X594037D01*
G01X597269Y595689D02*
X597109Y595814D01*
X596922Y595897D01*
X596709D01*
X596469Y595772D01*
X596282Y595564D01*
X596149Y595314D01*
X596042Y594897D01*
X596015Y594522D01*
X596069Y594147D01*
X596149Y593897D01*
X596309Y593647D01*
X596495Y593480D01*
X596682Y593397D01*
X596869D01*
X597055Y593480D01*
X597215Y593605D01*
X597349Y593772D01*
G01X598295D02*
X598455Y593564D01*
X598642Y593439D01*
X598882Y593397D01*
X599122Y593480D01*
X599309Y593647D01*
X599442Y593939D01*
X599469Y594272D01*
X599415Y594605D01*
X599282Y594814D01*
X599095Y594980D01*
X598909Y595022D01*
X598722Y594980D01*
X598482Y594814D01*
X598562Y595897D01*
X599282D01*
G01X600575Y595480D02*
X600735Y595730D01*
X600922Y595855D01*
X601135Y595897D01*
X601402Y595814D01*
X601589Y595605D01*
X601642Y595355D01*
X601615Y595105D01*
X601509Y594897D01*
X600975Y594480D01*
X600735Y594189D01*
X600575Y593772D01*
X600522Y593397D01*
X601642D01*
G01X603282D02*
X603469Y593439D01*
X603682Y593564D01*
X603815Y593772D01*
X603869Y594064D01*
X603815Y594355D01*
X603655Y594605D01*
X603415Y594730D01*
X603149D01*
X602989Y594814D01*
X602855Y595022D01*
X602802Y595314D01*
X602882Y595605D01*
X603069Y595814D01*
X603282Y595897D01*
X603495Y595814D01*
X603682Y595605D01*
X603762Y595314D01*
X603709Y595022D01*
X603575Y594814D01*
X603415Y594730D01*
X603149D01*
X602909Y594605D01*
X602749Y594355D01*
X602695Y594064D01*
X602749Y593772D01*
X602882Y593564D01*
X603095Y593439D01*
X603282Y593397D01*
G01X597182Y599026D02*
X597022Y599151D01*
X596835Y599234D01*
X596622D01*
X596382Y599109D01*
X596195Y598901D01*
X596062Y598651D01*
X595955Y598234D01*
X595928Y597859D01*
X595982Y597484D01*
X596062Y597234D01*
X596222Y596984D01*
X596408Y596817D01*
X596595Y596734D01*
X596782D01*
X596968Y596817D01*
X597128Y596942D01*
X597262Y597109D01*
G01X598208D02*
X598368Y596901D01*
X598555Y596776D01*
X598795Y596734D01*
X599035Y596817D01*
X599222Y596984D01*
X599355Y597276D01*
X599382Y597609D01*
X599328Y597942D01*
X599195Y598151D01*
X599008Y598317D01*
X598822Y598359D01*
X598635Y598317D01*
X598395Y598151D01*
X598475Y599234D01*
X599195D01*
G01X600488Y598817D02*
X600648Y599067D01*
X600835Y599192D01*
X601048Y599234D01*
X601315Y599151D01*
X601502Y598942D01*
X601555Y598692D01*
X601528Y598442D01*
X601422Y598234D01*
X600888Y597817D01*
X600648Y597526D01*
X600488Y597109D01*
X600435Y596734D01*
X601555D01*
G01X603142D02*
X603195Y597276D01*
X603275Y597734D01*
X603382Y598151D01*
X603515Y598609D01*
X603728Y599234D01*
X602662D01*
G01X601065Y581403D02*
Y584403D01*
G01X597965Y584503D02*
X604165D01*
G01D02*
Y581303D01*
G01D02*
X597965D01*
G01D02*
Y584503D01*
G01X604165Y588503D02*
Y585303D01*
G01D02*
X597965D01*
G01Y588503D02*
X604165D01*
G01X597965Y585303D02*
Y588503D01*
G01X604132Y592705D02*
Y589505D01*
G01D02*
X597932D01*
G01Y592705D02*
X604132D01*
G01X597932Y589505D02*
Y592705D01*
G01X594937Y613045D02*
Y610045D01*
G01X598037Y609945D02*
X591837D01*
G01D02*
Y613145D01*
G01X598037D02*
Y609945D01*
G01X596062Y600006D02*
Y602506D01*
X596728D01*
X596942Y602381D01*
X597075Y602214D01*
X597128Y601881D01*
X597075Y601548D01*
X596915Y601339D01*
X596728Y601214D01*
X596062D01*
G01X596728D02*
X597128Y600006D01*
G01X598208Y600381D02*
X598368Y600173D01*
X598555Y600048D01*
X598795Y600006D01*
X599035Y600089D01*
X599222Y600256D01*
X599355Y600548D01*
X599382Y600881D01*
X599328Y601214D01*
X599195Y601423D01*
X599008Y601589D01*
X598822Y601631D01*
X598635Y601589D01*
X598395Y601423D01*
X598475Y602506D01*
X599195D01*
G01X600995Y600006D02*
X601182Y600048D01*
X601395Y600173D01*
X601528Y600381D01*
X601582Y600673D01*
X601528Y600964D01*
X601368Y601214D01*
X601128Y601339D01*
X600862D01*
X600702Y601423D01*
X600568Y601631D01*
X600515Y601923D01*
X600595Y602214D01*
X600782Y602423D01*
X600995Y602506D01*
X601208Y602423D01*
X601395Y602214D01*
X601475Y601923D01*
X601422Y601631D01*
X601288Y601423D01*
X601128Y601339D01*
X600862D01*
X600622Y601214D01*
X600462Y600964D01*
X600408Y600673D01*
X600462Y600381D01*
X600595Y600173D01*
X600808Y600048D01*
X600995Y600006D01*
G01X603195D02*
X603382Y600048D01*
X603595Y600173D01*
X603728Y600381D01*
X603782Y600673D01*
X603728Y600964D01*
X603568Y601214D01*
X603328Y601339D01*
X603062D01*
X602902Y601423D01*
X602768Y601631D01*
X602715Y601923D01*
X602795Y602214D01*
X602982Y602423D01*
X603195Y602506D01*
X603408Y602423D01*
X603595Y602214D01*
X603675Y601923D01*
X603622Y601631D01*
X603488Y601423D01*
X603328Y601339D01*
X603062D01*
X602822Y601214D01*
X602662Y600964D01*
X602608Y600673D01*
X602662Y600381D01*
X602795Y600173D01*
X603008Y600048D01*
X603195Y600006D01*
G01X596231Y604057D02*
Y606557D01*
X596897D01*
X597111Y606432D01*
X597244Y606265D01*
X597297Y605932D01*
X597244Y605599D01*
X597084Y605390D01*
X596897Y605265D01*
X596231D01*
G01X596897D02*
X597297Y604057D01*
G01X598377Y604432D02*
X598537Y604224D01*
X598724Y604099D01*
X598964Y604057D01*
X599204Y604140D01*
X599391Y604307D01*
X599524Y604599D01*
X599551Y604932D01*
X599497Y605265D01*
X599364Y605474D01*
X599177Y605640D01*
X598991Y605682D01*
X598804Y605640D01*
X598564Y605474D01*
X598644Y606557D01*
X599364D01*
G01X600711Y604349D02*
X600897Y604140D01*
X601111Y604057D01*
X601324Y604140D01*
X601511Y604390D01*
X601644Y604765D01*
X601697Y605140D01*
Y605599D01*
X601644Y605974D01*
X601511Y606307D01*
X601351Y606474D01*
X601164Y606557D01*
X600951Y606474D01*
X600791Y606307D01*
X600684Y606057D01*
X600631Y605724D01*
X600684Y605432D01*
X600817Y605140D01*
X600977Y604974D01*
X601164Y604932D01*
X601377Y605015D01*
X601537Y605224D01*
X601697Y605599D01*
G01X603311Y604057D02*
X603364Y604599D01*
X603444Y605057D01*
X603551Y605474D01*
X603684Y605932D01*
X603897Y606557D01*
X602831D01*
G01X600607Y621119D02*
X600377Y621274D01*
X600109Y621377D01*
X599802D01*
X599457Y621222D01*
X599189Y620964D01*
X598997Y620654D01*
X598844Y620137D01*
X598806Y619672D01*
X598882Y619207D01*
X598997Y618897D01*
X599227Y618587D01*
X599496Y618380D01*
X599764Y618277D01*
X600032D01*
X600301Y618380D01*
X600531Y618535D01*
X600722Y618742D01*
G01X603324Y618277D02*
Y621377D01*
X601906Y619155D01*
X603822D01*
G01X605121Y618897D02*
X605351Y618535D01*
X605657Y618329D01*
X606002Y618277D01*
X606309Y618329D01*
X606616Y618587D01*
X606807Y618897D01*
X606846Y619207D01*
X606769Y619569D01*
X606501Y619827D01*
X606232Y619930D01*
X605887D01*
G01X606232D02*
X606462Y620085D01*
X606654Y620344D01*
X606731Y620654D01*
X606654Y620964D01*
X606462Y621222D01*
X606117Y621377D01*
X605772Y621325D01*
X605427Y621119D01*
G01X608336Y619569D02*
X608604Y619930D01*
X608834Y620137D01*
X609141Y620240D01*
X609409Y620137D01*
X609601Y619930D01*
X609754Y619620D01*
X609792Y619259D01*
X609754Y618949D01*
X609601Y618639D01*
X609371Y618380D01*
X609102Y618277D01*
X608796Y618380D01*
X608527Y618690D01*
X608374Y619155D01*
X608336Y619672D01*
X608412Y620344D01*
X608527Y620705D01*
X608719Y621067D01*
X608987Y621325D01*
X609256Y621377D01*
X609524Y621274D01*
X609716Y621015D01*
G01X594937Y617045D02*
Y614045D01*
G01X598037Y613945D02*
X591837D01*
G01D02*
Y617145D01*
G01D02*
X598037D01*
G01D02*
Y613945D01*
G01X600548Y616948D02*
X600318Y617103D01*
X600050Y617206D01*
X599743D01*
X599398Y617051D01*
X599130Y616793D01*
X598938Y616483D01*
X598785Y615966D01*
X598747Y615501D01*
X598823Y615036D01*
X598938Y614726D01*
X599168Y614416D01*
X599437Y614209D01*
X599705Y614106D01*
X599973D01*
X600242Y614209D01*
X600472Y614364D01*
X600663Y614571D01*
G01X603265Y614106D02*
Y617206D01*
X601847Y614984D01*
X603763D01*
G01X605062Y614726D02*
X605292Y614364D01*
X605598Y614158D01*
X605943Y614106D01*
X606250Y614158D01*
X606557Y614416D01*
X606748Y614726D01*
X606787Y615036D01*
X606710Y615398D01*
X606442Y615656D01*
X606173Y615759D01*
X605828D01*
G01X606173D02*
X606403Y615914D01*
X606595Y616173D01*
X606672Y616483D01*
X606595Y616793D01*
X606403Y617051D01*
X606058Y617206D01*
X605713Y617154D01*
X605368Y616948D01*
G01X608162Y614571D02*
X608392Y614313D01*
X608660Y614158D01*
X609005Y614106D01*
X609350Y614209D01*
X609618Y614416D01*
X609810Y614778D01*
X609848Y615191D01*
X609772Y615604D01*
X609580Y615863D01*
X609312Y616069D01*
X609043Y616121D01*
X608775Y616069D01*
X608430Y615863D01*
X608545Y617206D01*
X609580D01*
G01X591837Y613145D02*
X598037D01*
G01X589649Y659949D02*
Y662449D01*
X590315D01*
X590529Y662324D01*
X590662Y662157D01*
X590715Y661824D01*
X590662Y661491D01*
X590502Y661282D01*
X590315Y661157D01*
X589649D01*
G01X590315D02*
X590715Y659949D01*
G01X592382D02*
Y662449D01*
X592062Y661949D01*
G01Y659949D02*
X592702D01*
G01X594582D02*
Y662449D01*
X594262Y661949D01*
G01Y659949D02*
X594902D01*
G01X596195Y660324D02*
X596355Y660116D01*
X596542Y659991D01*
X596782Y659949D01*
X597022Y660032D01*
X597209Y660199D01*
X597342Y660491D01*
X597369Y660824D01*
X597315Y661157D01*
X597182Y661366D01*
X596995Y661532D01*
X596809Y661574D01*
X596622Y661532D01*
X596382Y661366D01*
X596462Y662449D01*
X597182D01*
G01X598982Y659949D02*
X599169Y659991D01*
X599382Y660116D01*
X599515Y660324D01*
X599569Y660616D01*
X599515Y660907D01*
X599355Y661157D01*
X599115Y661282D01*
X598849D01*
X598689Y661366D01*
X598555Y661574D01*
X598502Y661866D01*
X598582Y662157D01*
X598769Y662366D01*
X598982Y662449D01*
X599195Y662366D01*
X599382Y662157D01*
X599462Y661866D01*
X599409Y661574D01*
X599275Y661366D01*
X599115Y661282D01*
X598849D01*
X598609Y661157D01*
X598449Y660907D01*
X598395Y660616D01*
X598449Y660324D01*
X598582Y660116D01*
X598795Y659991D01*
X598982Y659949D01*
G01X593443Y654985D02*
Y651785D01*
G01X594961Y688375D02*
X591861D01*
Y689334D01*
X592016Y689640D01*
X592223Y689832D01*
X592636Y689909D01*
X593049Y689832D01*
X593308Y689602D01*
X593463Y689334D01*
Y688375D01*
G01Y689334D02*
X594961Y689909D01*
G01Y692242D02*
X591861D01*
X592481Y691782D01*
G01X594961D02*
Y692702D01*
G01X592378Y694614D02*
X592068Y694844D01*
X591913Y695112D01*
X591861Y695419D01*
X591964Y695802D01*
X592223Y696070D01*
X592533Y696147D01*
X592843Y696109D01*
X593101Y695955D01*
X593618Y695189D01*
X593979Y694844D01*
X594496Y694614D01*
X594961Y694537D01*
Y696147D01*
G01X593669Y697714D02*
X593308Y697982D01*
X593101Y698212D01*
X592998Y698519D01*
X593101Y698787D01*
X593308Y698979D01*
X593618Y699132D01*
X593979Y699170D01*
X594289Y699132D01*
X594599Y698979D01*
X594858Y698749D01*
X594961Y698480D01*
X594858Y698174D01*
X594548Y697905D01*
X594083Y697752D01*
X593566Y697714D01*
X592894Y697790D01*
X592533Y697905D01*
X592171Y698097D01*
X591913Y698365D01*
X591861Y698634D01*
X591964Y698902D01*
X592223Y699094D01*
G01X594961Y701542D02*
X591861D01*
X592481Y701082D01*
G01X594961D02*
Y702002D01*
G01X591400Y688584D02*
Y682384D01*
G01X603405Y692924D02*
X600305D01*
Y693883D01*
X600460Y694189D01*
X600667Y694381D01*
X601080Y694458D01*
X601493Y694381D01*
X601752Y694151D01*
X601907Y693883D01*
Y692924D01*
G01Y693883D02*
X603405Y694458D01*
G01Y696791D02*
X600305D01*
X600925Y696331D01*
G01X603405D02*
Y697251D01*
G01X602785Y699048D02*
X603147Y699278D01*
X603353Y699584D01*
X603405Y699929D01*
X603353Y700236D01*
X603095Y700543D01*
X602785Y700734D01*
X602475Y700773D01*
X602113Y700696D01*
X601855Y700428D01*
X601752Y700159D01*
Y699814D01*
G01Y700159D02*
X601597Y700389D01*
X601338Y700581D01*
X601028Y700658D01*
X600718Y700581D01*
X600460Y700389D01*
X600305Y700044D01*
X600357Y699699D01*
X600563Y699354D01*
G01X600305Y702991D02*
X600408Y702684D01*
X600667Y702454D01*
X600977Y702301D01*
X601390Y702186D01*
X601855Y702148D01*
X602320Y702186D01*
X602733Y702301D01*
X603043Y702454D01*
X603302Y702684D01*
X603405Y702991D01*
X603302Y703298D01*
X603043Y703528D01*
X602733Y703681D01*
X602320Y703796D01*
X601855Y703834D01*
X601390Y703796D01*
X600977Y703681D01*
X600667Y703528D01*
X600408Y703298D01*
X600305Y702991D01*
G01X602940Y705248D02*
X603198Y705478D01*
X603353Y705746D01*
X603405Y706091D01*
X603302Y706436D01*
X603095Y706704D01*
X602733Y706896D01*
X602320Y706934D01*
X601907Y706858D01*
X601648Y706666D01*
X601442Y706398D01*
X601390Y706129D01*
X601442Y705861D01*
X601648Y705516D01*
X600305Y705631D01*
Y706666D01*
G01X607330Y708442D02*
X604230D01*
Y709401D01*
X604385Y709707D01*
X604592Y709899D01*
X605005Y709976D01*
X605418Y709899D01*
X605677Y709669D01*
X605832Y709401D01*
Y708442D01*
G01Y709401D02*
X607330Y709976D01*
G01Y712309D02*
X604230D01*
X604850Y711849D01*
G01X607330D02*
Y712769D01*
G01Y715409D02*
X604230D01*
X604850Y714949D01*
G01X607330D02*
Y715869D01*
G01X606038Y717781D02*
X605677Y718049D01*
X605470Y718279D01*
X605367Y718586D01*
X605470Y718854D01*
X605677Y719046D01*
X605987Y719199D01*
X606348Y719237D01*
X606658Y719199D01*
X606968Y719046D01*
X607227Y718816D01*
X607330Y718547D01*
X607227Y718241D01*
X606917Y717972D01*
X606452Y717819D01*
X605935Y717781D01*
X605263Y717857D01*
X604902Y717972D01*
X604540Y718164D01*
X604282Y718432D01*
X604230Y718701D01*
X604333Y718969D01*
X604592Y719161D01*
G01X607330Y721609D02*
X607278Y721877D01*
X607123Y722184D01*
X606865Y722376D01*
X606503Y722452D01*
X606142Y722376D01*
X605832Y722146D01*
X605677Y721801D01*
Y721417D01*
X605573Y721187D01*
X605315Y720996D01*
X604953Y720919D01*
X604592Y721034D01*
X604333Y721302D01*
X604230Y721609D01*
X604333Y721916D01*
X604592Y722184D01*
X604953Y722299D01*
X605315Y722222D01*
X605573Y722031D01*
X605677Y721801D01*
Y721417D01*
X605832Y721072D01*
X606142Y720842D01*
X606503Y720766D01*
X606865Y720842D01*
X607123Y721034D01*
X607278Y721341D01*
X607330Y721609D01*
G01X598540Y726056D02*
X595340D01*
G01X598540Y732256D02*
Y726056D01*
G01X595340Y732256D02*
X598540D01*
G01X595340Y726056D02*
Y732256D01*
G01X598440Y729156D02*
X595440D01*
G01X603040Y737556D02*
X599840D01*
G01X603040Y743756D02*
Y737556D01*
G01X599840D02*
Y743756D01*
G01X607540Y737556D02*
X604340D01*
G01D02*
Y743756D01*
G01X594040Y737556D02*
X590840D01*
G01D02*
Y743756D01*
G01X594040D02*
Y737556D01*
G01X589540Y732256D02*
Y726056D01*
G01Y743756D02*
Y737556D01*
G01X590840Y732256D02*
X594040D01*
G01X590840Y726056D02*
Y732256D01*
G01X594040Y726056D02*
X590840D01*
G01X594040Y732256D02*
Y726056D01*
G01X599840Y732256D02*
X603040D01*
G01X599840Y726056D02*
Y732256D01*
G01X603040Y726056D02*
X599840D01*
G01X603040Y732256D02*
Y726056D01*
G01X604340Y732256D02*
X607540D01*
G01X604340Y726056D02*
Y732256D01*
G01X607540Y726056D02*
X604340D01*
G01X595340Y737556D02*
Y743756D01*
G01X598540Y737556D02*
X595340D01*
G01X598540Y743756D02*
Y737556D01*
G01X596481Y749921D02*
X596326Y749691D01*
X596223Y749423D01*
Y749116D01*
X596378Y748771D01*
X596636Y748503D01*
X596946Y748311D01*
X597463Y748158D01*
X597928Y748120D01*
X598393Y748196D01*
X598703Y748311D01*
X599013Y748541D01*
X599220Y748810D01*
X599323Y749078D01*
Y749346D01*
X599220Y749615D01*
X599065Y749845D01*
X598858Y750036D01*
G01X599323Y752101D02*
X598651Y752178D01*
X598083Y752293D01*
X597566Y752446D01*
X596998Y752638D01*
X596223Y752945D01*
Y751411D01*
G01X599323Y755738D02*
X596223D01*
X598445Y754320D01*
Y756236D01*
G01X599323Y758838D02*
X596223D01*
X598445Y757420D01*
Y759336D01*
G01X599840Y743756D02*
X603040D01*
G01X602940Y740656D02*
X599940D01*
G01X604340Y743756D02*
X607540D01*
G01X607440Y740656D02*
X604440D01*
G01X590840Y743756D02*
X594040D01*
G01X593940Y740656D02*
X590940D01*
G01X594857Y748311D02*
X591757D01*
Y749270D01*
X591912Y749576D01*
X592119Y749768D01*
X592532Y749845D01*
X592945Y749768D01*
X593204Y749538D01*
X593359Y749270D01*
Y748311D01*
G01Y749270D02*
X594857Y749845D01*
G01X594495Y751526D02*
X594754Y751795D01*
X594857Y752101D01*
X594754Y752408D01*
X594444Y752676D01*
X593979Y752868D01*
X593514Y752945D01*
X592945D01*
X592480Y752868D01*
X592067Y752676D01*
X591860Y752446D01*
X591757Y752178D01*
X591860Y751871D01*
X592067Y751641D01*
X592377Y751488D01*
X592790Y751411D01*
X593152Y751488D01*
X593514Y751680D01*
X593720Y751910D01*
X593772Y752178D01*
X593669Y752485D01*
X593410Y752715D01*
X592945Y752945D01*
G01X594857Y755278D02*
X594805Y755546D01*
X594650Y755853D01*
X594392Y756045D01*
X594030Y756121D01*
X593669Y756045D01*
X593359Y755815D01*
X593204Y755470D01*
Y755086D01*
X593100Y754856D01*
X592842Y754665D01*
X592480Y754588D01*
X592119Y754703D01*
X591860Y754971D01*
X591757Y755278D01*
X591860Y755585D01*
X592119Y755853D01*
X592480Y755968D01*
X592842Y755891D01*
X593100Y755700D01*
X593204Y755470D01*
Y755086D01*
X593359Y754741D01*
X593669Y754511D01*
X594030Y754435D01*
X594392Y754511D01*
X594650Y754703D01*
X594805Y755010D01*
X594857Y755278D01*
G01Y758838D02*
X591757D01*
X593979Y757420D01*
Y759336D01*
G01X603857Y748311D02*
X600757D01*
Y749270D01*
X600912Y749576D01*
X601119Y749768D01*
X601532Y749845D01*
X601945Y749768D01*
X602204Y749538D01*
X602359Y749270D01*
Y748311D01*
G01Y749270D02*
X603857Y749845D01*
G01X603495Y751526D02*
X603754Y751795D01*
X603857Y752101D01*
X603754Y752408D01*
X603444Y752676D01*
X602979Y752868D01*
X602514Y752945D01*
X601945D01*
X601480Y752868D01*
X601067Y752676D01*
X600860Y752446D01*
X600757Y752178D01*
X600860Y751871D01*
X601067Y751641D01*
X601377Y751488D01*
X601790Y751411D01*
X602152Y751488D01*
X602514Y751680D01*
X602720Y751910D01*
X602772Y752178D01*
X602669Y752485D01*
X602410Y752715D01*
X601945Y752945D01*
G01X600757Y755278D02*
X600860Y754971D01*
X601119Y754741D01*
X601429Y754588D01*
X601842Y754473D01*
X602307Y754435D01*
X602772Y754473D01*
X603185Y754588D01*
X603495Y754741D01*
X603754Y754971D01*
X603857Y755278D01*
X603754Y755585D01*
X603495Y755815D01*
X603185Y755968D01*
X602772Y756083D01*
X602307Y756121D01*
X601842Y756083D01*
X601429Y755968D01*
X601119Y755815D01*
X600860Y755585D01*
X600757Y755278D01*
G01X603237Y757535D02*
X603599Y757765D01*
X603805Y758071D01*
X603857Y758416D01*
X603805Y758723D01*
X603547Y759030D01*
X603237Y759221D01*
X602927Y759260D01*
X602565Y759183D01*
X602307Y758915D01*
X602204Y758646D01*
Y758301D01*
G01Y758646D02*
X602049Y758876D01*
X601790Y759068D01*
X601480Y759145D01*
X601170Y759068D01*
X600912Y758876D01*
X600757Y758531D01*
X600809Y758186D01*
X601015Y757841D01*
G01X595340Y743756D02*
X598540D01*
G01X595891Y764380D02*
X595736Y764150D01*
X595633Y763882D01*
Y763575D01*
X595788Y763230D01*
X596046Y762962D01*
X596356Y762770D01*
X596873Y762617D01*
X597338Y762579D01*
X597803Y762655D01*
X598113Y762770D01*
X598423Y763000D01*
X598630Y763269D01*
X598733Y763537D01*
Y763805D01*
X598630Y764074D01*
X598475Y764304D01*
X598268Y764495D01*
G01X597441Y765909D02*
X597080Y766177D01*
X596873Y766407D01*
X596770Y766714D01*
X596873Y766982D01*
X597080Y767174D01*
X597390Y767327D01*
X597751Y767365D01*
X598061Y767327D01*
X598371Y767174D01*
X598630Y766944D01*
X598733Y766675D01*
X598630Y766369D01*
X598320Y766100D01*
X597855Y765947D01*
X597338Y765909D01*
X596666Y765985D01*
X596305Y766100D01*
X595943Y766292D01*
X595685Y766560D01*
X595633Y766829D01*
X595736Y767097D01*
X595995Y767289D01*
G01X597441Y769009D02*
X597080Y769277D01*
X596873Y769507D01*
X596770Y769814D01*
X596873Y770082D01*
X597080Y770274D01*
X597390Y770427D01*
X597751Y770465D01*
X598061Y770427D01*
X598371Y770274D01*
X598630Y770044D01*
X598733Y769775D01*
X598630Y769469D01*
X598320Y769200D01*
X597855Y769047D01*
X597338Y769009D01*
X596666Y769085D01*
X596305Y769200D01*
X595943Y769392D01*
X595685Y769660D01*
X595633Y769929D01*
X595736Y770197D01*
X595995Y770389D01*
G01X595633Y772837D02*
X595736Y772530D01*
X595995Y772300D01*
X596305Y772147D01*
X596718Y772032D01*
X597183Y771994D01*
X597648Y772032D01*
X598061Y772147D01*
X598371Y772300D01*
X598630Y772530D01*
X598733Y772837D01*
X598630Y773144D01*
X598371Y773374D01*
X598061Y773527D01*
X597648Y773642D01*
X597183Y773680D01*
X596718Y773642D01*
X596305Y773527D01*
X595995Y773374D01*
X595736Y773144D01*
X595633Y772837D01*
G01X591935Y764380D02*
X591780Y764150D01*
X591677Y763882D01*
Y763575D01*
X591832Y763230D01*
X592090Y762962D01*
X592400Y762770D01*
X592917Y762617D01*
X593382Y762579D01*
X593847Y762655D01*
X594157Y762770D01*
X594467Y763000D01*
X594674Y763269D01*
X594777Y763537D01*
Y763805D01*
X594674Y764074D01*
X594519Y764304D01*
X594312Y764495D01*
G01X593485Y765909D02*
X593124Y766177D01*
X592917Y766407D01*
X592814Y766714D01*
X592917Y766982D01*
X593124Y767174D01*
X593434Y767327D01*
X593795Y767365D01*
X594105Y767327D01*
X594415Y767174D01*
X594674Y766944D01*
X594777Y766675D01*
X594674Y766369D01*
X594364Y766100D01*
X593899Y765947D01*
X593382Y765909D01*
X592710Y765985D01*
X592349Y766100D01*
X591987Y766292D01*
X591729Y766560D01*
X591677Y766829D01*
X591780Y767097D01*
X592039Y767289D01*
G01X593485Y769009D02*
X593124Y769277D01*
X592917Y769507D01*
X592814Y769814D01*
X592917Y770082D01*
X593124Y770274D01*
X593434Y770427D01*
X593795Y770465D01*
X594105Y770427D01*
X594415Y770274D01*
X594674Y770044D01*
X594777Y769775D01*
X594674Y769469D01*
X594364Y769200D01*
X593899Y769047D01*
X593382Y769009D01*
X592710Y769085D01*
X592349Y769200D01*
X591987Y769392D01*
X591729Y769660D01*
X591677Y769929D01*
X591780Y770197D01*
X592039Y770389D01*
G01X594157Y771994D02*
X594519Y772224D01*
X594725Y772530D01*
X594777Y772875D01*
X594725Y773182D01*
X594467Y773489D01*
X594157Y773680D01*
X593847Y773719D01*
X593485Y773642D01*
X593227Y773374D01*
X593124Y773105D01*
Y772760D01*
G01Y773105D02*
X592969Y773335D01*
X592710Y773527D01*
X592400Y773604D01*
X592090Y773527D01*
X591832Y773335D01*
X591677Y772990D01*
X591729Y772645D01*
X591935Y772300D01*
G01X602816Y762770D02*
X599716D01*
Y763729D01*
X599871Y764035D01*
X600078Y764227D01*
X600491Y764304D01*
X600904Y764227D01*
X601163Y763997D01*
X601318Y763729D01*
Y762770D01*
G01Y763729D02*
X602816Y764304D01*
G01Y766637D02*
X599716D01*
X600336Y766177D01*
G01X602816D02*
Y767097D01*
G01X600233Y769009D02*
X599923Y769239D01*
X599768Y769507D01*
X599716Y769814D01*
X599819Y770197D01*
X600078Y770465D01*
X600388Y770542D01*
X600698Y770504D01*
X600956Y770350D01*
X601473Y769584D01*
X601834Y769239D01*
X602351Y769009D01*
X602816Y768932D01*
Y770542D01*
G01X600233Y772109D02*
X599923Y772339D01*
X599768Y772607D01*
X599716Y772914D01*
X599819Y773297D01*
X600078Y773565D01*
X600388Y773642D01*
X600698Y773604D01*
X600956Y773450D01*
X601473Y772684D01*
X601834Y772339D01*
X602351Y772109D01*
X602816Y772032D01*
Y773642D01*
G01Y775937D02*
X599716D01*
X600336Y775477D01*
G01X602816D02*
Y776397D01*
G01X606817Y762770D02*
X603717D01*
Y763729D01*
X603872Y764035D01*
X604079Y764227D01*
X604492Y764304D01*
X604905Y764227D01*
X605164Y763997D01*
X605319Y763729D01*
Y762770D01*
G01Y763729D02*
X606817Y764304D01*
G01Y766637D02*
X603717D01*
X604337Y766177D01*
G01X606817D02*
Y767097D01*
G01X604234Y769009D02*
X603924Y769239D01*
X603769Y769507D01*
X603717Y769814D01*
X603820Y770197D01*
X604079Y770465D01*
X604389Y770542D01*
X604699Y770504D01*
X604957Y770350D01*
X605474Y769584D01*
X605835Y769239D01*
X606352Y769009D01*
X606817Y768932D01*
Y770542D01*
G01X604234Y772109D02*
X603924Y772339D01*
X603769Y772607D01*
X603717Y772914D01*
X603820Y773297D01*
X604079Y773565D01*
X604389Y773642D01*
X604699Y773604D01*
X604957Y773450D01*
X605474Y772684D01*
X605835Y772339D01*
X606352Y772109D01*
X606817Y772032D01*
Y773642D01*
G01X603717Y775937D02*
X603820Y775630D01*
X604079Y775400D01*
X604389Y775247D01*
X604802Y775132D01*
X605267Y775094D01*
X605732Y775132D01*
X606145Y775247D01*
X606455Y775400D01*
X606714Y775630D01*
X606817Y775937D01*
X606714Y776244D01*
X606455Y776474D01*
X606145Y776627D01*
X605732Y776742D01*
X605267Y776780D01*
X604802Y776742D01*
X604389Y776627D01*
X604079Y776474D01*
X603820Y776244D01*
X603717Y775937D01*
G01X620597Y21417D02*
X620827Y21727D01*
X621095Y21882D01*
X621402Y21934D01*
X621785Y21831D01*
X622053Y21572D01*
X622130Y21262D01*
X622092Y20952D01*
X621938Y20694D01*
X621172Y20177D01*
X620827Y19816D01*
X620597Y19299D01*
X620520Y18834D01*
X622130D01*
G01X618394Y59777D02*
X615294D01*
X617516Y58359D01*
Y60275D01*
G01X612114Y61293D02*
X622350D01*
G01X605815Y63261D02*
Y66778D01*
G01X620382Y63261D02*
X605815D01*
G01Y71578D02*
Y98695D01*
G01X620382Y73104D02*
Y63261D01*
G01X622350Y73104D02*
X620382D01*
G01Y88852D02*
X622350D01*
G01X620382Y98695D02*
Y88852D01*
G01X609018Y106332D02*
X615218D01*
G01D02*
Y103132D01*
G01D02*
X609018D01*
G01D02*
Y106332D01*
G01X612118Y103232D02*
Y106232D01*
G01X623298Y103104D02*
X617098D01*
G01D02*
Y106304D01*
G01D02*
X623298D01*
G01X620198Y106204D02*
Y103204D01*
G01X607718Y106332D02*
Y103132D01*
G01X605815Y98695D02*
X620382D01*
G01X619518Y151032D02*
Y112432D01*
G01D02*
X613918D01*
G01D02*
X611618Y114732D01*
G01D02*
X609318Y112432D01*
G01X618618Y114732D02*
G02I-1000J0D01*
G01X615080Y154034D02*
Y156534D01*
X614760Y156034D01*
G01Y154034D02*
X615400D01*
G01X619576Y221065D02*
Y158073D01*
G01X622890Y185634D02*
X623200Y185826D01*
X623407Y186056D01*
X623510Y186324D01*
X623407Y186631D01*
X623200Y186861D01*
X622890Y187091D01*
X622477Y187168D01*
X620410D01*
G01X623510Y189424D02*
X622838Y189501D01*
X622270Y189616D01*
X621753Y189769D01*
X621185Y189961D01*
X620410Y190268D01*
Y188734D01*
G01X616022Y173669D02*
X617222D01*
G01X616022Y208169D02*
Y173669D01*
G01X617222D02*
Y209669D01*
G01X605222Y208169D02*
X616022D01*
G01X605222Y209669D02*
Y208169D01*
G01X617222Y209669D02*
X605222D01*
G01X611544Y250670D02*
X611314Y250825D01*
X611046Y250928D01*
X610739D01*
X610394Y250773D01*
X610126Y250515D01*
X609934Y250205D01*
X609781Y249688D01*
X609743Y249223D01*
X609819Y248758D01*
X609934Y248448D01*
X610164Y248138D01*
X610433Y247931D01*
X610701Y247828D01*
X610969D01*
X611238Y247931D01*
X611468Y248086D01*
X611659Y248293D01*
G01X614261Y247828D02*
Y250928D01*
X612843Y248706D01*
X614759D01*
G01X616249Y248190D02*
X616518Y247931D01*
X616824Y247828D01*
X617131Y247931D01*
X617399Y248241D01*
X617591Y248706D01*
X617668Y249171D01*
Y249740D01*
X617591Y250205D01*
X617399Y250618D01*
X617169Y250825D01*
X616901Y250928D01*
X616594Y250825D01*
X616364Y250618D01*
X616211Y250308D01*
X616134Y249895D01*
X616211Y249533D01*
X616403Y249171D01*
X616633Y248965D01*
X616901Y248913D01*
X617208Y249016D01*
X617438Y249275D01*
X617668Y249740D01*
G01X620001Y250928D02*
X619694Y250825D01*
X619464Y250566D01*
X619311Y250256D01*
X619196Y249843D01*
X619158Y249378D01*
X619196Y248913D01*
X619311Y248500D01*
X619464Y248190D01*
X619694Y247931D01*
X620001Y247828D01*
X620308Y247931D01*
X620538Y248190D01*
X620691Y248500D01*
X620806Y248913D01*
X620844Y249378D01*
X620806Y249843D01*
X620691Y250256D01*
X620538Y250566D01*
X620308Y250825D01*
X620001Y250928D01*
G01X615400Y265670D02*
Y283200D01*
G01X700690Y265670D02*
X615400D01*
G01X611544Y254670D02*
X611314Y254825D01*
X611046Y254928D01*
X610739D01*
X610394Y254773D01*
X610126Y254515D01*
X609934Y254205D01*
X609781Y253688D01*
X609743Y253223D01*
X609819Y252758D01*
X609934Y252448D01*
X610164Y252138D01*
X610433Y251931D01*
X610701Y251828D01*
X610969D01*
X611238Y251931D01*
X611468Y252086D01*
X611659Y252293D01*
G01X614261Y251828D02*
Y254928D01*
X612843Y252706D01*
X614759D01*
G01X616901Y251828D02*
X617169Y251880D01*
X617476Y252035D01*
X617668Y252293D01*
X617744Y252655D01*
X617668Y253016D01*
X617438Y253326D01*
X617093Y253481D01*
X616709D01*
X616479Y253585D01*
X616288Y253843D01*
X616211Y254205D01*
X616326Y254566D01*
X616594Y254825D01*
X616901Y254928D01*
X617208Y254825D01*
X617476Y254566D01*
X617591Y254205D01*
X617514Y253843D01*
X617323Y253585D01*
X617093Y253481D01*
X616709D01*
X616364Y253326D01*
X616134Y253016D01*
X616058Y252655D01*
X616134Y252293D01*
X616326Y252035D01*
X616633Y251880D01*
X616901Y251828D01*
G01X619349Y252190D02*
X619618Y251931D01*
X619924Y251828D01*
X620231Y251931D01*
X620499Y252241D01*
X620691Y252706D01*
X620768Y253171D01*
Y253740D01*
X620691Y254205D01*
X620499Y254618D01*
X620269Y254825D01*
X620001Y254928D01*
X619694Y254825D01*
X619464Y254618D01*
X619311Y254308D01*
X619234Y253895D01*
X619311Y253533D01*
X619503Y253171D01*
X619733Y252965D01*
X620001Y252913D01*
X620308Y253016D01*
X620538Y253275D01*
X620768Y253740D01*
G01X608541Y263404D02*
X614741D01*
G01D02*
Y260204D01*
G01D02*
X608541D01*
G01D02*
Y263404D01*
G01X611641Y260304D02*
Y263304D01*
G01X608541Y259404D02*
X614741D01*
G01D02*
Y256204D01*
G01D02*
X608541D01*
G01D02*
Y259404D01*
G01X611641Y256304D02*
Y259304D01*
G01X620550Y268514D02*
X620395Y268284D01*
X620292Y268016D01*
Y267709D01*
X620447Y267364D01*
X620705Y267096D01*
X621015Y266904D01*
X621532Y266751D01*
X621997Y266713D01*
X622462Y266789D01*
X622772Y266904D01*
X623082Y267134D01*
X623289Y267403D01*
X623392Y267671D01*
Y267939D01*
X623289Y268208D01*
X623134Y268438D01*
X622927Y268629D01*
G01Y269928D02*
X623185Y270158D01*
X623340Y270426D01*
X623392Y270771D01*
X623289Y271116D01*
X623082Y271384D01*
X622720Y271576D01*
X622307Y271614D01*
X621894Y271538D01*
X621635Y271346D01*
X621429Y271078D01*
X621377Y270809D01*
X621429Y270541D01*
X621635Y270196D01*
X620292Y270311D01*
Y271346D01*
G01X622772Y273028D02*
X623134Y273258D01*
X623340Y273564D01*
X623392Y273909D01*
X623340Y274216D01*
X623082Y274523D01*
X622772Y274714D01*
X622462Y274753D01*
X622100Y274676D01*
X621842Y274408D01*
X621739Y274139D01*
Y273794D01*
G01Y274139D02*
X621584Y274369D01*
X621325Y274561D01*
X621015Y274638D01*
X620705Y274561D01*
X620447Y274369D01*
X620292Y274024D01*
X620344Y273679D01*
X620550Y273334D01*
G01X622100Y276243D02*
X621739Y276511D01*
X621532Y276741D01*
X621429Y277048D01*
X621532Y277316D01*
X621739Y277508D01*
X622049Y277661D01*
X622410Y277699D01*
X622720Y277661D01*
X623030Y277508D01*
X623289Y277278D01*
X623392Y277009D01*
X623289Y276703D01*
X622979Y276434D01*
X622514Y276281D01*
X621997Y276243D01*
X621325Y276319D01*
X620964Y276434D01*
X620602Y276626D01*
X620344Y276894D01*
X620292Y277163D01*
X620395Y277431D01*
X620654Y277623D01*
G01X619392Y267071D02*
X616292D01*
Y268030D01*
X616447Y268336D01*
X616654Y268528D01*
X617067Y268605D01*
X617480Y268528D01*
X617739Y268298D01*
X617894Y268030D01*
Y267071D01*
G01Y268030D02*
X619392Y268605D01*
G01X618100Y270210D02*
X617739Y270478D01*
X617532Y270708D01*
X617429Y271015D01*
X617532Y271283D01*
X617739Y271475D01*
X618049Y271628D01*
X618410Y271666D01*
X618720Y271628D01*
X619030Y271475D01*
X619289Y271245D01*
X619392Y270976D01*
X619289Y270670D01*
X618979Y270401D01*
X618514Y270248D01*
X617997Y270210D01*
X617325Y270286D01*
X616964Y270401D01*
X616602Y270593D01*
X616344Y270861D01*
X616292Y271130D01*
X616395Y271398D01*
X616654Y271590D01*
G01X616809Y273310D02*
X616499Y273540D01*
X616344Y273808D01*
X616292Y274115D01*
X616395Y274498D01*
X616654Y274766D01*
X616964Y274843D01*
X617274Y274805D01*
X617532Y274651D01*
X618049Y273885D01*
X618410Y273540D01*
X618927Y273310D01*
X619392Y273233D01*
Y274843D01*
G01Y277138D02*
X616292D01*
X616912Y276678D01*
G01X619392D02*
Y277598D01*
G01X615400Y283200D02*
X679140D01*
G01X611254Y286872D02*
X611024Y287027D01*
X610756Y287130D01*
X610449D01*
X610104Y286975D01*
X609836Y286717D01*
X609644Y286407D01*
X609491Y285890D01*
X609453Y285425D01*
X609529Y284960D01*
X609644Y284650D01*
X609874Y284340D01*
X610143Y284133D01*
X610411Y284030D01*
X610679D01*
X610948Y284133D01*
X611178Y284288D01*
X611369Y284495D01*
G01X613511Y284030D02*
X613779Y284082D01*
X614086Y284237D01*
X614278Y284495D01*
X614354Y284857D01*
X614278Y285218D01*
X614048Y285528D01*
X613703Y285683D01*
X613319D01*
X613089Y285787D01*
X612898Y286045D01*
X612821Y286407D01*
X612936Y286768D01*
X613204Y287027D01*
X613511Y287130D01*
X613818Y287027D01*
X614086Y286768D01*
X614201Y286407D01*
X614124Y286045D01*
X613933Y285787D01*
X613703Y285683D01*
X613319D01*
X612974Y285528D01*
X612744Y285218D01*
X612668Y284857D01*
X612744Y284495D01*
X612936Y284237D01*
X613243Y284082D01*
X613511Y284030D01*
G01X616611D02*
X616879Y284082D01*
X617186Y284237D01*
X617378Y284495D01*
X617454Y284857D01*
X617378Y285218D01*
X617148Y285528D01*
X616803Y285683D01*
X616419D01*
X616189Y285787D01*
X615998Y286045D01*
X615921Y286407D01*
X616036Y286768D01*
X616304Y287027D01*
X616611Y287130D01*
X616918Y287027D01*
X617186Y286768D01*
X617301Y286407D01*
X617224Y286045D01*
X617033Y285787D01*
X616803Y285683D01*
X616419D01*
X616074Y285528D01*
X615844Y285218D01*
X615768Y284857D01*
X615844Y284495D01*
X616036Y284237D01*
X616343Y284082D01*
X616611Y284030D01*
G01X620171D02*
Y287130D01*
X618753Y284908D01*
X620669D01*
G01X609726Y287858D02*
Y290958D01*
X610685D01*
X610991Y290803D01*
X611183Y290596D01*
X611260Y290183D01*
X611183Y289770D01*
X610953Y289511D01*
X610685Y289356D01*
X609726D01*
G01X610685D02*
X611260Y287858D01*
G01X613593D02*
Y290958D01*
X613133Y290338D01*
G01Y287858D02*
X614053D01*
G01X615965Y290441D02*
X616195Y290751D01*
X616463Y290906D01*
X616770Y290958D01*
X617153Y290855D01*
X617421Y290596D01*
X617498Y290286D01*
X617460Y289976D01*
X617306Y289718D01*
X616540Y289201D01*
X616195Y288840D01*
X615965Y288323D01*
X615888Y287858D01*
X617498D01*
G01X619793D02*
Y290958D01*
X619333Y290338D01*
G01Y287858D02*
X620253D01*
G01X622893D02*
X623161Y287910D01*
X623468Y288065D01*
X623660Y288323D01*
X623736Y288685D01*
X623660Y289046D01*
X623430Y289356D01*
X623085Y289511D01*
X622701D01*
X622471Y289615D01*
X622280Y289873D01*
X622203Y290235D01*
X622318Y290596D01*
X622586Y290855D01*
X622893Y290958D01*
X623200Y290855D01*
X623468Y290596D01*
X623583Y290235D01*
X623506Y289873D01*
X623315Y289615D01*
X623085Y289511D01*
X622701D01*
X622356Y289356D01*
X622126Y289046D01*
X622050Y288685D01*
X622126Y288323D01*
X622318Y288065D01*
X622625Y287910D01*
X622893Y287858D01*
G01X613571Y298231D02*
Y301331D01*
X614491D01*
X614798Y301176D01*
X615028Y300814D01*
X615105Y300401D01*
X615028Y299988D01*
X614836Y299678D01*
X614491Y299523D01*
X613571D01*
G01X616671Y298231D02*
Y301331D01*
X617630D01*
X617936Y301176D01*
X618128Y300969D01*
X618205Y300556D01*
X618128Y300143D01*
X617898Y299884D01*
X617630Y299729D01*
X616671D01*
G01X617630D02*
X618205Y298231D01*
G01X619886Y298593D02*
X620155Y298334D01*
X620461Y298231D01*
X620768Y298334D01*
X621036Y298644D01*
X621228Y299109D01*
X621305Y299574D01*
Y300143D01*
X621228Y300608D01*
X621036Y301021D01*
X620806Y301228D01*
X620538Y301331D01*
X620231Y301228D01*
X620001Y301021D01*
X619848Y300711D01*
X619771Y300298D01*
X619848Y299936D01*
X620040Y299574D01*
X620270Y299368D01*
X620538Y299316D01*
X620845Y299419D01*
X621075Y299678D01*
X621305Y300143D01*
G01X609002Y293160D02*
X609194Y292850D01*
X609424Y292643D01*
X609692Y292540D01*
X609999Y292643D01*
X610229Y292850D01*
X610459Y293160D01*
X610536Y293573D01*
Y295640D01*
G01X612141Y295123D02*
X612371Y295433D01*
X612639Y295588D01*
X612946Y295640D01*
X613329Y295537D01*
X613597Y295278D01*
X613674Y294968D01*
X613636Y294658D01*
X613482Y294400D01*
X612716Y293883D01*
X612371Y293522D01*
X612141Y293005D01*
X612064Y292540D01*
X613674D01*
G01X615969D02*
X616237Y292592D01*
X616544Y292747D01*
X616736Y293005D01*
X616812Y293367D01*
X616736Y293728D01*
X616506Y294038D01*
X616161Y294193D01*
X615777D01*
X615547Y294297D01*
X615356Y294555D01*
X615279Y294917D01*
X615394Y295278D01*
X615662Y295537D01*
X615969Y295640D01*
X616276Y295537D01*
X616544Y295278D01*
X616659Y294917D01*
X616582Y294555D01*
X616391Y294297D01*
X616161Y294193D01*
X615777D01*
X615432Y294038D01*
X615202Y293728D01*
X615126Y293367D01*
X615202Y293005D01*
X615394Y292747D01*
X615701Y292592D01*
X615969Y292540D01*
G01X615181Y305073D02*
X614951Y305228D01*
X614683Y305331D01*
X614376D01*
X614031Y305176D01*
X613763Y304918D01*
X613571Y304608D01*
X613418Y304091D01*
X613380Y303626D01*
X613456Y303161D01*
X613571Y302851D01*
X613801Y302541D01*
X614070Y302334D01*
X614338Y302231D01*
X614606D01*
X614875Y302334D01*
X615105Y302489D01*
X615296Y302696D01*
G01X617438Y302231D02*
X617706Y302283D01*
X618013Y302438D01*
X618205Y302696D01*
X618281Y303058D01*
X618205Y303419D01*
X617975Y303729D01*
X617630Y303884D01*
X617246D01*
X617016Y303988D01*
X616825Y304246D01*
X616748Y304608D01*
X616863Y304969D01*
X617131Y305228D01*
X617438Y305331D01*
X617745Y305228D01*
X618013Y304969D01*
X618128Y304608D01*
X618051Y304246D01*
X617860Y303988D01*
X617630Y303884D01*
X617246D01*
X616901Y303729D01*
X616671Y303419D01*
X616595Y303058D01*
X616671Y302696D01*
X616863Y302438D01*
X617170Y302283D01*
X617438Y302231D01*
G01X619695Y302696D02*
X619925Y302438D01*
X620193Y302283D01*
X620538Y302231D01*
X620883Y302334D01*
X621151Y302541D01*
X621343Y302903D01*
X621381Y303316D01*
X621305Y303729D01*
X621113Y303988D01*
X620845Y304194D01*
X620576Y304246D01*
X620308Y304194D01*
X619963Y303988D01*
X620078Y305331D01*
X621113D01*
G01X623638Y302231D02*
Y305331D01*
X623178Y304711D01*
G01Y302231D02*
X624098D01*
G01X613571Y310805D02*
Y313905D01*
X614491D01*
X614798Y313750D01*
X615028Y313388D01*
X615105Y312975D01*
X615028Y312562D01*
X614836Y312252D01*
X614491Y312097D01*
X613571D01*
G01X618281Y313647D02*
X618051Y313802D01*
X617783Y313905D01*
X617476D01*
X617131Y313750D01*
X616863Y313492D01*
X616671Y313182D01*
X616518Y312665D01*
X616480Y312200D01*
X616556Y311735D01*
X616671Y311425D01*
X616901Y311115D01*
X617170Y310908D01*
X617438Y310805D01*
X617706D01*
X617975Y310908D01*
X618205Y311063D01*
X618396Y311270D01*
G01X619810Y313388D02*
X620040Y313698D01*
X620308Y313853D01*
X620615Y313905D01*
X620998Y313802D01*
X621266Y313543D01*
X621343Y313233D01*
X621305Y312923D01*
X621151Y312665D01*
X620385Y312148D01*
X620040Y311787D01*
X619810Y311270D01*
X619733Y310805D01*
X621343D01*
G01X622986Y311167D02*
X623255Y310908D01*
X623561Y310805D01*
X623868Y310908D01*
X624136Y311218D01*
X624328Y311683D01*
X624405Y312148D01*
Y312717D01*
X624328Y313182D01*
X624136Y313595D01*
X623906Y313802D01*
X623638Y313905D01*
X623331Y313802D01*
X623101Y313595D01*
X622948Y313285D01*
X622871Y312872D01*
X622948Y312510D01*
X623140Y312148D01*
X623370Y311942D01*
X623638Y311890D01*
X623945Y311993D01*
X624175Y312252D01*
X624405Y312717D01*
G01X613571Y306654D02*
Y309754D01*
X614491D01*
X614798Y309599D01*
X615028Y309237D01*
X615105Y308824D01*
X615028Y308411D01*
X614836Y308101D01*
X614491Y307946D01*
X613571D01*
G01X616671Y306654D02*
Y309754D01*
X617630D01*
X617936Y309599D01*
X618128Y309392D01*
X618205Y308979D01*
X618128Y308566D01*
X617898Y308307D01*
X617630Y308152D01*
X616671D01*
G01X617630D02*
X618205Y306654D01*
G01X620538D02*
Y309754D01*
X620078Y309134D01*
G01Y306654D02*
X620998D01*
G01X623638Y309754D02*
X623331Y309651D01*
X623101Y309392D01*
X622948Y309082D01*
X622833Y308669D01*
X622795Y308204D01*
X622833Y307739D01*
X622948Y307326D01*
X623101Y307016D01*
X623331Y306757D01*
X623638Y306654D01*
X623945Y306757D01*
X624175Y307016D01*
X624328Y307326D01*
X624443Y307739D01*
X624481Y308204D01*
X624443Y308669D01*
X624328Y309082D01*
X624175Y309392D01*
X623945Y309651D01*
X623638Y309754D01*
G01X618440Y337418D02*
Y357218D01*
G01X629640Y337418D02*
X618440D01*
G01X605938Y346285D02*
Y340085D01*
G01X621540Y354818D02*
G02I-1000J0D01*
G01X618440Y357218D02*
X622240D01*
G01X605691Y354279D02*
Y348079D01*
G01X606093Y362665D02*
Y356465D01*
G01X616413Y395327D02*
X616183Y395482D01*
X615915Y395585D01*
X615608D01*
X615263Y395430D01*
X614995Y395172D01*
X614803Y394862D01*
X614650Y394345D01*
X614612Y393880D01*
X614688Y393415D01*
X614803Y393105D01*
X615033Y392795D01*
X615302Y392588D01*
X615570Y392485D01*
X615838D01*
X616107Y392588D01*
X616337Y392743D01*
X616528Y392950D01*
G01X617827Y393105D02*
X618057Y392743D01*
X618363Y392537D01*
X618708Y392485D01*
X619015Y392537D01*
X619322Y392795D01*
X619513Y393105D01*
X619552Y393415D01*
X619475Y393777D01*
X619207Y394035D01*
X618938Y394138D01*
X618593D01*
G01X618938D02*
X619168Y394293D01*
X619360Y394552D01*
X619437Y394862D01*
X619360Y395172D01*
X619168Y395430D01*
X618823Y395585D01*
X618478Y395533D01*
X618133Y395327D01*
G01X621042Y393777D02*
X621310Y394138D01*
X621540Y394345D01*
X621847Y394448D01*
X622115Y394345D01*
X622307Y394138D01*
X622460Y393828D01*
X622498Y393467D01*
X622460Y393157D01*
X622307Y392847D01*
X622077Y392588D01*
X621808Y392485D01*
X621502Y392588D01*
X621233Y392898D01*
X621080Y393363D01*
X621042Y393880D01*
X621118Y394552D01*
X621233Y394913D01*
X621425Y395275D01*
X621693Y395533D01*
X621962Y395585D01*
X622230Y395482D01*
X622422Y395223D01*
G01X624027Y393105D02*
X624257Y392743D01*
X624563Y392537D01*
X624908Y392485D01*
X625215Y392537D01*
X625522Y392795D01*
X625713Y393105D01*
X625752Y393415D01*
X625675Y393777D01*
X625407Y394035D01*
X625138Y394138D01*
X624793D01*
G01X625138D02*
X625368Y394293D01*
X625560Y394552D01*
X625637Y394862D01*
X625560Y395172D01*
X625368Y395430D01*
X625023Y395585D01*
X624678Y395533D01*
X624333Y395327D01*
G01X616413Y391327D02*
X616183Y391482D01*
X615915Y391585D01*
X615608D01*
X615263Y391430D01*
X614995Y391172D01*
X614803Y390862D01*
X614650Y390345D01*
X614612Y389880D01*
X614688Y389415D01*
X614803Y389105D01*
X615033Y388795D01*
X615302Y388588D01*
X615570Y388485D01*
X615838D01*
X616107Y388588D01*
X616337Y388743D01*
X616528Y388950D01*
G01X617827Y389105D02*
X618057Y388743D01*
X618363Y388537D01*
X618708Y388485D01*
X619015Y388537D01*
X619322Y388795D01*
X619513Y389105D01*
X619552Y389415D01*
X619475Y389777D01*
X619207Y390035D01*
X618938Y390138D01*
X618593D01*
G01X618938D02*
X619168Y390293D01*
X619360Y390552D01*
X619437Y390862D01*
X619360Y391172D01*
X619168Y391430D01*
X618823Y391585D01*
X618478Y391533D01*
X618133Y391327D01*
G01X621042Y389777D02*
X621310Y390138D01*
X621540Y390345D01*
X621847Y390448D01*
X622115Y390345D01*
X622307Y390138D01*
X622460Y389828D01*
X622498Y389467D01*
X622460Y389157D01*
X622307Y388847D01*
X622077Y388588D01*
X621808Y388485D01*
X621502Y388588D01*
X621233Y388898D01*
X621080Y389363D01*
X621042Y389880D01*
X621118Y390552D01*
X621233Y390913D01*
X621425Y391275D01*
X621693Y391533D01*
X621962Y391585D01*
X622230Y391482D01*
X622422Y391223D01*
G01X625330Y388485D02*
Y391585D01*
X623912Y389363D01*
X625828D01*
G01X614760Y383541D02*
Y386641D01*
X615719D01*
X616025Y386486D01*
X616217Y386279D01*
X616294Y385866D01*
X616217Y385453D01*
X615987Y385194D01*
X615719Y385039D01*
X614760D01*
G01X615719D02*
X616294Y383541D01*
G01X617784Y384006D02*
X618014Y383748D01*
X618282Y383593D01*
X618627Y383541D01*
X618972Y383644D01*
X619240Y383851D01*
X619432Y384213D01*
X619470Y384626D01*
X619394Y385039D01*
X619202Y385298D01*
X618934Y385504D01*
X618665Y385556D01*
X618397Y385504D01*
X618052Y385298D01*
X618167Y386641D01*
X619202D01*
G01X620884Y384161D02*
X621114Y383799D01*
X621420Y383593D01*
X621765Y383541D01*
X622072Y383593D01*
X622379Y383851D01*
X622570Y384161D01*
X622609Y384471D01*
X622532Y384833D01*
X622264Y385091D01*
X621995Y385194D01*
X621650D01*
G01X621995D02*
X622225Y385349D01*
X622417Y385608D01*
X622494Y385918D01*
X622417Y386228D01*
X622225Y386486D01*
X621880Y386641D01*
X621535Y386589D01*
X621190Y386383D01*
G01X623984Y384161D02*
X624214Y383799D01*
X624520Y383593D01*
X624865Y383541D01*
X625172Y383593D01*
X625479Y383851D01*
X625670Y384161D01*
X625709Y384471D01*
X625632Y384833D01*
X625364Y385091D01*
X625095Y385194D01*
X624750D01*
G01X625095D02*
X625325Y385349D01*
X625517Y385608D01*
X625594Y385918D01*
X625517Y386228D01*
X625325Y386486D01*
X624980Y386641D01*
X624635Y386589D01*
X624290Y386383D01*
G01X614760Y379284D02*
Y382384D01*
X615719D01*
X616025Y382229D01*
X616217Y382022D01*
X616294Y381609D01*
X616217Y381196D01*
X615987Y380937D01*
X615719Y380782D01*
X614760D01*
G01X615719D02*
X616294Y379284D01*
G01X617784Y379749D02*
X618014Y379491D01*
X618282Y379336D01*
X618627Y379284D01*
X618972Y379387D01*
X619240Y379594D01*
X619432Y379956D01*
X619470Y380369D01*
X619394Y380782D01*
X619202Y381041D01*
X618934Y381247D01*
X618665Y381299D01*
X618397Y381247D01*
X618052Y381041D01*
X618167Y382384D01*
X619202D01*
G01X620999Y381867D02*
X621229Y382177D01*
X621497Y382332D01*
X621804Y382384D01*
X622187Y382281D01*
X622455Y382022D01*
X622532Y381712D01*
X622494Y381402D01*
X622340Y381144D01*
X621574Y380627D01*
X621229Y380266D01*
X620999Y379749D01*
X620922Y379284D01*
X622532D01*
G01X624750D02*
X624827Y379956D01*
X624942Y380524D01*
X625095Y381041D01*
X625287Y381609D01*
X625594Y382384D01*
X624060D01*
G01X617320Y403652D02*
X623520D01*
G01X617320Y400452D02*
Y403652D01*
G01X623520Y400452D02*
X617320D01*
G01X620420Y403552D02*
Y400552D01*
G01X617320Y399652D02*
X623520D01*
G01X617320Y396452D02*
Y399652D01*
G01X623520Y396452D02*
X617320D01*
G01X620420Y399552D02*
Y396552D01*
G01X610388Y406325D02*
Y412525D01*
G01X613588Y406325D02*
X610388D01*
G01X613588Y412525D02*
Y406325D01*
G01X609288Y406651D02*
X606188D01*
Y407610D01*
X606343Y407916D01*
X606550Y408108D01*
X606963Y408185D01*
X607376Y408108D01*
X607635Y407878D01*
X607790Y407610D01*
Y406651D01*
G01Y407610D02*
X609288Y408185D01*
G01X608823Y409675D02*
X609081Y409905D01*
X609236Y410173D01*
X609288Y410518D01*
X609185Y410863D01*
X608978Y411131D01*
X608616Y411323D01*
X608203Y411361D01*
X607790Y411285D01*
X607531Y411093D01*
X607325Y410825D01*
X607273Y410556D01*
X607325Y410288D01*
X607531Y409943D01*
X606188Y410058D01*
Y411093D01*
G01X608668Y412775D02*
X609030Y413005D01*
X609236Y413311D01*
X609288Y413656D01*
X609236Y413963D01*
X608978Y414270D01*
X608668Y414461D01*
X608358Y414500D01*
X607996Y414423D01*
X607738Y414155D01*
X607635Y413886D01*
Y413541D01*
G01Y413886D02*
X607480Y414116D01*
X607221Y414308D01*
X606911Y414385D01*
X606601Y414308D01*
X606343Y414116D01*
X606188Y413771D01*
X606240Y413426D01*
X606446Y413081D01*
G01X609288Y417178D02*
X606188D01*
X608410Y415760D01*
Y417676D01*
G01X614328Y406325D02*
Y412525D01*
G01X617528Y406325D02*
X614328D01*
G01X617528Y412525D02*
Y406325D01*
G01X610388Y412525D02*
X613588D01*
G01X614328D02*
X617528D01*
G01X615778Y423891D02*
X612678D01*
Y424850D01*
X612833Y425156D01*
X613040Y425348D01*
X613453Y425425D01*
X613866Y425348D01*
X614125Y425118D01*
X614280Y424850D01*
Y423891D01*
G01Y424850D02*
X615778Y425425D01*
G01X613195Y427030D02*
X612885Y427260D01*
X612730Y427528D01*
X612678Y427835D01*
X612781Y428218D01*
X613040Y428486D01*
X613350Y428563D01*
X613660Y428525D01*
X613918Y428371D01*
X614435Y427605D01*
X614796Y427260D01*
X615313Y427030D01*
X615778Y426953D01*
Y428563D01*
G01Y430781D02*
X615106Y430858D01*
X614538Y430973D01*
X614021Y431126D01*
X613453Y431318D01*
X612678Y431625D01*
Y430091D01*
G01X615158Y433115D02*
X615520Y433345D01*
X615726Y433651D01*
X615778Y433996D01*
X615726Y434303D01*
X615468Y434610D01*
X615158Y434801D01*
X614848Y434840D01*
X614486Y434763D01*
X614228Y434495D01*
X614125Y434226D01*
Y433881D01*
G01Y434226D02*
X613970Y434456D01*
X613711Y434648D01*
X613401Y434725D01*
X613091Y434648D01*
X612833Y434456D01*
X612678Y434111D01*
X612730Y433766D01*
X612936Y433421D01*
G01X612738Y420345D02*
X615938D01*
G01X612738Y414145D02*
Y420345D01*
G01X615938Y414145D02*
X612738D01*
G01X615938Y420345D02*
Y414145D01*
G01X619778Y423891D02*
X616678D01*
Y424850D01*
X616833Y425156D01*
X617040Y425348D01*
X617453Y425425D01*
X617866Y425348D01*
X618125Y425118D01*
X618280Y424850D01*
Y423891D01*
G01Y424850D02*
X619778Y425425D01*
G01X617195Y427030D02*
X616885Y427260D01*
X616730Y427528D01*
X616678Y427835D01*
X616781Y428218D01*
X617040Y428486D01*
X617350Y428563D01*
X617660Y428525D01*
X617918Y428371D01*
X618435Y427605D01*
X618796Y427260D01*
X619313Y427030D01*
X619778Y426953D01*
Y428563D01*
G01Y430781D02*
X619106Y430858D01*
X618538Y430973D01*
X618021Y431126D01*
X617453Y431318D01*
X616678Y431625D01*
Y430091D01*
G01X619778Y434418D02*
X616678D01*
X618900Y433000D01*
Y434916D01*
G01X616768Y420355D02*
X619968D01*
G01X616768Y414155D02*
Y420355D01*
G01X619968Y414155D02*
X616768D01*
G01X619968Y420355D02*
Y414155D01*
G01X620520Y493820D02*
Y443160D01*
G01X607853Y448847D02*
Y451947D01*
X608812D01*
X609118Y451792D01*
X609310Y451585D01*
X609387Y451172D01*
X609310Y450759D01*
X609080Y450500D01*
X608812Y450345D01*
X607853D01*
G01X608812D02*
X609387Y448847D01*
G01X610992Y450139D02*
X611260Y450500D01*
X611490Y450707D01*
X611797Y450810D01*
X612065Y450707D01*
X612257Y450500D01*
X612410Y450190D01*
X612448Y449829D01*
X612410Y449519D01*
X612257Y449209D01*
X612027Y448950D01*
X611758Y448847D01*
X611452Y448950D01*
X611183Y449260D01*
X611030Y449725D01*
X610992Y450242D01*
X611068Y450914D01*
X611183Y451275D01*
X611375Y451637D01*
X611643Y451895D01*
X611912Y451947D01*
X612180Y451844D01*
X612372Y451585D01*
G01X614092Y450139D02*
X614360Y450500D01*
X614590Y450707D01*
X614897Y450810D01*
X615165Y450707D01*
X615357Y450500D01*
X615510Y450190D01*
X615548Y449829D01*
X615510Y449519D01*
X615357Y449209D01*
X615127Y448950D01*
X614858Y448847D01*
X614552Y448950D01*
X614283Y449260D01*
X614130Y449725D01*
X614092Y450242D01*
X614168Y450914D01*
X614283Y451275D01*
X614475Y451637D01*
X614743Y451895D01*
X615012Y451947D01*
X615280Y451844D01*
X615472Y451585D01*
G01X617077Y449312D02*
X617307Y449054D01*
X617575Y448899D01*
X617920Y448847D01*
X618265Y448950D01*
X618533Y449157D01*
X618725Y449519D01*
X618763Y449932D01*
X618687Y450345D01*
X618495Y450604D01*
X618227Y450810D01*
X617958Y450862D01*
X617690Y450810D01*
X617345Y450604D01*
X617460Y451947D01*
X618495D01*
G01X605830Y468424D02*
Y471524D01*
X606789D01*
X607095Y471369D01*
X607287Y471162D01*
X607364Y470749D01*
X607287Y470336D01*
X607057Y470077D01*
X606789Y469922D01*
X605830D01*
G01X606789D02*
X607364Y468424D01*
G01X609620D02*
X609697Y469096D01*
X609812Y469664D01*
X609965Y470181D01*
X610157Y470749D01*
X610464Y471524D01*
X608930D01*
G01X612145Y468786D02*
X612414Y468527D01*
X612720Y468424D01*
X613027Y468527D01*
X613295Y468837D01*
X613487Y469302D01*
X613564Y469767D01*
Y470336D01*
X613487Y470801D01*
X613295Y471214D01*
X613065Y471421D01*
X612797Y471524D01*
X612490Y471421D01*
X612260Y471214D01*
X612107Y470904D01*
X612030Y470491D01*
X612107Y470129D01*
X612299Y469767D01*
X612529Y469561D01*
X612797Y469509D01*
X613104Y469612D01*
X613334Y469871D01*
X613564Y470336D01*
G01X615169Y471007D02*
X615399Y471317D01*
X615667Y471472D01*
X615974Y471524D01*
X616357Y471421D01*
X616625Y471162D01*
X616702Y470852D01*
X616664Y470542D01*
X616510Y470284D01*
X615744Y469767D01*
X615399Y469406D01*
X615169Y468889D01*
X615092Y468424D01*
X616702D01*
G01X605899Y464399D02*
Y467499D01*
X606858D01*
X607164Y467344D01*
X607356Y467137D01*
X607433Y466724D01*
X607356Y466311D01*
X607126Y466052D01*
X606858Y465897D01*
X605899D01*
G01X606858D02*
X607433Y464399D01*
G01X609038Y465691D02*
X609306Y466052D01*
X609536Y466259D01*
X609843Y466362D01*
X610111Y466259D01*
X610303Y466052D01*
X610456Y465742D01*
X610494Y465381D01*
X610456Y465071D01*
X610303Y464761D01*
X610073Y464502D01*
X609804Y464399D01*
X609498Y464502D01*
X609229Y464812D01*
X609076Y465277D01*
X609038Y465794D01*
X609114Y466466D01*
X609229Y466827D01*
X609421Y467189D01*
X609689Y467447D01*
X609958Y467499D01*
X610226Y467396D01*
X610418Y467137D01*
G01X612866Y464399D02*
X613134Y464451D01*
X613441Y464606D01*
X613633Y464864D01*
X613709Y465226D01*
X613633Y465587D01*
X613403Y465897D01*
X613058Y466052D01*
X612674D01*
X612444Y466156D01*
X612253Y466414D01*
X612176Y466776D01*
X612291Y467137D01*
X612559Y467396D01*
X612866Y467499D01*
X613173Y467396D01*
X613441Y467137D01*
X613556Y466776D01*
X613479Y466414D01*
X613288Y466156D01*
X613058Y466052D01*
X612674D01*
X612329Y465897D01*
X612099Y465587D01*
X612023Y465226D01*
X612099Y464864D01*
X612291Y464606D01*
X612598Y464451D01*
X612866Y464399D01*
G01X615966Y467499D02*
X615659Y467396D01*
X615429Y467137D01*
X615276Y466827D01*
X615161Y466414D01*
X615123Y465949D01*
X615161Y465484D01*
X615276Y465071D01*
X615429Y464761D01*
X615659Y464502D01*
X615966Y464399D01*
X616273Y464502D01*
X616503Y464761D01*
X616656Y465071D01*
X616771Y465484D01*
X616809Y465949D01*
X616771Y466414D01*
X616656Y466827D01*
X616503Y467137D01*
X616273Y467396D01*
X615966Y467499D01*
G01X606035Y485562D02*
Y488662D01*
X606994D01*
X607300Y488507D01*
X607492Y488300D01*
X607569Y487887D01*
X607492Y487474D01*
X607262Y487215D01*
X606994Y487060D01*
X606035D01*
G01X606994D02*
X607569Y485562D01*
G01X609174Y486854D02*
X609442Y487215D01*
X609672Y487422D01*
X609979Y487525D01*
X610247Y487422D01*
X610439Y487215D01*
X610592Y486905D01*
X610630Y486544D01*
X610592Y486234D01*
X610439Y485924D01*
X610209Y485665D01*
X609940Y485562D01*
X609634Y485665D01*
X609365Y485975D01*
X609212Y486440D01*
X609174Y486957D01*
X609250Y487629D01*
X609365Y487990D01*
X609557Y488352D01*
X609825Y488610D01*
X610094Y488662D01*
X610362Y488559D01*
X610554Y488300D01*
G01X613002Y485562D02*
X613270Y485614D01*
X613577Y485769D01*
X613769Y486027D01*
X613845Y486389D01*
X613769Y486750D01*
X613539Y487060D01*
X613194Y487215D01*
X612810D01*
X612580Y487319D01*
X612389Y487577D01*
X612312Y487939D01*
X612427Y488300D01*
X612695Y488559D01*
X613002Y488662D01*
X613309Y488559D01*
X613577Y488300D01*
X613692Y487939D01*
X613615Y487577D01*
X613424Y487319D01*
X613194Y487215D01*
X612810D01*
X612465Y487060D01*
X612235Y486750D01*
X612159Y486389D01*
X612235Y486027D01*
X612427Y485769D01*
X612734Y485614D01*
X613002Y485562D01*
G01X615374Y488145D02*
X615604Y488455D01*
X615872Y488610D01*
X616179Y488662D01*
X616562Y488559D01*
X616830Y488300D01*
X616907Y487990D01*
X616869Y487680D01*
X616715Y487422D01*
X615949Y486905D01*
X615604Y486544D01*
X615374Y486027D01*
X615297Y485562D01*
X616907D01*
G01X606035Y481666D02*
Y484766D01*
X606994D01*
X607300Y484611D01*
X607492Y484404D01*
X607569Y483991D01*
X607492Y483578D01*
X607262Y483319D01*
X606994Y483164D01*
X606035D01*
G01X606994D02*
X607569Y481666D01*
G01X609174Y482958D02*
X609442Y483319D01*
X609672Y483526D01*
X609979Y483629D01*
X610247Y483526D01*
X610439Y483319D01*
X610592Y483009D01*
X610630Y482648D01*
X610592Y482338D01*
X610439Y482028D01*
X610209Y481769D01*
X609940Y481666D01*
X609634Y481769D01*
X609365Y482079D01*
X609212Y482544D01*
X609174Y483061D01*
X609250Y483733D01*
X609365Y484094D01*
X609557Y484456D01*
X609825Y484714D01*
X610094Y484766D01*
X610362Y484663D01*
X610554Y484404D01*
G01X612925Y481666D02*
X613002Y482338D01*
X613117Y482906D01*
X613270Y483423D01*
X613462Y483991D01*
X613769Y484766D01*
X612235D01*
G01X616562Y481666D02*
Y484766D01*
X615144Y482544D01*
X617060D01*
G01X606035Y477666D02*
Y480766D01*
X606994D01*
X607300Y480611D01*
X607492Y480404D01*
X607569Y479991D01*
X607492Y479578D01*
X607262Y479319D01*
X606994Y479164D01*
X606035D01*
G01X606994D02*
X607569Y477666D01*
G01X609174Y478958D02*
X609442Y479319D01*
X609672Y479526D01*
X609979Y479629D01*
X610247Y479526D01*
X610439Y479319D01*
X610592Y479009D01*
X610630Y478648D01*
X610592Y478338D01*
X610439Y478028D01*
X610209Y477769D01*
X609940Y477666D01*
X609634Y477769D01*
X609365Y478079D01*
X609212Y478544D01*
X609174Y479061D01*
X609250Y479733D01*
X609365Y480094D01*
X609557Y480456D01*
X609825Y480714D01*
X610094Y480766D01*
X610362Y480663D01*
X610554Y480404D01*
G01X612925Y477666D02*
X613002Y478338D01*
X613117Y478906D01*
X613270Y479423D01*
X613462Y479991D01*
X613769Y480766D01*
X612235D01*
G01X615374Y480249D02*
X615604Y480559D01*
X615872Y480714D01*
X616179Y480766D01*
X616562Y480663D01*
X616830Y480404D01*
X616907Y480094D01*
X616869Y479784D01*
X616715Y479526D01*
X615949Y479009D01*
X615604Y478648D01*
X615374Y478131D01*
X615297Y477666D01*
X616907D01*
G01X605830Y472424D02*
Y475524D01*
X606789D01*
X607095Y475369D01*
X607287Y475162D01*
X607364Y474749D01*
X607287Y474336D01*
X607057Y474077D01*
X606789Y473922D01*
X605830D01*
G01X606789D02*
X607364Y472424D01*
G01X608969Y473716D02*
X609237Y474077D01*
X609467Y474284D01*
X609774Y474387D01*
X610042Y474284D01*
X610234Y474077D01*
X610387Y473767D01*
X610425Y473406D01*
X610387Y473096D01*
X610234Y472786D01*
X610004Y472527D01*
X609735Y472424D01*
X609429Y472527D01*
X609160Y472837D01*
X609007Y473302D01*
X608969Y473819D01*
X609045Y474491D01*
X609160Y474852D01*
X609352Y475214D01*
X609620Y475472D01*
X609889Y475524D01*
X610157Y475421D01*
X610349Y475162D01*
G01X612069Y475007D02*
X612299Y475317D01*
X612567Y475472D01*
X612874Y475524D01*
X613257Y475421D01*
X613525Y475162D01*
X613602Y474852D01*
X613564Y474542D01*
X613410Y474284D01*
X612644Y473767D01*
X612299Y473406D01*
X612069Y472889D01*
X611992Y472424D01*
X613602D01*
G01X615054Y473044D02*
X615284Y472682D01*
X615590Y472476D01*
X615935Y472424D01*
X616242Y472476D01*
X616549Y472734D01*
X616740Y473044D01*
X616779Y473354D01*
X616702Y473716D01*
X616434Y473974D01*
X616165Y474077D01*
X615820D01*
G01X616165D02*
X616395Y474232D01*
X616587Y474491D01*
X616664Y474801D01*
X616587Y475111D01*
X616395Y475369D01*
X616050Y475524D01*
X615705Y475472D01*
X615360Y475266D01*
G01X607645Y492428D02*
X607415Y492583D01*
X607147Y492686D01*
X606840D01*
X606495Y492531D01*
X606227Y492273D01*
X606035Y491963D01*
X605882Y491446D01*
X605844Y490981D01*
X605920Y490516D01*
X606035Y490206D01*
X606265Y489896D01*
X606534Y489689D01*
X606802Y489586D01*
X607070D01*
X607339Y489689D01*
X607569Y489844D01*
X607760Y490051D01*
G01X609059D02*
X609289Y489793D01*
X609557Y489638D01*
X609902Y489586D01*
X610247Y489689D01*
X610515Y489896D01*
X610707Y490258D01*
X610745Y490671D01*
X610669Y491084D01*
X610477Y491343D01*
X610209Y491549D01*
X609940Y491601D01*
X609672Y491549D01*
X609327Y491343D01*
X609442Y492686D01*
X610477D01*
G01X612274Y490878D02*
X612542Y491239D01*
X612772Y491446D01*
X613079Y491549D01*
X613347Y491446D01*
X613539Y491239D01*
X613692Y490929D01*
X613730Y490568D01*
X613692Y490258D01*
X613539Y489948D01*
X613309Y489689D01*
X613040Y489586D01*
X612734Y489689D01*
X612465Y489999D01*
X612312Y490464D01*
X612274Y490981D01*
X612350Y491653D01*
X612465Y492014D01*
X612657Y492376D01*
X612925Y492634D01*
X613194Y492686D01*
X613462Y492583D01*
X613654Y492324D01*
G01X615374Y490878D02*
X615642Y491239D01*
X615872Y491446D01*
X616179Y491549D01*
X616447Y491446D01*
X616639Y491239D01*
X616792Y490929D01*
X616830Y490568D01*
X616792Y490258D01*
X616639Y489948D01*
X616409Y489689D01*
X616140Y489586D01*
X615834Y489689D01*
X615565Y489999D01*
X615412Y490464D01*
X615374Y490981D01*
X615450Y491653D01*
X615565Y492014D01*
X615757Y492376D01*
X616025Y492634D01*
X616294Y492686D01*
X616562Y492583D01*
X616754Y492324D01*
G01X621705Y490563D02*
X621398Y490615D01*
X621130Y490821D01*
X620900Y491131D01*
X620747Y491493D01*
X620670Y491906D01*
Y492320D01*
X620747Y492733D01*
X620900Y493095D01*
X621130Y493405D01*
X621398Y493611D01*
X621705Y493663D01*
X622012Y493611D01*
X622280Y493405D01*
X622510Y493095D01*
X622663Y492733D01*
X622740Y492320D01*
Y491906D01*
X622663Y491493D01*
X622510Y491131D01*
X622280Y490821D01*
X622012Y490615D01*
X621705Y490563D01*
G01X622012Y491390D02*
X622472Y490563D01*
G01X624077Y493146D02*
X624307Y493456D01*
X624575Y493611D01*
X624882Y493663D01*
X625265Y493560D01*
X625533Y493301D01*
X625610Y492991D01*
X625572Y492681D01*
X625418Y492423D01*
X624652Y491906D01*
X624307Y491545D01*
X624077Y491028D01*
X624000Y490563D01*
X625610D01*
G01X628365D02*
Y493663D01*
X626947Y491441D01*
X628863D01*
G01X612906Y522301D02*
X606083D01*
Y522361D01*
G01X621632Y523567D02*
X606632D01*
G01Y530367D02*
X621632D01*
G01X606632Y523567D02*
Y530367D01*
G01X614132Y530267D02*
Y523667D01*
G01X622123Y532161D02*
X606123D01*
G01D02*
Y544365D01*
G01X615304Y545164D02*
Y548364D01*
G01X621504Y545164D02*
X615304D01*
G01Y548364D02*
X621504D01*
G01X618404Y545264D02*
Y548264D01*
G01X605953Y550944D02*
Y548722D01*
X606106Y548257D01*
X606413Y547947D01*
X606796Y547844D01*
X607179Y547947D01*
X607486Y548257D01*
X607639Y548722D01*
Y550944D01*
G01X609053Y548309D02*
X609283Y548051D01*
X609551Y547896D01*
X609896Y547844D01*
X610241Y547947D01*
X610509Y548154D01*
X610701Y548516D01*
X610739Y548929D01*
X610663Y549342D01*
X610471Y549601D01*
X610203Y549807D01*
X609934Y549859D01*
X609666Y549807D01*
X609321Y549601D01*
X609436Y550944D01*
X610471D01*
G01X612996Y547844D02*
X613264Y547896D01*
X613571Y548051D01*
X613763Y548309D01*
X613839Y548671D01*
X613763Y549032D01*
X613533Y549342D01*
X613188Y549497D01*
X612804D01*
X612574Y549601D01*
X612383Y549859D01*
X612306Y550221D01*
X612421Y550582D01*
X612689Y550841D01*
X612996Y550944D01*
X613303Y550841D01*
X613571Y550582D01*
X613686Y550221D01*
X613609Y549859D01*
X613418Y549601D01*
X613188Y549497D01*
X612804D01*
X612459Y549342D01*
X612229Y549032D01*
X612153Y548671D01*
X612229Y548309D01*
X612421Y548051D01*
X612728Y547896D01*
X612996Y547844D01*
G01X605963Y545243D02*
Y547743D01*
X605643Y547243D01*
G01Y545243D02*
X606283D01*
G01X606123Y544365D02*
X622123D01*
G01X614537Y565845D02*
Y559645D01*
G01D02*
X611337D01*
G01D02*
Y565845D01*
G01X619037D02*
Y559645D01*
G01D02*
X615837D01*
G01D02*
Y565845D01*
G01X623537Y559645D02*
X620337D01*
G01D02*
Y565845D01*
G01X610037Y565645D02*
Y559445D01*
G01D02*
X606837D01*
G01D02*
Y565645D01*
G01X606037D02*
Y559445D01*
G01X618458Y579827D02*
X618618Y579535D01*
X618832Y579369D01*
X619072Y579327D01*
X619285Y579369D01*
X619498Y579577D01*
X619632Y579827D01*
X619658Y580077D01*
X619605Y580369D01*
X619418Y580577D01*
X619232Y580660D01*
X618992D01*
G01X619232D02*
X619392Y580785D01*
X619525Y580994D01*
X619578Y581244D01*
X619525Y581494D01*
X619392Y581702D01*
X619152Y581827D01*
X618912Y581785D01*
X618672Y581619D01*
G01X620658Y579827D02*
X620818Y579535D01*
X621032Y579369D01*
X621272Y579327D01*
X621485Y579369D01*
X621698Y579577D01*
X621832Y579827D01*
X621858Y580077D01*
X621805Y580369D01*
X621618Y580577D01*
X621432Y580660D01*
X621192D01*
G01X621432D02*
X621592Y580785D01*
X621725Y580994D01*
X621778Y581244D01*
X621725Y581494D01*
X621592Y581702D01*
X621352Y581827D01*
X621112Y581785D01*
X620872Y581619D01*
G01X612396Y581187D02*
X612556Y580895D01*
X612770Y580729D01*
X613010Y580687D01*
X613223Y580729D01*
X613436Y580937D01*
X613570Y581187D01*
X613596Y581437D01*
X613543Y581729D01*
X613356Y581937D01*
X613170Y582020D01*
X612930D01*
G01X613170D02*
X613330Y582145D01*
X613463Y582354D01*
X613516Y582604D01*
X613463Y582854D01*
X613330Y583062D01*
X613090Y583187D01*
X612850Y583145D01*
X612610Y582979D01*
G01X614676Y582770D02*
X614836Y583020D01*
X615023Y583145D01*
X615236Y583187D01*
X615503Y583104D01*
X615690Y582895D01*
X615743Y582645D01*
X615716Y582395D01*
X615610Y582187D01*
X615076Y581770D01*
X614836Y581479D01*
X614676Y581062D01*
X614623Y580687D01*
X615743D01*
G01X616037Y567973D02*
X612937D01*
Y568932D01*
X613092Y569238D01*
X613299Y569430D01*
X613712Y569507D01*
X614125Y569430D01*
X614384Y569200D01*
X614539Y568932D01*
Y567973D01*
G01Y568932D02*
X616037Y569507D01*
G01X615572Y570997D02*
X615830Y571227D01*
X615985Y571495D01*
X616037Y571840D01*
X615934Y572185D01*
X615727Y572453D01*
X615365Y572645D01*
X614952Y572683D01*
X614539Y572607D01*
X614280Y572415D01*
X614074Y572147D01*
X614022Y571878D01*
X614074Y571610D01*
X614280Y571265D01*
X612937Y571380D01*
Y572415D01*
G01X614745Y574212D02*
X614384Y574480D01*
X614177Y574710D01*
X614074Y575017D01*
X614177Y575285D01*
X614384Y575477D01*
X614694Y575630D01*
X615055Y575668D01*
X615365Y575630D01*
X615675Y575477D01*
X615934Y575247D01*
X616037Y574978D01*
X615934Y574672D01*
X615624Y574403D01*
X615159Y574250D01*
X614642Y574212D01*
X613970Y574288D01*
X613609Y574403D01*
X613247Y574595D01*
X612989Y574863D01*
X612937Y575132D01*
X613040Y575400D01*
X613299Y575592D01*
G01X616037Y578040D02*
X615985Y578308D01*
X615830Y578615D01*
X615572Y578807D01*
X615210Y578883D01*
X614849Y578807D01*
X614539Y578577D01*
X614384Y578232D01*
Y577848D01*
X614280Y577618D01*
X614022Y577427D01*
X613660Y577350D01*
X613299Y577465D01*
X613040Y577733D01*
X612937Y578040D01*
X613040Y578347D01*
X613299Y578615D01*
X613660Y578730D01*
X614022Y578653D01*
X614280Y578462D01*
X614384Y578232D01*
Y577848D01*
X614539Y577503D01*
X614849Y577273D01*
X615210Y577197D01*
X615572Y577273D01*
X615830Y577465D01*
X615985Y577772D01*
X616037Y578040D01*
G01X611337Y565845D02*
X614537D01*
G01X620037Y567973D02*
X616937D01*
Y568932D01*
X617092Y569238D01*
X617299Y569430D01*
X617712Y569507D01*
X618125Y569430D01*
X618384Y569200D01*
X618539Y568932D01*
Y567973D01*
G01Y568932D02*
X620037Y569507D01*
G01X619572Y570997D02*
X619830Y571227D01*
X619985Y571495D01*
X620037Y571840D01*
X619934Y572185D01*
X619727Y572453D01*
X619365Y572645D01*
X618952Y572683D01*
X618539Y572607D01*
X618280Y572415D01*
X618074Y572147D01*
X618022Y571878D01*
X618074Y571610D01*
X618280Y571265D01*
X616937Y571380D01*
Y572415D01*
G01X620037Y574863D02*
X619365Y574940D01*
X618797Y575055D01*
X618280Y575208D01*
X617712Y575400D01*
X616937Y575707D01*
Y574173D01*
G01X620037Y578040D02*
X616937D01*
X617557Y577580D01*
G01X620037D02*
Y578500D01*
G01X615837Y565845D02*
X619037D01*
G01X620337D02*
X623537D01*
G01X612147Y568004D02*
X609047D01*
Y568963D01*
X609202Y569269D01*
X609409Y569461D01*
X609822Y569538D01*
X610235Y569461D01*
X610494Y569231D01*
X610649Y568963D01*
Y568004D01*
G01Y568963D02*
X612147Y569538D01*
G01X611682Y571028D02*
X611940Y571258D01*
X612095Y571526D01*
X612147Y571871D01*
X612044Y572216D01*
X611837Y572484D01*
X611475Y572676D01*
X611062Y572714D01*
X610649Y572638D01*
X610390Y572446D01*
X610184Y572178D01*
X610132Y571909D01*
X610184Y571641D01*
X610390Y571296D01*
X609047Y571411D01*
Y572446D01*
G01X611785Y574319D02*
X612044Y574588D01*
X612147Y574894D01*
X612044Y575201D01*
X611734Y575469D01*
X611269Y575661D01*
X610804Y575738D01*
X610235D01*
X609770Y575661D01*
X609357Y575469D01*
X609150Y575239D01*
X609047Y574971D01*
X609150Y574664D01*
X609357Y574434D01*
X609667Y574281D01*
X610080Y574204D01*
X610442Y574281D01*
X610804Y574473D01*
X611010Y574703D01*
X611062Y574971D01*
X610959Y575278D01*
X610700Y575508D01*
X610235Y575738D01*
G01X609564Y577343D02*
X609254Y577573D01*
X609099Y577841D01*
X609047Y578148D01*
X609150Y578531D01*
X609409Y578799D01*
X609719Y578876D01*
X610029Y578838D01*
X610287Y578684D01*
X610804Y577918D01*
X611165Y577573D01*
X611682Y577343D01*
X612147Y577266D01*
Y578876D01*
G01X606837Y565645D02*
X610037D01*
G01X607753Y568253D02*
X605253D01*
Y568919D01*
X605378Y569133D01*
X605545Y569266D01*
X605878Y569319D01*
X606211Y569266D01*
X606420Y569106D01*
X606545Y568919D01*
Y568253D01*
G01Y568919D02*
X607753Y569319D01*
G01X607378Y570399D02*
X607586Y570559D01*
X607711Y570746D01*
X607753Y570986D01*
X607670Y571226D01*
X607503Y571413D01*
X607211Y571546D01*
X606878Y571573D01*
X606545Y571519D01*
X606336Y571386D01*
X606170Y571199D01*
X606128Y571013D01*
X606170Y570826D01*
X606336Y570586D01*
X605253Y570666D01*
Y571386D01*
G01X606711Y572679D02*
X606420Y572866D01*
X606253Y573026D01*
X606170Y573239D01*
X606253Y573426D01*
X606420Y573559D01*
X606670Y573666D01*
X606961Y573693D01*
X607211Y573666D01*
X607461Y573559D01*
X607670Y573399D01*
X607753Y573213D01*
X607670Y572999D01*
X607420Y572813D01*
X607045Y572706D01*
X606628Y572679D01*
X606086Y572733D01*
X605795Y572813D01*
X605503Y572946D01*
X605295Y573133D01*
X605253Y573319D01*
X605336Y573506D01*
X605545Y573639D01*
G01X606711Y574879D02*
X606420Y575066D01*
X606253Y575226D01*
X606170Y575439D01*
X606253Y575626D01*
X606420Y575759D01*
X606670Y575866D01*
X606961Y575893D01*
X607211Y575866D01*
X607461Y575759D01*
X607670Y575599D01*
X607753Y575413D01*
X607670Y575199D01*
X607420Y575013D01*
X607045Y574906D01*
X606628Y574879D01*
X606086Y574933D01*
X605795Y575013D01*
X605503Y575146D01*
X605295Y575333D01*
X605253Y575519D01*
X605336Y575706D01*
X605545Y575839D01*
G01X618037Y585028D02*
X616220D01*
G01D02*
Y586945D01*
G01X613437Y591918D02*
X609437D01*
G01X607275Y582959D02*
X607150Y582799D01*
X607067Y582612D01*
Y582399D01*
X607192Y582159D01*
X607400Y581972D01*
X607650Y581839D01*
X608067Y581732D01*
X608442Y581705D01*
X608817Y581759D01*
X609067Y581839D01*
X609317Y581999D01*
X609484Y582185D01*
X609567Y582372D01*
Y582559D01*
X609484Y582745D01*
X609359Y582905D01*
X609192Y583039D01*
G01Y583985D02*
X609400Y584145D01*
X609525Y584332D01*
X609567Y584572D01*
X609484Y584812D01*
X609317Y584999D01*
X609025Y585132D01*
X608692Y585159D01*
X608359Y585105D01*
X608150Y584972D01*
X607984Y584785D01*
X607942Y584599D01*
X607984Y584412D01*
X608150Y584172D01*
X607067Y584252D01*
Y584972D01*
G01X607484Y586265D02*
X607234Y586425D01*
X607109Y586612D01*
X607067Y586825D01*
X607150Y587092D01*
X607359Y587279D01*
X607609Y587332D01*
X607859Y587305D01*
X608067Y587199D01*
X608484Y586665D01*
X608775Y586425D01*
X609192Y586265D01*
X609567Y586212D01*
Y587332D01*
G01X609275Y588519D02*
X609484Y588705D01*
X609567Y588919D01*
X609484Y589132D01*
X609234Y589319D01*
X608859Y589452D01*
X608484Y589505D01*
X608025D01*
X607650Y589452D01*
X607317Y589319D01*
X607150Y589159D01*
X607067Y588972D01*
X607150Y588759D01*
X607317Y588599D01*
X607567Y588492D01*
X607900Y588439D01*
X608192Y588492D01*
X608484Y588625D01*
X608650Y588785D01*
X608692Y588972D01*
X608609Y589185D01*
X608400Y589345D01*
X608025Y589505D01*
G01X613437Y601761D02*
X611437D01*
G01X612014Y620026D02*
Y622526D01*
X611694Y622026D01*
G01Y620026D02*
X612334D01*
G01X614161D02*
X614214Y620568D01*
X614294Y621026D01*
X614401Y621443D01*
X614534Y621901D01*
X614747Y622526D01*
X613681D01*
G01X617616Y626342D02*
Y628842D01*
X617296Y628342D01*
G01Y626342D02*
X617936D01*
G01X619309Y627384D02*
X619496Y627675D01*
X619656Y627842D01*
X619869Y627925D01*
X620056Y627842D01*
X620189Y627675D01*
X620296Y627425D01*
X620323Y627134D01*
X620296Y626884D01*
X620189Y626634D01*
X620029Y626425D01*
X619843Y626342D01*
X619629Y626425D01*
X619443Y626675D01*
X619336Y627050D01*
X619309Y627467D01*
X619363Y628009D01*
X619443Y628300D01*
X619576Y628592D01*
X619763Y628800D01*
X619949Y628842D01*
X620136Y628759D01*
X620269Y628550D01*
G01X616220Y618545D02*
Y620362D01*
G01D02*
X616320Y620462D01*
G01D02*
X618137D01*
G01X658161Y630809D02*
X607274D01*
Y641058D01*
X658698D01*
Y620799D01*
X674550D01*
Y615853D01*
X682714D01*
X680303Y618264D01*
X680210D01*
Y613080D01*
X682606Y615476D01*
Y615751D01*
G01X609649Y631600D02*
Y637800D01*
G01X612849Y631600D02*
X609649D01*
G01Y637800D02*
X612849D01*
G01D02*
Y631600D01*
G01X617702Y631540D02*
Y637740D01*
G01D02*
X620902D01*
G01Y631540D02*
X617702D01*
G01X611569Y657172D02*
Y653972D01*
G01D02*
X605369D01*
G01D02*
Y657172D01*
G01D02*
X611569D01*
G01Y652172D02*
Y648972D01*
G01X605369Y652172D02*
X611569D01*
G01X605369Y648972D02*
Y652172D01*
G01X611569Y648972D02*
X605369D01*
G01X611569Y662172D02*
Y658972D01*
G01D02*
X605369D01*
G01D02*
Y662172D01*
G01X613323Y670709D02*
X613093Y670864D01*
X612825Y670967D01*
X612518D01*
X612173Y670812D01*
X611905Y670554D01*
X611713Y670244D01*
X611560Y669727D01*
X611522Y669262D01*
X611598Y668797D01*
X611713Y668487D01*
X611943Y668177D01*
X612212Y667970D01*
X612480Y667867D01*
X612748D01*
X613017Y667970D01*
X613247Y668125D01*
X613438Y668332D01*
G01X614928Y668229D02*
X615197Y667970D01*
X615503Y667867D01*
X615810Y667970D01*
X616078Y668280D01*
X616270Y668745D01*
X616347Y669210D01*
Y669779D01*
X616270Y670244D01*
X616078Y670657D01*
X615848Y670864D01*
X615580Y670967D01*
X615273Y670864D01*
X615043Y670657D01*
X614890Y670347D01*
X614813Y669934D01*
X614890Y669572D01*
X615082Y669210D01*
X615312Y669004D01*
X615580Y668952D01*
X615887Y669055D01*
X616117Y669314D01*
X616347Y669779D01*
G01X618680Y667867D02*
Y670967D01*
X618220Y670347D01*
G01Y667867D02*
X619140D01*
G01X622240D02*
Y670967D01*
X620822Y668745D01*
X622738D01*
G01X616484Y676683D02*
Y673683D01*
G01X619584Y673583D02*
X613384D01*
G01D02*
Y676783D01*
G01X619584D02*
Y673583D01*
G01X605651Y666567D02*
X605496Y666337D01*
X605393Y666069D01*
Y665762D01*
X605548Y665417D01*
X605806Y665149D01*
X606116Y664957D01*
X606633Y664804D01*
X607098Y664766D01*
X607563Y664842D01*
X607873Y664957D01*
X608183Y665187D01*
X608390Y665456D01*
X608493Y665724D01*
Y665992D01*
X608390Y666261D01*
X608235Y666491D01*
X608028Y666682D01*
G01X608131Y668172D02*
X608390Y668441D01*
X608493Y668747D01*
X608390Y669054D01*
X608080Y669322D01*
X607615Y669514D01*
X607150Y669591D01*
X606581D01*
X606116Y669514D01*
X605703Y669322D01*
X605496Y669092D01*
X605393Y668824D01*
X605496Y668517D01*
X605703Y668287D01*
X606013Y668134D01*
X606426Y668057D01*
X606788Y668134D01*
X607150Y668326D01*
X607356Y668556D01*
X607408Y668824D01*
X607305Y669131D01*
X607046Y669361D01*
X606581Y669591D01*
G01X608493Y671924D02*
X605393D01*
X606013Y671464D01*
G01X608493D02*
Y672384D01*
G01X605910Y674296D02*
X605600Y674526D01*
X605445Y674794D01*
X605393Y675101D01*
X605496Y675484D01*
X605755Y675752D01*
X606065Y675829D01*
X606375Y675791D01*
X606633Y675637D01*
X607150Y674871D01*
X607511Y674526D01*
X608028Y674296D01*
X608493Y674219D01*
Y675829D01*
G01X605369Y662172D02*
X611569D01*
G01X613384Y676783D02*
X619584D01*
G01X608892Y676725D02*
X605692D01*
G01X605792Y679825D02*
X608792D01*
G01X608892Y682925D02*
Y676725D01*
G01X605692D02*
Y682925D01*
G01D02*
X608892D01*
G01X620648Y678736D02*
X620493Y678506D01*
X620390Y678238D01*
Y677931D01*
X620545Y677586D01*
X620803Y677318D01*
X621113Y677126D01*
X621630Y676973D01*
X622095Y676935D01*
X622560Y677011D01*
X622870Y677126D01*
X623180Y677356D01*
X623387Y677625D01*
X623490Y677893D01*
Y678161D01*
X623387Y678430D01*
X623232Y678660D01*
X623025Y678851D01*
G01X623128Y680341D02*
X623387Y680610D01*
X623490Y680916D01*
X623387Y681223D01*
X623077Y681491D01*
X622612Y681683D01*
X622147Y681760D01*
X621578D01*
X621113Y681683D01*
X620700Y681491D01*
X620493Y681261D01*
X620390Y680993D01*
X620493Y680686D01*
X620700Y680456D01*
X621010Y680303D01*
X621423Y680226D01*
X621785Y680303D01*
X622147Y680495D01*
X622353Y680725D01*
X622405Y680993D01*
X622302Y681300D01*
X622043Y681530D01*
X621578Y681760D01*
G01X623490Y684093D02*
X620390D01*
X621010Y683633D01*
G01X623490D02*
Y684553D01*
G01X622870Y686350D02*
X623232Y686580D01*
X623438Y686886D01*
X623490Y687231D01*
X623438Y687538D01*
X623180Y687845D01*
X622870Y688036D01*
X622560Y688075D01*
X622198Y687998D01*
X621940Y687730D01*
X621837Y687461D01*
Y687116D01*
G01Y687461D02*
X621682Y687691D01*
X621423Y687883D01*
X621113Y687960D01*
X620803Y687883D01*
X620545Y687691D01*
X620390Y687346D01*
X620442Y687001D01*
X620648Y686656D01*
G01X618842Y678022D02*
X615642D01*
G01X618842Y684222D02*
Y678022D01*
G01X615742Y681122D02*
X618742D01*
G01X615642Y678022D02*
Y684222D01*
G01D02*
X618842D01*
G01X608572Y687279D02*
X605372D01*
G01X608572Y693479D02*
Y687279D01*
G01X605372D02*
Y693479D01*
G01X622595Y691078D02*
X619495D01*
Y692037D01*
X619650Y692343D01*
X619857Y692535D01*
X620270Y692612D01*
X620683Y692535D01*
X620942Y692305D01*
X621097Y692037D01*
Y691078D01*
G01Y692037D02*
X622595Y692612D01*
G01Y694945D02*
X619495D01*
X620115Y694485D01*
G01X622595D02*
Y695405D01*
G01X621975Y697202D02*
X622337Y697432D01*
X622543Y697738D01*
X622595Y698083D01*
X622543Y698390D01*
X622285Y698697D01*
X621975Y698888D01*
X621665Y698927D01*
X621303Y698850D01*
X621045Y698582D01*
X620942Y698313D01*
Y697968D01*
G01Y698313D02*
X620787Y698543D01*
X620528Y698735D01*
X620218Y698812D01*
X619908Y698735D01*
X619650Y698543D01*
X619495Y698198D01*
X619547Y697853D01*
X619753Y697508D01*
G01X619495Y701145D02*
X619598Y700838D01*
X619857Y700608D01*
X620167Y700455D01*
X620580Y700340D01*
X621045Y700302D01*
X621510Y700340D01*
X621923Y700455D01*
X622233Y700608D01*
X622492Y700838D01*
X622595Y701145D01*
X622492Y701452D01*
X622233Y701682D01*
X621923Y701835D01*
X621510Y701950D01*
X621045Y701988D01*
X620580Y701950D01*
X620167Y701835D01*
X619857Y701682D01*
X619598Y701452D01*
X619495Y701145D01*
G01X622595Y704705D02*
X619495D01*
X621717Y703287D01*
Y705203D01*
G01X615482Y690143D02*
X612282D01*
G01X615482Y696343D02*
Y690143D01*
G01X612282D02*
Y696343D01*
G01X605372Y693479D02*
X608572D01*
G01X612282Y696343D02*
X615482D01*
G01X615771Y706601D02*
Y700401D01*
G01D02*
X612573D01*
G01D02*
Y706601D01*
G01D02*
X615771D01*
G01X611772Y700401D02*
X608572D01*
G01X611772Y706601D02*
Y700401D01*
G01X608572D02*
Y706601D01*
G01D02*
X611772D01*
G01X619913Y710574D02*
X616813D01*
Y711533D01*
X616968Y711839D01*
X617175Y712031D01*
X617588Y712108D01*
X618001Y712031D01*
X618260Y711801D01*
X618415Y711533D01*
Y710574D01*
G01Y711533D02*
X619913Y712108D01*
G01Y714441D02*
X616813D01*
X617433Y713981D01*
G01X619913D02*
Y714901D01*
G01Y717541D02*
X616813D01*
X617433Y717081D01*
G01X619913D02*
Y718001D01*
G01X618621Y719913D02*
X618260Y720181D01*
X618053Y720411D01*
X617950Y720718D01*
X618053Y720986D01*
X618260Y721178D01*
X618570Y721331D01*
X618931Y721369D01*
X619241Y721331D01*
X619551Y721178D01*
X619810Y720948D01*
X619913Y720679D01*
X619810Y720373D01*
X619500Y720104D01*
X619035Y719951D01*
X618518Y719913D01*
X617846Y719989D01*
X617485Y720104D01*
X617123Y720296D01*
X616865Y720564D01*
X616813Y720833D01*
X616916Y721101D01*
X617175Y721293D01*
G01X619913Y723664D02*
X619241Y723741D01*
X618673Y723856D01*
X618156Y724009D01*
X617588Y724201D01*
X616813Y724508D01*
Y722974D01*
G01X612040Y737556D02*
X608840D01*
G01X612040Y743756D02*
Y737556D01*
G01X608840D02*
Y743756D01*
G01X607540D02*
Y737556D01*
G01X613340D02*
Y743756D01*
G01X616540Y737556D02*
X613340D01*
G01X616540Y743756D02*
Y737556D01*
G01X617840D02*
Y743756D01*
G01X621040Y737556D02*
X617840D01*
G01X613340Y732256D02*
X616540D01*
G01X613340Y726056D02*
Y732256D01*
G01X616540Y726056D02*
X613340D01*
G01X616540Y732256D02*
Y726056D01*
G01X617840Y732256D02*
X621040D01*
G01X617840Y726056D02*
Y732256D01*
G01X621040Y726056D02*
X617840D01*
G01X608840Y732256D02*
X612040D01*
G01X608840Y726056D02*
Y732256D01*
G01X612040Y726056D02*
X608840D01*
G01X612040Y732256D02*
Y726056D01*
G01X607540Y732256D02*
Y726056D01*
G01X608840Y743756D02*
X612040D01*
G01X611940Y740656D02*
X608940D01*
G01X613340Y743756D02*
X616540D01*
G01X617840D02*
X621040D01*
G01X617508Y748311D02*
X614408D01*
Y749270D01*
X614563Y749576D01*
X614770Y749768D01*
X615183Y749845D01*
X615596Y749768D01*
X615855Y749538D01*
X616010Y749270D01*
Y748311D01*
G01Y749270D02*
X617508Y749845D01*
G01Y752178D02*
X617456Y752446D01*
X617301Y752753D01*
X617043Y752945D01*
X616681Y753021D01*
X616320Y752945D01*
X616010Y752715D01*
X615855Y752370D01*
Y751986D01*
X615751Y751756D01*
X615493Y751565D01*
X615131Y751488D01*
X614770Y751603D01*
X614511Y751871D01*
X614408Y752178D01*
X614511Y752485D01*
X614770Y752753D01*
X615131Y752868D01*
X615493Y752791D01*
X615751Y752600D01*
X615855Y752370D01*
Y751986D01*
X616010Y751641D01*
X616320Y751411D01*
X616681Y751335D01*
X617043Y751411D01*
X617301Y751603D01*
X617456Y751910D01*
X617508Y752178D01*
G01X614925Y754550D02*
X614615Y754780D01*
X614460Y755048D01*
X614408Y755355D01*
X614511Y755738D01*
X614770Y756006D01*
X615080Y756083D01*
X615390Y756045D01*
X615648Y755891D01*
X616165Y755125D01*
X616526Y754780D01*
X617043Y754550D01*
X617508Y754473D01*
Y756083D01*
G01X617043Y757535D02*
X617301Y757765D01*
X617456Y758033D01*
X617508Y758378D01*
X617405Y758723D01*
X617198Y758991D01*
X616836Y759183D01*
X616423Y759221D01*
X616010Y759145D01*
X615751Y758953D01*
X615545Y758685D01*
X615493Y758416D01*
X615545Y758148D01*
X615751Y757803D01*
X614408Y757918D01*
Y758953D01*
G01X622008Y748311D02*
X618908D01*
Y749270D01*
X619063Y749576D01*
X619270Y749768D01*
X619683Y749845D01*
X620096Y749768D01*
X620355Y749538D01*
X620510Y749270D01*
Y748311D01*
G01Y749270D02*
X622008Y749845D01*
G01Y752178D02*
X621956Y752446D01*
X621801Y752753D01*
X621543Y752945D01*
X621181Y753021D01*
X620820Y752945D01*
X620510Y752715D01*
X620355Y752370D01*
Y751986D01*
X620251Y751756D01*
X619993Y751565D01*
X619631Y751488D01*
X619270Y751603D01*
X619011Y751871D01*
X618908Y752178D01*
X619011Y752485D01*
X619270Y752753D01*
X619631Y752868D01*
X619993Y752791D01*
X620251Y752600D01*
X620355Y752370D01*
Y751986D01*
X620510Y751641D01*
X620820Y751411D01*
X621181Y751335D01*
X621543Y751411D01*
X621801Y751603D01*
X621956Y751910D01*
X622008Y752178D01*
G01X619425Y754550D02*
X619115Y754780D01*
X618960Y755048D01*
X618908Y755355D01*
X619011Y755738D01*
X619270Y756006D01*
X619580Y756083D01*
X619890Y756045D01*
X620148Y755891D01*
X620665Y755125D01*
X621026Y754780D01*
X621543Y754550D01*
X622008Y754473D01*
Y756083D01*
G01X621388Y757535D02*
X621750Y757765D01*
X621956Y758071D01*
X622008Y758416D01*
X621956Y758723D01*
X621698Y759030D01*
X621388Y759221D01*
X621078Y759260D01*
X620716Y759183D01*
X620458Y758915D01*
X620355Y758646D01*
Y758301D01*
G01Y758646D02*
X620200Y758876D01*
X619941Y759068D01*
X619631Y759145D01*
X619321Y759068D01*
X619063Y758876D01*
X618908Y758531D01*
X618960Y758186D01*
X619166Y757841D01*
G01X612857Y748311D02*
X609757D01*
Y749270D01*
X609912Y749576D01*
X610119Y749768D01*
X610532Y749845D01*
X610945Y749768D01*
X611204Y749538D01*
X611359Y749270D01*
Y748311D01*
G01Y749270D02*
X612857Y749845D01*
G01Y752178D02*
X612805Y752446D01*
X612650Y752753D01*
X612392Y752945D01*
X612030Y753021D01*
X611669Y752945D01*
X611359Y752715D01*
X611204Y752370D01*
Y751986D01*
X611100Y751756D01*
X610842Y751565D01*
X610480Y751488D01*
X610119Y751603D01*
X609860Y751871D01*
X609757Y752178D01*
X609860Y752485D01*
X610119Y752753D01*
X610480Y752868D01*
X610842Y752791D01*
X611100Y752600D01*
X611204Y752370D01*
Y751986D01*
X611359Y751641D01*
X611669Y751411D01*
X612030Y751335D01*
X612392Y751411D01*
X612650Y751603D01*
X612805Y751910D01*
X612857Y752178D01*
G01X612495Y754626D02*
X612754Y754895D01*
X612857Y755201D01*
X612754Y755508D01*
X612444Y755776D01*
X611979Y755968D01*
X611514Y756045D01*
X610945D01*
X610480Y755968D01*
X610067Y755776D01*
X609860Y755546D01*
X609757Y755278D01*
X609860Y754971D01*
X610067Y754741D01*
X610377Y754588D01*
X610790Y754511D01*
X611152Y754588D01*
X611514Y754780D01*
X611720Y755010D01*
X611772Y755278D01*
X611669Y755585D01*
X611410Y755815D01*
X610945Y756045D01*
G01X612857Y758301D02*
X612185Y758378D01*
X611617Y758493D01*
X611100Y758646D01*
X610532Y758838D01*
X609757Y759145D01*
Y757611D01*
G01X608357Y748311D02*
X605257D01*
Y749270D01*
X605412Y749576D01*
X605619Y749768D01*
X606032Y749845D01*
X606445Y749768D01*
X606704Y749538D01*
X606859Y749270D01*
Y748311D01*
G01Y749270D02*
X608357Y749845D01*
G01X607995Y751526D02*
X608254Y751795D01*
X608357Y752101D01*
X608254Y752408D01*
X607944Y752676D01*
X607479Y752868D01*
X607014Y752945D01*
X606445D01*
X605980Y752868D01*
X605567Y752676D01*
X605360Y752446D01*
X605257Y752178D01*
X605360Y751871D01*
X605567Y751641D01*
X605877Y751488D01*
X606290Y751411D01*
X606652Y751488D01*
X607014Y751680D01*
X607220Y751910D01*
X607272Y752178D01*
X607169Y752485D01*
X606910Y752715D01*
X606445Y752945D01*
G01X605257Y755278D02*
X605360Y754971D01*
X605619Y754741D01*
X605929Y754588D01*
X606342Y754473D01*
X606807Y754435D01*
X607272Y754473D01*
X607685Y754588D01*
X607995Y754741D01*
X608254Y754971D01*
X608357Y755278D01*
X608254Y755585D01*
X607995Y755815D01*
X607685Y755968D01*
X607272Y756083D01*
X606807Y756121D01*
X606342Y756083D01*
X605929Y755968D01*
X605619Y755815D01*
X605360Y755585D01*
X605257Y755278D01*
G01Y758378D02*
X605360Y758071D01*
X605619Y757841D01*
X605929Y757688D01*
X606342Y757573D01*
X606807Y757535D01*
X607272Y757573D01*
X607685Y757688D01*
X607995Y757841D01*
X608254Y758071D01*
X608357Y758378D01*
X608254Y758685D01*
X607995Y758915D01*
X607685Y759068D01*
X607272Y759183D01*
X606807Y759221D01*
X606342Y759183D01*
X605929Y759068D01*
X605619Y758915D01*
X605360Y758685D01*
X605257Y758378D01*
G01X612098Y764380D02*
X611943Y764150D01*
X611840Y763882D01*
Y763575D01*
X611995Y763230D01*
X612253Y762962D01*
X612563Y762770D01*
X613080Y762617D01*
X613545Y762579D01*
X614010Y762655D01*
X614320Y762770D01*
X614630Y763000D01*
X614837Y763269D01*
X614940Y763537D01*
Y763805D01*
X614837Y764074D01*
X614682Y764304D01*
X614475Y764495D01*
G01Y765794D02*
X614733Y766024D01*
X614888Y766292D01*
X614940Y766637D01*
X614837Y766982D01*
X614630Y767250D01*
X614268Y767442D01*
X613855Y767480D01*
X613442Y767404D01*
X613183Y767212D01*
X612977Y766944D01*
X612925Y766675D01*
X612977Y766407D01*
X613183Y766062D01*
X611840Y766177D01*
Y767212D01*
G01X614940Y769737D02*
X614888Y770005D01*
X614733Y770312D01*
X614475Y770504D01*
X614113Y770580D01*
X613752Y770504D01*
X613442Y770274D01*
X613287Y769929D01*
Y769545D01*
X613183Y769315D01*
X612925Y769124D01*
X612563Y769047D01*
X612202Y769162D01*
X611943Y769430D01*
X611840Y769737D01*
X611943Y770044D01*
X612202Y770312D01*
X612563Y770427D01*
X612925Y770350D01*
X613183Y770159D01*
X613287Y769929D01*
Y769545D01*
X613442Y769200D01*
X613752Y768970D01*
X614113Y768894D01*
X614475Y768970D01*
X614733Y769162D01*
X614888Y769469D01*
X614940Y769737D01*
G01Y772837D02*
X614888Y773105D01*
X614733Y773412D01*
X614475Y773604D01*
X614113Y773680D01*
X613752Y773604D01*
X613442Y773374D01*
X613287Y773029D01*
Y772645D01*
X613183Y772415D01*
X612925Y772224D01*
X612563Y772147D01*
X612202Y772262D01*
X611943Y772530D01*
X611840Y772837D01*
X611943Y773144D01*
X612202Y773412D01*
X612563Y773527D01*
X612925Y773450D01*
X613183Y773259D01*
X613287Y773029D01*
Y772645D01*
X613442Y772300D01*
X613752Y772070D01*
X614113Y771994D01*
X614475Y772070D01*
X614733Y772262D01*
X614888Y772569D01*
X614940Y772837D01*
G01X610918Y762770D02*
X607818D01*
Y763729D01*
X607973Y764035D01*
X608180Y764227D01*
X608593Y764304D01*
X609006Y764227D01*
X609265Y763997D01*
X609420Y763729D01*
Y762770D01*
G01Y763729D02*
X610918Y764304D01*
G01Y766637D02*
X607818D01*
X608438Y766177D01*
G01X610918D02*
Y767097D01*
G01X608335Y769009D02*
X608025Y769239D01*
X607870Y769507D01*
X607818Y769814D01*
X607921Y770197D01*
X608180Y770465D01*
X608490Y770542D01*
X608800Y770504D01*
X609058Y770350D01*
X609575Y769584D01*
X609936Y769239D01*
X610453Y769009D01*
X610918Y768932D01*
Y770542D01*
G01Y772837D02*
X607818D01*
X608438Y772377D01*
G01X610918D02*
Y773297D01*
G01X610556Y775285D02*
X610815Y775554D01*
X610918Y775860D01*
X610815Y776167D01*
X610505Y776435D01*
X610040Y776627D01*
X609575Y776704D01*
X609006D01*
X608541Y776627D01*
X608128Y776435D01*
X607921Y776205D01*
X607818Y775937D01*
X607921Y775630D01*
X608128Y775400D01*
X608438Y775247D01*
X608851Y775170D01*
X609213Y775247D01*
X609575Y775439D01*
X609781Y775669D01*
X609833Y775937D01*
X609730Y776244D01*
X609471Y776474D01*
X609006Y776704D01*
G01X638029Y13121D02*
X637649Y13371D01*
X637206Y13538D01*
X636699D01*
X636129Y13288D01*
X635686Y12871D01*
X635369Y12371D01*
X635116Y11538D01*
X635053Y10788D01*
X635179Y10038D01*
X635369Y9538D01*
X635749Y9038D01*
X636193Y8705D01*
X636636Y8538D01*
X637079D01*
X637523Y8705D01*
X637903Y8955D01*
X638219Y9288D01*
G01X640469Y8538D02*
Y13538D01*
X641989D01*
X642496Y13288D01*
X642876Y12705D01*
X643003Y12038D01*
X642876Y11371D01*
X642559Y10871D01*
X641989Y10621D01*
X640469D01*
G01X645569Y13538D02*
Y8538D01*
X648103D01*
G01X650543D02*
Y13538D01*
X651809D01*
X652316Y13288D01*
X652696Y12955D01*
X653013Y12455D01*
X653266Y11871D01*
X653329Y11038D01*
X653266Y10205D01*
X653013Y9621D01*
X652696Y9121D01*
X652316Y8788D01*
X651809Y8538D01*
X650543D01*
G01X655643Y9538D02*
X656023Y8955D01*
X656529Y8621D01*
X657099Y8538D01*
X657606Y8621D01*
X658113Y9038D01*
X658429Y9538D01*
X658493Y10038D01*
X658366Y10621D01*
X657923Y11038D01*
X657479Y11205D01*
X656909D01*
G01X657479D02*
X657859Y11455D01*
X658176Y11871D01*
X658303Y12371D01*
X658176Y12871D01*
X657859Y13288D01*
X657289Y13538D01*
X656719Y13455D01*
X656149Y13121D01*
G01X665969Y9538D02*
X666286Y9038D01*
X666666Y8705D01*
X667109Y8538D01*
X667616Y8705D01*
X667996Y9038D01*
X668376Y9538D01*
X668503Y10205D01*
Y13538D01*
G01X672336D02*
Y8538D01*
G01X670879Y13538D02*
X673793D01*
G01X675853Y8538D02*
X677436Y13538D01*
X679019Y8538D01*
G01X678449Y10288D02*
X676423D01*
G01X682916Y11038D02*
X684183D01*
Y9538D01*
X683803Y9038D01*
X683359Y8705D01*
X682726Y8538D01*
X682093Y8705D01*
X681649Y9038D01*
X681269Y9538D01*
X681016Y10121D01*
X680889Y10788D01*
Y11371D01*
X681016Y11871D01*
X681269Y12455D01*
X681649Y12955D01*
X682029Y13288D01*
X682536Y13538D01*
X682979D01*
X683486Y13371D01*
X683866Y13038D01*
G01X635353Y14979D02*
X686085D01*
Y6240D01*
X634168D01*
Y14979D01*
X635353D01*
G01X629109Y25674D02*
Y28774D01*
X628649Y28154D01*
G01Y25674D02*
X629569D01*
G01X632209Y28774D02*
X631902Y28671D01*
X631672Y28412D01*
X631519Y28102D01*
X631404Y27689D01*
X631366Y27224D01*
X631404Y26759D01*
X631519Y26346D01*
X631672Y26036D01*
X631902Y25777D01*
X632209Y25674D01*
X632516Y25777D01*
X632746Y26036D01*
X632899Y26346D01*
X633014Y26759D01*
X633052Y27224D01*
X633014Y27689D01*
X632899Y28102D01*
X632746Y28412D01*
X632516Y28671D01*
X632209Y28774D01*
G01X634183Y17520D02*
X634375Y17210D01*
X634605Y17003D01*
X634873Y16900D01*
X635180Y17003D01*
X635410Y17210D01*
X635640Y17520D01*
X635717Y17933D01*
Y20000D01*
G01X637322Y19483D02*
X637552Y19793D01*
X637820Y19948D01*
X638127Y20000D01*
X638510Y19897D01*
X638778Y19638D01*
X638855Y19328D01*
X638817Y19018D01*
X638663Y18760D01*
X637897Y18243D01*
X637552Y17882D01*
X637322Y17365D01*
X637245Y16900D01*
X638855D01*
G01X641073D02*
X641150Y17572D01*
X641265Y18140D01*
X641418Y18657D01*
X641610Y19225D01*
X641917Y20000D01*
X640383D01*
G01X685947Y23409D02*
X633979D01*
G01D02*
Y44197D01*
G01X623355D02*
Y23409D01*
G01X630027Y41936D02*
X630296Y41677D01*
X630602Y41574D01*
X630909Y41677D01*
X631177Y41987D01*
X631369Y42452D01*
X631446Y42917D01*
Y43486D01*
X631369Y43951D01*
X631177Y44364D01*
X630947Y44571D01*
X630679Y44674D01*
X630372Y44571D01*
X630142Y44364D01*
X629989Y44054D01*
X629912Y43641D01*
X629989Y43279D01*
X630181Y42917D01*
X630411Y42711D01*
X630679Y42659D01*
X630986Y42762D01*
X631216Y43021D01*
X631446Y43486D01*
G01X633979Y44197D02*
X685947D01*
G01X625745Y42054D02*
Y45154D01*
X625285Y44534D01*
G01Y42054D02*
X626205D01*
G01X637420Y45986D02*
X634320D01*
Y46945D01*
X634475Y47251D01*
X634682Y47443D01*
X635095Y47520D01*
X635508Y47443D01*
X635767Y47213D01*
X635922Y46945D01*
Y45986D01*
G01Y46945D02*
X637420Y47520D01*
G01Y49853D02*
X634320D01*
X634940Y49393D01*
G01X637420D02*
Y50313D01*
G01X634837Y52225D02*
X634527Y52455D01*
X634372Y52723D01*
X634320Y53030D01*
X634423Y53413D01*
X634682Y53681D01*
X634992Y53758D01*
X635302Y53720D01*
X635560Y53566D01*
X636077Y52800D01*
X636438Y52455D01*
X636955Y52225D01*
X637420Y52148D01*
Y53758D01*
G01Y56053D02*
X634320D01*
X634940Y55593D01*
G01X637420D02*
Y56513D01*
G01Y59613D02*
X634320D01*
X636542Y58195D01*
Y60111D01*
G01X633230Y45986D02*
X630130D01*
Y46945D01*
X630285Y47251D01*
X630492Y47443D01*
X630905Y47520D01*
X631318Y47443D01*
X631577Y47213D01*
X631732Y46945D01*
Y45986D01*
G01Y46945D02*
X633230Y47520D01*
G01Y49853D02*
X630130D01*
X630750Y49393D01*
G01X633230D02*
Y50313D01*
G01Y52953D02*
X630130D01*
X630750Y52493D01*
G01X633230D02*
Y53413D01*
G01X632868Y55401D02*
X633127Y55670D01*
X633230Y55976D01*
X633127Y56283D01*
X632817Y56551D01*
X632352Y56743D01*
X631887Y56820D01*
X631318D01*
X630853Y56743D01*
X630440Y56551D01*
X630233Y56321D01*
X630130Y56053D01*
X630233Y55746D01*
X630440Y55516D01*
X630750Y55363D01*
X631163Y55286D01*
X631525Y55363D01*
X631887Y55555D01*
X632093Y55785D01*
X632145Y56053D01*
X632042Y56360D01*
X631783Y56590D01*
X631318Y56820D01*
G01X633230Y59153D02*
X633178Y59421D01*
X633023Y59728D01*
X632765Y59920D01*
X632403Y59996D01*
X632042Y59920D01*
X631732Y59690D01*
X631577Y59345D01*
Y58961D01*
X631473Y58731D01*
X631215Y58540D01*
X630853Y58463D01*
X630492Y58578D01*
X630233Y58846D01*
X630130Y59153D01*
X630233Y59460D01*
X630492Y59728D01*
X630853Y59843D01*
X631215Y59766D01*
X631473Y59575D01*
X631577Y59345D01*
Y58961D01*
X631732Y58616D01*
X632042Y58386D01*
X632403Y58310D01*
X632765Y58386D01*
X633023Y58578D01*
X633178Y58885D01*
X633230Y59153D01*
G01X630352Y70138D02*
X630102Y69758D01*
X629935Y69315D01*
Y68808D01*
X630185Y68238D01*
X630602Y67795D01*
X631102Y67478D01*
X631935Y67225D01*
X632685Y67162D01*
X633435Y67288D01*
X633935Y67478D01*
X634435Y67858D01*
X634768Y68302D01*
X634935Y68745D01*
Y69188D01*
X634768Y69632D01*
X634518Y70012D01*
X634185Y70328D01*
G01X634935Y73845D02*
X634852Y73338D01*
X634518Y72895D01*
X634018Y72515D01*
X633435Y72262D01*
X632768Y72135D01*
X632102D01*
X631435Y72262D01*
X630852Y72515D01*
X630352Y72895D01*
X630018Y73338D01*
X629935Y73845D01*
X630018Y74352D01*
X630352Y74795D01*
X630852Y75175D01*
X631435Y75428D01*
X632102Y75555D01*
X632768D01*
X633435Y75428D01*
X634018Y75175D01*
X634518Y74795D01*
X634852Y74352D01*
X634935Y73845D01*
G01Y77298D02*
X629935D01*
X634102Y78945D01*
X629935Y80592D01*
X634935D01*
G01X633935Y82652D02*
X634518Y83032D01*
X634852Y83538D01*
X634935Y84108D01*
X634852Y84615D01*
X634435Y85122D01*
X633935Y85438D01*
X633435Y85502D01*
X632852Y85375D01*
X632435Y84932D01*
X632268Y84488D01*
Y83918D01*
G01Y84488D02*
X632018Y84868D01*
X631602Y85185D01*
X631102Y85312D01*
X630602Y85185D01*
X630185Y84868D01*
X629935Y84298D01*
X630018Y83728D01*
X630352Y83158D01*
G01X630016Y86803D02*
X636376D01*
Y65265D01*
X629148D01*
Y86803D01*
X630016D01*
G01X630617Y64057D02*
X623934D01*
Y64078D01*
X626127Y66271D01*
X626148Y66250D01*
Y61422D01*
X623913Y63657D01*
Y63994D01*
G01X626399Y74014D02*
X626709Y74206D01*
X626916Y74436D01*
X627019Y74704D01*
X626916Y75011D01*
X626709Y75241D01*
X626399Y75471D01*
X625986Y75548D01*
X623919D01*
G01X626554Y77038D02*
X626812Y77268D01*
X626967Y77536D01*
X627019Y77881D01*
X626916Y78226D01*
X626709Y78494D01*
X626347Y78686D01*
X625934Y78724D01*
X625521Y78648D01*
X625262Y78456D01*
X625056Y78188D01*
X625004Y77919D01*
X625056Y77651D01*
X625262Y77306D01*
X623919Y77421D01*
Y78456D01*
G01X622350Y61293D02*
Y100663D01*
G01X628690Y103358D02*
X628535Y103128D01*
X628432Y102860D01*
Y102553D01*
X628587Y102208D01*
X628845Y101940D01*
X629155Y101748D01*
X629672Y101595D01*
X630137Y101557D01*
X630602Y101633D01*
X630912Y101748D01*
X631222Y101978D01*
X631429Y102247D01*
X631532Y102515D01*
Y102783D01*
X631429Y103052D01*
X631274Y103282D01*
X631067Y103473D01*
G01Y104772D02*
X631325Y105002D01*
X631480Y105270D01*
X631532Y105615D01*
X631429Y105960D01*
X631222Y106228D01*
X630860Y106420D01*
X630447Y106458D01*
X630034Y106382D01*
X629775Y106190D01*
X629569Y105922D01*
X629517Y105653D01*
X629569Y105385D01*
X629775Y105040D01*
X628432Y105155D01*
Y106190D01*
G01X630912Y107872D02*
X631274Y108102D01*
X631480Y108408D01*
X631532Y108753D01*
X631480Y109060D01*
X631222Y109367D01*
X630912Y109558D01*
X630602Y109597D01*
X630240Y109520D01*
X629982Y109252D01*
X629879Y108983D01*
Y108638D01*
G01Y108983D02*
X629724Y109213D01*
X629465Y109405D01*
X629155Y109482D01*
X628845Y109405D01*
X628587Y109213D01*
X628432Y108868D01*
X628484Y108523D01*
X628690Y108178D01*
G01X631532Y112275D02*
X628432D01*
X630654Y110857D01*
Y112773D01*
G01X632771Y103358D02*
X632616Y103128D01*
X632513Y102860D01*
Y102553D01*
X632668Y102208D01*
X632926Y101940D01*
X633236Y101748D01*
X633753Y101595D01*
X634218Y101557D01*
X634683Y101633D01*
X634993Y101748D01*
X635303Y101978D01*
X635510Y102247D01*
X635613Y102515D01*
Y102783D01*
X635510Y103052D01*
X635355Y103282D01*
X635148Y103473D01*
G01Y104772D02*
X635406Y105002D01*
X635561Y105270D01*
X635613Y105615D01*
X635510Y105960D01*
X635303Y106228D01*
X634941Y106420D01*
X634528Y106458D01*
X634115Y106382D01*
X633856Y106190D01*
X633650Y105922D01*
X633598Y105653D01*
X633650Y105385D01*
X633856Y105040D01*
X632513Y105155D01*
Y106190D01*
G01X634993Y107872D02*
X635355Y108102D01*
X635561Y108408D01*
X635613Y108753D01*
X635561Y109060D01*
X635303Y109367D01*
X634993Y109558D01*
X634683Y109597D01*
X634321Y109520D01*
X634063Y109252D01*
X633960Y108983D01*
Y108638D01*
G01Y108983D02*
X633805Y109213D01*
X633546Y109405D01*
X633236Y109482D01*
X632926Y109405D01*
X632668Y109213D01*
X632513Y108868D01*
X632565Y108523D01*
X632771Y108178D01*
G01X633030Y111087D02*
X632720Y111317D01*
X632565Y111585D01*
X632513Y111892D01*
X632616Y112275D01*
X632875Y112543D01*
X633185Y112620D01*
X633495Y112582D01*
X633753Y112428D01*
X634270Y111662D01*
X634631Y111317D01*
X635148Y111087D01*
X635613Y111010D01*
Y112620D01*
G01X623298Y106304D02*
Y103104D01*
G01X624599Y103358D02*
X624444Y103128D01*
X624341Y102860D01*
Y102553D01*
X624496Y102208D01*
X624754Y101940D01*
X625064Y101748D01*
X625581Y101595D01*
X626046Y101557D01*
X626511Y101633D01*
X626821Y101748D01*
X627131Y101978D01*
X627338Y102247D01*
X627441Y102515D01*
Y102783D01*
X627338Y103052D01*
X627183Y103282D01*
X626976Y103473D01*
G01Y104772D02*
X627234Y105002D01*
X627389Y105270D01*
X627441Y105615D01*
X627338Y105960D01*
X627131Y106228D01*
X626769Y106420D01*
X626356Y106458D01*
X625943Y106382D01*
X625684Y106190D01*
X625478Y105922D01*
X625426Y105653D01*
X625478Y105385D01*
X625684Y105040D01*
X624341Y105155D01*
Y106190D01*
G01X626821Y107872D02*
X627183Y108102D01*
X627389Y108408D01*
X627441Y108753D01*
X627389Y109060D01*
X627131Y109367D01*
X626821Y109558D01*
X626511Y109597D01*
X626149Y109520D01*
X625891Y109252D01*
X625788Y108983D01*
Y108638D01*
G01Y108983D02*
X625633Y109213D01*
X625374Y109405D01*
X625064Y109482D01*
X624754Y109405D01*
X624496Y109213D01*
X624341Y108868D01*
X624393Y108523D01*
X624599Y108178D01*
G01X626821Y110972D02*
X627183Y111202D01*
X627389Y111508D01*
X627441Y111853D01*
X627389Y112160D01*
X627131Y112467D01*
X626821Y112658D01*
X626511Y112697D01*
X626149Y112620D01*
X625891Y112352D01*
X625788Y112083D01*
Y111738D01*
G01Y112083D02*
X625633Y112313D01*
X625374Y112505D01*
X625064Y112582D01*
X624754Y112505D01*
X624496Y112313D01*
X624341Y111968D01*
X624393Y111623D01*
X624599Y111278D01*
G01X631541Y118284D02*
X633763D01*
X634228Y118437D01*
X634538Y118744D01*
X634641Y119127D01*
X634538Y119510D01*
X634228Y119817D01*
X633763Y119970D01*
X631541D01*
G01X634176Y121384D02*
X634434Y121614D01*
X634589Y121882D01*
X634641Y122227D01*
X634538Y122572D01*
X634331Y122840D01*
X633969Y123032D01*
X633556Y123070D01*
X633143Y122994D01*
X632884Y122802D01*
X632678Y122534D01*
X632626Y122265D01*
X632678Y121997D01*
X632884Y121652D01*
X631541Y121767D01*
Y122802D01*
G01X634641Y125327D02*
X631541D01*
X632161Y124867D01*
G01X634641D02*
Y125787D01*
G01X629744Y134824D02*
Y137924D01*
X630703D01*
X631009Y137769D01*
X631201Y137562D01*
X631278Y137149D01*
X631201Y136736D01*
X630971Y136477D01*
X630703Y136322D01*
X629744D01*
G01X630703D02*
X631278Y134824D01*
G01X632883Y136116D02*
X633151Y136477D01*
X633381Y136684D01*
X633688Y136787D01*
X633956Y136684D01*
X634148Y136477D01*
X634301Y136167D01*
X634339Y135806D01*
X634301Y135496D01*
X634148Y135186D01*
X633918Y134927D01*
X633649Y134824D01*
X633343Y134927D01*
X633074Y135237D01*
X632921Y135702D01*
X632883Y136219D01*
X632959Y136891D01*
X633074Y137252D01*
X633266Y137614D01*
X633534Y137872D01*
X633803Y137924D01*
X634071Y137821D01*
X634263Y137562D01*
G01X635868Y135289D02*
X636098Y135031D01*
X636366Y134876D01*
X636711Y134824D01*
X637056Y134927D01*
X637324Y135134D01*
X637516Y135496D01*
X637554Y135909D01*
X637478Y136322D01*
X637286Y136581D01*
X637018Y136787D01*
X636749Y136839D01*
X636481Y136787D01*
X636136Y136581D01*
X636251Y137924D01*
X637286D01*
G01X639083Y136116D02*
X639351Y136477D01*
X639581Y136684D01*
X639888Y136787D01*
X640156Y136684D01*
X640348Y136477D01*
X640501Y136167D01*
X640539Y135806D01*
X640501Y135496D01*
X640348Y135186D01*
X640118Y134927D01*
X639849Y134824D01*
X639543Y134927D01*
X639274Y135237D01*
X639121Y135702D01*
X639083Y136219D01*
X639159Y136891D01*
X639274Y137252D01*
X639466Y137614D01*
X639734Y137872D01*
X640003Y137924D01*
X640271Y137821D01*
X640463Y137562D01*
G01X631549Y133841D02*
X637749D01*
G01Y130641D02*
X631549D01*
G01D02*
Y133841D01*
G01X632445Y151138D02*
X629345D01*
Y152097D01*
X629500Y152403D01*
X629707Y152595D01*
X630120Y152672D01*
X630533Y152595D01*
X630792Y152365D01*
X630947Y152097D01*
Y151138D01*
G01Y152097D02*
X632445Y152672D01*
G01Y155005D02*
X629345D01*
X629965Y154545D01*
G01X632445D02*
Y155465D01*
G01X629345Y158105D02*
X629448Y157798D01*
X629707Y157568D01*
X630017Y157415D01*
X630430Y157300D01*
X630895Y157262D01*
X631360Y157300D01*
X631773Y157415D01*
X632083Y157568D01*
X632342Y157798D01*
X632445Y158105D01*
X632342Y158412D01*
X632083Y158642D01*
X631773Y158795D01*
X631360Y158910D01*
X630895Y158948D01*
X630430Y158910D01*
X630017Y158795D01*
X629707Y158642D01*
X629448Y158412D01*
X629345Y158105D01*
G01Y161205D02*
X629448Y160898D01*
X629707Y160668D01*
X630017Y160515D01*
X630430Y160400D01*
X630895Y160362D01*
X631360Y160400D01*
X631773Y160515D01*
X632083Y160668D01*
X632342Y160898D01*
X632445Y161205D01*
X632342Y161512D01*
X632083Y161742D01*
X631773Y161895D01*
X631360Y162010D01*
X630895Y162048D01*
X630430Y162010D01*
X630017Y161895D01*
X629707Y161742D01*
X629448Y161512D01*
X629345Y161205D01*
G01X631980Y163462D02*
X632238Y163692D01*
X632393Y163960D01*
X632445Y164305D01*
X632342Y164650D01*
X632135Y164918D01*
X631773Y165110D01*
X631360Y165148D01*
X630947Y165072D01*
X630688Y164880D01*
X630482Y164612D01*
X630430Y164343D01*
X630482Y164075D01*
X630688Y163730D01*
X629345Y163845D01*
Y164880D01*
G01X628445Y151138D02*
X625345D01*
Y152097D01*
X625500Y152403D01*
X625707Y152595D01*
X626120Y152672D01*
X626533Y152595D01*
X626792Y152365D01*
X626947Y152097D01*
Y151138D01*
G01Y152097D02*
X628445Y152672D01*
G01Y155005D02*
X625345D01*
X625965Y154545D01*
G01X628445D02*
Y155465D01*
G01X625345Y158105D02*
X625448Y157798D01*
X625707Y157568D01*
X626017Y157415D01*
X626430Y157300D01*
X626895Y157262D01*
X627360Y157300D01*
X627773Y157415D01*
X628083Y157568D01*
X628342Y157798D01*
X628445Y158105D01*
X628342Y158412D01*
X628083Y158642D01*
X627773Y158795D01*
X627360Y158910D01*
X626895Y158948D01*
X626430Y158910D01*
X626017Y158795D01*
X625707Y158642D01*
X625448Y158412D01*
X625345Y158105D01*
G01Y161205D02*
X625448Y160898D01*
X625707Y160668D01*
X626017Y160515D01*
X626430Y160400D01*
X626895Y160362D01*
X627360Y160400D01*
X627773Y160515D01*
X628083Y160668D01*
X628342Y160898D01*
X628445Y161205D01*
X628342Y161512D01*
X628083Y161742D01*
X627773Y161895D01*
X627360Y162010D01*
X626895Y162048D01*
X626430Y162010D01*
X626017Y161895D01*
X625707Y161742D01*
X625448Y161512D01*
X625345Y161205D01*
G01X628445Y164305D02*
X628393Y164573D01*
X628238Y164880D01*
X627980Y165072D01*
X627618Y165148D01*
X627257Y165072D01*
X626947Y164842D01*
X626792Y164497D01*
Y164113D01*
X626688Y163883D01*
X626430Y163692D01*
X626068Y163615D01*
X625707Y163730D01*
X625448Y163998D01*
X625345Y164305D01*
X625448Y164612D01*
X625707Y164880D01*
X626068Y164995D01*
X626430Y164918D01*
X626688Y164727D01*
X626792Y164497D01*
Y164113D01*
X626947Y163768D01*
X627257Y163538D01*
X627618Y163462D01*
X627980Y163538D01*
X628238Y163730D01*
X628393Y164037D01*
X628445Y164305D01*
G01X632558Y166668D02*
X629458D01*
Y167627D01*
X629613Y167933D01*
X629820Y168125D01*
X630233Y168202D01*
X630646Y168125D01*
X630905Y167895D01*
X631060Y167627D01*
Y166668D01*
G01Y167627D02*
X632558Y168202D01*
G01Y170535D02*
X629458D01*
X630078Y170075D01*
G01X632558D02*
Y170995D01*
G01X629458Y173635D02*
X629561Y173328D01*
X629820Y173098D01*
X630130Y172945D01*
X630543Y172830D01*
X631008Y172792D01*
X631473Y172830D01*
X631886Y172945D01*
X632196Y173098D01*
X632455Y173328D01*
X632558Y173635D01*
X632455Y173942D01*
X632196Y174172D01*
X631886Y174325D01*
X631473Y174440D01*
X631008Y174478D01*
X630543Y174440D01*
X630130Y174325D01*
X629820Y174172D01*
X629561Y173942D01*
X629458Y173635D01*
G01X632558Y176735D02*
X629458D01*
X630078Y176275D01*
G01X632558D02*
Y177195D01*
G01Y179835D02*
X629458D01*
X630078Y179375D01*
G01X632558D02*
Y180295D01*
G01X628156Y166631D02*
X625056D01*
Y167590D01*
X625211Y167896D01*
X625418Y168088D01*
X625831Y168165D01*
X626244Y168088D01*
X626503Y167858D01*
X626658Y167590D01*
Y166631D01*
G01Y167590D02*
X628156Y168165D01*
G01Y170498D02*
X625056D01*
X625676Y170038D01*
G01X628156D02*
Y170958D01*
G01X625056Y173598D02*
X625159Y173291D01*
X625418Y173061D01*
X625728Y172908D01*
X626141Y172793D01*
X626606Y172755D01*
X627071Y172793D01*
X627484Y172908D01*
X627794Y173061D01*
X628053Y173291D01*
X628156Y173598D01*
X628053Y173905D01*
X627794Y174135D01*
X627484Y174288D01*
X627071Y174403D01*
X626606Y174441D01*
X626141Y174403D01*
X625728Y174288D01*
X625418Y174135D01*
X625159Y173905D01*
X625056Y173598D01*
G01X628156Y176698D02*
X625056D01*
X625676Y176238D01*
G01X628156D02*
Y177158D01*
G01X627536Y178955D02*
X627898Y179185D01*
X628104Y179491D01*
X628156Y179836D01*
X628104Y180143D01*
X627846Y180450D01*
X627536Y180641D01*
X627226Y180680D01*
X626864Y180603D01*
X626606Y180335D01*
X626503Y180066D01*
Y179721D01*
G01Y180066D02*
X626348Y180296D01*
X626089Y180488D01*
X625779Y180565D01*
X625469Y180488D01*
X625211Y180296D01*
X625056Y179951D01*
X625108Y179606D01*
X625314Y179261D01*
G01X638207Y192991D02*
X631524D01*
Y193012D01*
X633717Y195205D01*
X633738Y195184D01*
Y190356D01*
X631503Y192591D01*
Y192928D01*
G01X621757Y206251D02*
X621810Y206793D01*
X621890Y207251D01*
X621997Y207668D01*
X622130Y208126D01*
X622343Y208751D01*
X621277D01*
G01X624450Y232560D02*
Y265510D01*
G01X622870Y264090D02*
X624370Y265590D01*
G01X622870Y263870D02*
Y264090D01*
G01X625810Y263870D02*
X622870D01*
G01X625910Y263970D02*
X625810Y263870D01*
G01X625910Y264050D02*
Y263970D01*
G01X624450Y265510D02*
X625910Y264050D01*
G01X631100Y267183D02*
X628000D01*
Y268142D01*
X628155Y268448D01*
X628362Y268640D01*
X628775Y268717D01*
X629188Y268640D01*
X629447Y268410D01*
X629602Y268142D01*
Y267183D01*
G01Y268142D02*
X631100Y268717D01*
G01Y271050D02*
X628000D01*
X628620Y270590D01*
G01X631100D02*
Y271510D01*
G01Y274150D02*
X628000D01*
X628620Y273690D01*
G01X631100D02*
Y274610D01*
G01X629808Y276522D02*
X629447Y276790D01*
X629240Y277020D01*
X629137Y277327D01*
X629240Y277595D01*
X629447Y277787D01*
X629757Y277940D01*
X630118Y277978D01*
X630428Y277940D01*
X630738Y277787D01*
X630997Y277557D01*
X631100Y277288D01*
X630997Y276982D01*
X630687Y276713D01*
X630222Y276560D01*
X629705Y276522D01*
X629033Y276598D01*
X628672Y276713D01*
X628310Y276905D01*
X628052Y277173D01*
X628000Y277442D01*
X628103Y277710D01*
X628362Y277902D01*
G01X631100Y280350D02*
X628000D01*
X628620Y279890D01*
G01X631100D02*
Y280810D01*
G01X638800Y267183D02*
X635700D01*
Y268142D01*
X635855Y268448D01*
X636062Y268640D01*
X636475Y268717D01*
X636888Y268640D01*
X637147Y268410D01*
X637302Y268142D01*
Y267183D01*
G01Y268142D02*
X638800Y268717D01*
G01Y271050D02*
X635700D01*
X636320Y270590D01*
G01X638800D02*
Y271510D01*
G01Y274150D02*
X635700D01*
X636320Y273690D01*
G01X638800D02*
Y274610D01*
G01X637508Y276522D02*
X637147Y276790D01*
X636940Y277020D01*
X636837Y277327D01*
X636940Y277595D01*
X637147Y277787D01*
X637457Y277940D01*
X637818Y277978D01*
X638128Y277940D01*
X638438Y277787D01*
X638697Y277557D01*
X638800Y277288D01*
X638697Y276982D01*
X638387Y276713D01*
X637922Y276560D01*
X637405Y276522D01*
X636733Y276598D01*
X636372Y276713D01*
X636010Y276905D01*
X635752Y277173D01*
X635700Y277442D01*
X635803Y277710D01*
X636062Y277902D01*
G01X638800Y280810D02*
X635700D01*
X637922Y279392D01*
Y281308D01*
G01X627200Y266983D02*
X624100D01*
Y267942D01*
X624255Y268248D01*
X624462Y268440D01*
X624875Y268517D01*
X625288Y268440D01*
X625547Y268210D01*
X625702Y267942D01*
Y266983D01*
G01Y267942D02*
X627200Y268517D01*
G01X625908Y270122D02*
X625547Y270390D01*
X625340Y270620D01*
X625237Y270927D01*
X625340Y271195D01*
X625547Y271387D01*
X625857Y271540D01*
X626218Y271578D01*
X626528Y271540D01*
X626838Y271387D01*
X627097Y271157D01*
X627200Y270888D01*
X627097Y270582D01*
X626787Y270313D01*
X626322Y270160D01*
X625805Y270122D01*
X625133Y270198D01*
X624772Y270313D01*
X624410Y270505D01*
X624152Y270773D01*
X624100Y271042D01*
X624203Y271310D01*
X624462Y271502D01*
G01X627200Y273950D02*
X624100D01*
X624720Y273490D01*
G01X627200D02*
Y274410D01*
G01X625908Y276322D02*
X625547Y276590D01*
X625340Y276820D01*
X625237Y277127D01*
X625340Y277395D01*
X625547Y277587D01*
X625857Y277740D01*
X626218Y277778D01*
X626528Y277740D01*
X626838Y277587D01*
X627097Y277357D01*
X627200Y277088D01*
X627097Y276782D01*
X626787Y276513D01*
X626322Y276360D01*
X625805Y276322D01*
X625133Y276398D01*
X624772Y276513D01*
X624410Y276705D01*
X624152Y276973D01*
X624100Y277242D01*
X624203Y277510D01*
X624462Y277702D01*
G01X634900Y267183D02*
X631800D01*
Y268142D01*
X631955Y268448D01*
X632162Y268640D01*
X632575Y268717D01*
X632988Y268640D01*
X633247Y268410D01*
X633402Y268142D01*
Y267183D01*
G01Y268142D02*
X634900Y268717D01*
G01Y271050D02*
X631800D01*
X632420Y270590D01*
G01X634900D02*
Y271510D01*
G01X634280Y273307D02*
X634642Y273537D01*
X634848Y273843D01*
X634900Y274188D01*
X634848Y274495D01*
X634590Y274802D01*
X634280Y274993D01*
X633970Y275032D01*
X633608Y274955D01*
X633350Y274687D01*
X633247Y274418D01*
Y274073D01*
G01Y274418D02*
X633092Y274648D01*
X632833Y274840D01*
X632523Y274917D01*
X632213Y274840D01*
X631955Y274648D01*
X631800Y274303D01*
X631852Y273958D01*
X632058Y273613D01*
G01X632317Y276522D02*
X632007Y276752D01*
X631852Y277020D01*
X631800Y277327D01*
X631903Y277710D01*
X632162Y277978D01*
X632472Y278055D01*
X632782Y278017D01*
X633040Y277863D01*
X633557Y277097D01*
X633918Y276752D01*
X634435Y276522D01*
X634900Y276445D01*
Y278055D01*
G01X634280Y279507D02*
X634642Y279737D01*
X634848Y280043D01*
X634900Y280388D01*
X634848Y280695D01*
X634590Y281002D01*
X634280Y281193D01*
X633970Y281232D01*
X633608Y281155D01*
X633350Y280887D01*
X633247Y280618D01*
Y280273D01*
G01Y280618D02*
X633092Y280848D01*
X632833Y281040D01*
X632523Y281117D01*
X632213Y281040D01*
X631955Y280848D01*
X631800Y280503D01*
X631852Y280158D01*
X632058Y279813D01*
G01Y285411D02*
X622496D01*
Y285379D01*
G01X635768Y287589D02*
Y290589D01*
G01X632668Y287489D02*
Y290689D01*
G01X638868Y287489D02*
X632668D01*
G01Y290689D02*
X638868D01*
G01X628552Y291091D02*
Y294091D01*
G01X625452Y290991D02*
Y294191D01*
G01X631652Y290991D02*
X625452D01*
G01X631652Y294191D02*
Y290991D01*
G01X625452Y294191D02*
X631652D01*
G01X632687Y283442D02*
Y286642D01*
G01X638887Y283442D02*
X632687D01*
G01Y286642D02*
X638887D01*
G01X631653Y298125D02*
Y294925D01*
G01X625453D02*
Y298125D01*
G01X631653Y294925D02*
X625453D01*
G01X625452Y286869D02*
Y290069D01*
G01X631652Y286869D02*
X625452D01*
G01X631652Y290069D02*
Y286869D01*
G01X625452Y290069D02*
X631652D01*
G01X634113Y296775D02*
X634273Y296567D01*
X634460Y296442D01*
X634700Y296400D01*
X634940Y296483D01*
X635127Y296650D01*
X635260Y296942D01*
X635287Y297275D01*
X635233Y297608D01*
X635100Y297817D01*
X634913Y297983D01*
X634727Y298025D01*
X634540Y297983D01*
X634300Y297817D01*
X634380Y298900D01*
X635100D01*
G01X628969Y305230D02*
Y299030D01*
G01X625769Y305230D02*
X628969D01*
G01X625769Y299030D02*
Y305230D01*
G01X628869Y302130D02*
X625869D01*
G01X628969Y299030D02*
X625769D01*
G01X625453Y298125D02*
X631653D01*
G01X626483Y312254D02*
X628705D01*
X629170Y312407D01*
X629480Y312714D01*
X629583Y313097D01*
X629480Y313480D01*
X629170Y313787D01*
X628705Y313940D01*
X626483D01*
G01X629583Y316197D02*
X626483D01*
X627103Y315737D01*
G01X629583D02*
Y316657D01*
G01X628963Y318454D02*
X629325Y318684D01*
X629531Y318990D01*
X629583Y319335D01*
X629531Y319642D01*
X629273Y319949D01*
X628963Y320140D01*
X628653Y320179D01*
X628291Y320102D01*
X628033Y319834D01*
X627930Y319565D01*
Y319220D01*
G01Y319565D02*
X627775Y319795D01*
X627516Y319987D01*
X627206Y320064D01*
X626896Y319987D01*
X626638Y319795D01*
X626483Y319450D01*
X626535Y319105D01*
X626741Y318760D01*
G01X626483Y322397D02*
X626586Y322090D01*
X626845Y321860D01*
X627155Y321707D01*
X627568Y321592D01*
X628033Y321554D01*
X628498Y321592D01*
X628911Y321707D01*
X629221Y321860D01*
X629480Y322090D01*
X629583Y322397D01*
X629480Y322704D01*
X629221Y322934D01*
X628911Y323087D01*
X628498Y323202D01*
X628033Y323240D01*
X627568Y323202D01*
X627155Y323087D01*
X626845Y322934D01*
X626586Y322704D01*
X626483Y322397D01*
G01X630291Y310060D02*
Y312560D01*
X629971Y312060D01*
G01Y310060D02*
X630611D01*
G01X648456Y310584D02*
X636448D01*
G01X648456Y298576D02*
X636448D01*
G01X639052Y310584D02*
X636448D01*
G01D02*
Y309780D01*
G01Y298576D02*
X638952D01*
G01X636448Y299380D02*
Y298576D01*
G01X634842Y320760D02*
X649842D01*
G01Y313960D02*
X634842D01*
G01D02*
Y320760D01*
G01X649832Y321598D02*
X634832D01*
G01Y328398D02*
X649832D01*
G01X634832Y321598D02*
Y328398D01*
G01X629640Y357218D02*
Y337418D01*
G01X621592Y361727D02*
Y359505D01*
X621745Y359040D01*
X622052Y358730D01*
X622435Y358627D01*
X622818Y358730D01*
X623125Y359040D01*
X623278Y359505D01*
Y361727D01*
G01X624692Y359247D02*
X624922Y358885D01*
X625228Y358679D01*
X625573Y358627D01*
X625880Y358679D01*
X626187Y358937D01*
X626378Y359247D01*
X626417Y359557D01*
X626340Y359919D01*
X626072Y360177D01*
X625803Y360280D01*
X625458D01*
G01X625803D02*
X626033Y360435D01*
X626225Y360694D01*
X626302Y361004D01*
X626225Y361314D01*
X626033Y361572D01*
X625688Y361727D01*
X625343Y361675D01*
X624998Y361469D01*
G01X627792Y359247D02*
X628022Y358885D01*
X628328Y358679D01*
X628673Y358627D01*
X628980Y358679D01*
X629287Y358937D01*
X629478Y359247D01*
X629517Y359557D01*
X629440Y359919D01*
X629172Y360177D01*
X628903Y360280D01*
X628558D01*
G01X628903D02*
X629133Y360435D01*
X629325Y360694D01*
X629402Y361004D01*
X629325Y361314D01*
X629133Y361572D01*
X628788Y361727D01*
X628443Y361675D01*
X628098Y361469D01*
G01X624040Y355418D02*
X625840Y357218D01*
G01X622240D02*
X624040Y355418D01*
G01X625840Y357218D02*
X629640D01*
G01X638001Y365013D02*
X634901D01*
Y365972D01*
X635056Y366278D01*
X635263Y366470D01*
X635676Y366547D01*
X636089Y366470D01*
X636348Y366240D01*
X636503Y365972D01*
Y365013D01*
G01Y365972D02*
X638001Y366547D01*
G01X637536Y368037D02*
X637794Y368267D01*
X637949Y368535D01*
X638001Y368880D01*
X637898Y369225D01*
X637691Y369493D01*
X637329Y369685D01*
X636916Y369723D01*
X636503Y369647D01*
X636244Y369455D01*
X636038Y369187D01*
X635986Y368918D01*
X636038Y368650D01*
X636244Y368305D01*
X634901Y368420D01*
Y369455D01*
G01X637381Y371137D02*
X637743Y371367D01*
X637949Y371673D01*
X638001Y372018D01*
X637949Y372325D01*
X637691Y372632D01*
X637381Y372823D01*
X637071Y372862D01*
X636709Y372785D01*
X636451Y372517D01*
X636348Y372248D01*
Y371903D01*
G01Y372248D02*
X636193Y372478D01*
X635934Y372670D01*
X635624Y372747D01*
X635314Y372670D01*
X635056Y372478D01*
X634901Y372133D01*
X634953Y371788D01*
X635159Y371443D01*
G01X635418Y374352D02*
X635108Y374582D01*
X634953Y374850D01*
X634901Y375157D01*
X635004Y375540D01*
X635263Y375808D01*
X635573Y375885D01*
X635883Y375847D01*
X636141Y375693D01*
X636658Y374927D01*
X637019Y374582D01*
X637536Y374352D01*
X638001Y374275D01*
Y375885D01*
G01X630003Y365035D02*
X626903D01*
Y365994D01*
X627058Y366300D01*
X627265Y366492D01*
X627678Y366569D01*
X628091Y366492D01*
X628350Y366262D01*
X628505Y365994D01*
Y365035D01*
G01Y365994D02*
X630003Y366569D01*
G01X629538Y368059D02*
X629796Y368289D01*
X629951Y368557D01*
X630003Y368902D01*
X629900Y369247D01*
X629693Y369515D01*
X629331Y369707D01*
X628918Y369745D01*
X628505Y369669D01*
X628246Y369477D01*
X628040Y369209D01*
X627988Y368940D01*
X628040Y368672D01*
X628246Y368327D01*
X626903Y368442D01*
Y369477D01*
G01X627420Y371274D02*
X627110Y371504D01*
X626955Y371772D01*
X626903Y372079D01*
X627006Y372462D01*
X627265Y372730D01*
X627575Y372807D01*
X627885Y372769D01*
X628143Y372615D01*
X628660Y371849D01*
X629021Y371504D01*
X629538Y371274D01*
X630003Y371197D01*
Y372807D01*
G01X627420Y374374D02*
X627110Y374604D01*
X626955Y374872D01*
X626903Y375179D01*
X627006Y375562D01*
X627265Y375830D01*
X627575Y375907D01*
X627885Y375869D01*
X628143Y375715D01*
X628660Y374949D01*
X629021Y374604D01*
X629538Y374374D01*
X630003Y374297D01*
Y375907D01*
G01X626003Y365035D02*
X622903D01*
Y365994D01*
X623058Y366300D01*
X623265Y366492D01*
X623678Y366569D01*
X624091Y366492D01*
X624350Y366262D01*
X624505Y365994D01*
Y365035D01*
G01Y365994D02*
X626003Y366569D01*
G01X625538Y368059D02*
X625796Y368289D01*
X625951Y368557D01*
X626003Y368902D01*
X625900Y369247D01*
X625693Y369515D01*
X625331Y369707D01*
X624918Y369745D01*
X624505Y369669D01*
X624246Y369477D01*
X624040Y369209D01*
X623988Y368940D01*
X624040Y368672D01*
X624246Y368327D01*
X622903Y368442D01*
Y369477D01*
G01X623420Y371274D02*
X623110Y371504D01*
X622955Y371772D01*
X622903Y372079D01*
X623006Y372462D01*
X623265Y372730D01*
X623575Y372807D01*
X623885Y372769D01*
X624143Y372615D01*
X624660Y371849D01*
X625021Y371504D01*
X625538Y371274D01*
X626003Y371197D01*
Y372807D01*
G01X625383Y374259D02*
X625745Y374489D01*
X625951Y374795D01*
X626003Y375140D01*
X625951Y375447D01*
X625693Y375754D01*
X625383Y375945D01*
X625073Y375984D01*
X624711Y375907D01*
X624453Y375639D01*
X624350Y375370D01*
Y375025D01*
G01Y375370D02*
X624195Y375600D01*
X623936Y375792D01*
X623626Y375869D01*
X623316Y375792D01*
X623058Y375600D01*
X622903Y375255D01*
X622955Y374910D01*
X623161Y374565D01*
G01X634001Y365013D02*
X630901D01*
Y365972D01*
X631056Y366278D01*
X631263Y366470D01*
X631676Y366547D01*
X632089Y366470D01*
X632348Y366240D01*
X632503Y365972D01*
Y365013D01*
G01Y365972D02*
X634001Y366547D01*
G01X633536Y368037D02*
X633794Y368267D01*
X633949Y368535D01*
X634001Y368880D01*
X633898Y369225D01*
X633691Y369493D01*
X633329Y369685D01*
X632916Y369723D01*
X632503Y369647D01*
X632244Y369455D01*
X632038Y369187D01*
X631986Y368918D01*
X632038Y368650D01*
X632244Y368305D01*
X630901Y368420D01*
Y369455D01*
G01X631418Y371252D02*
X631108Y371482D01*
X630953Y371750D01*
X630901Y372057D01*
X631004Y372440D01*
X631263Y372708D01*
X631573Y372785D01*
X631883Y372747D01*
X632141Y372593D01*
X632658Y371827D01*
X633019Y371482D01*
X633536Y371252D01*
X634001Y371175D01*
Y372785D01*
G01Y375540D02*
X630901D01*
X633123Y374122D01*
Y376038D01*
G01X626853Y385578D02*
Y388778D01*
G01X633053Y385578D02*
X626853D01*
G01Y388778D02*
X633053D01*
G01D02*
Y385578D01*
G01X634530Y384732D02*
Y381532D01*
G01X628330Y384732D02*
X634530D01*
G01Y381532D02*
X628330D01*
G01D02*
Y384732D01*
G01X636488Y395785D02*
X639988D01*
G01X623520Y403652D02*
Y400452D01*
G01Y399652D02*
Y396452D01*
G01X623131Y421362D02*
Y424462D01*
X624090D01*
X624396Y424307D01*
X624588Y424100D01*
X624665Y423687D01*
X624588Y423274D01*
X624358Y423015D01*
X624090Y422860D01*
X623131D01*
G01X624090D02*
X624665Y421362D01*
G01X626155Y421827D02*
X626385Y421569D01*
X626653Y421414D01*
X626998Y421362D01*
X627343Y421465D01*
X627611Y421672D01*
X627803Y422034D01*
X627841Y422447D01*
X627765Y422860D01*
X627573Y423119D01*
X627305Y423325D01*
X627036Y423377D01*
X626768Y423325D01*
X626423Y423119D01*
X626538Y424462D01*
X627573D01*
G01X629370Y423945D02*
X629600Y424255D01*
X629868Y424410D01*
X630175Y424462D01*
X630558Y424359D01*
X630826Y424100D01*
X630903Y423790D01*
X630865Y423480D01*
X630711Y423222D01*
X629945Y422705D01*
X629600Y422344D01*
X629370Y421827D01*
X629293Y421362D01*
X630903D01*
G01X632355Y421827D02*
X632585Y421569D01*
X632853Y421414D01*
X633198Y421362D01*
X633543Y421465D01*
X633811Y421672D01*
X634003Y422034D01*
X634041Y422447D01*
X633965Y422860D01*
X633773Y423119D01*
X633505Y423325D01*
X633236Y423377D01*
X632968Y423325D01*
X632623Y423119D01*
X632738Y424462D01*
X633773D01*
G01X625033Y417174D02*
Y420374D01*
G01X631233Y417174D02*
X625033D01*
G01Y420374D02*
X631233D01*
G01D02*
Y417174D01*
G01X622656Y452567D02*
Y455667D01*
X623615D01*
X623921Y455512D01*
X624113Y455305D01*
X624190Y454892D01*
X624113Y454479D01*
X623883Y454220D01*
X623615Y454065D01*
X622656D01*
G01X623615D02*
X624190Y452567D01*
G01X626523D02*
Y455667D01*
X626063Y455047D01*
G01Y452567D02*
X626983D01*
G01X629546D02*
X629623Y453239D01*
X629738Y453807D01*
X629891Y454324D01*
X630083Y454892D01*
X630390Y455667D01*
X628856D01*
G01X631880Y453032D02*
X632110Y452774D01*
X632378Y452619D01*
X632723Y452567D01*
X633068Y452670D01*
X633336Y452877D01*
X633528Y453239D01*
X633566Y453652D01*
X633490Y454065D01*
X633298Y454324D01*
X633030Y454530D01*
X632761Y454582D01*
X632493Y454530D01*
X632148Y454324D01*
X632263Y455667D01*
X633298D01*
G01X623254Y462956D02*
Y466056D01*
X624213D01*
X624519Y465901D01*
X624711Y465694D01*
X624788Y465281D01*
X624711Y464868D01*
X624481Y464609D01*
X624213Y464454D01*
X623254D01*
G01X624213D02*
X624788Y462956D01*
G01X627121D02*
Y466056D01*
X626661Y465436D01*
G01Y462956D02*
X627581D01*
G01X629378Y463576D02*
X629608Y463214D01*
X629914Y463008D01*
X630259Y462956D01*
X630566Y463008D01*
X630873Y463266D01*
X631064Y463576D01*
X631103Y463886D01*
X631026Y464248D01*
X630758Y464506D01*
X630489Y464609D01*
X630144D01*
G01X630489D02*
X630719Y464764D01*
X630911Y465023D01*
X630988Y465333D01*
X630911Y465643D01*
X630719Y465901D01*
X630374Y466056D01*
X630029Y466004D01*
X629684Y465798D01*
G01X633781Y462956D02*
Y466056D01*
X632363Y463834D01*
X634279D01*
G01X622726Y456959D02*
Y460059D01*
X623685D01*
X623991Y459904D01*
X624183Y459697D01*
X624260Y459284D01*
X624183Y458871D01*
X623953Y458612D01*
X623685Y458457D01*
X622726D01*
G01X623685D02*
X624260Y456959D01*
G01X626593D02*
Y460059D01*
X626133Y459439D01*
G01Y456959D02*
X627053D01*
G01X629616D02*
X629693Y457631D01*
X629808Y458199D01*
X629961Y458716D01*
X630153Y459284D01*
X630460Y460059D01*
X628926D01*
G01X632065Y458251D02*
X632333Y458612D01*
X632563Y458819D01*
X632870Y458922D01*
X633138Y458819D01*
X633330Y458612D01*
X633483Y458302D01*
X633521Y457941D01*
X633483Y457631D01*
X633330Y457321D01*
X633100Y457062D01*
X632831Y456959D01*
X632525Y457062D01*
X632256Y457372D01*
X632103Y457837D01*
X632065Y458354D01*
X632141Y459026D01*
X632256Y459387D01*
X632448Y459749D01*
X632716Y460007D01*
X632985Y460059D01*
X633253Y459956D01*
X633445Y459697D01*
G01X632552Y468899D02*
Y480979D01*
G01X645026Y468899D02*
X632552D01*
G01X631416Y487299D02*
X631256Y487424D01*
X631069Y487507D01*
X630856D01*
X630616Y487382D01*
X630429Y487174D01*
X630296Y486924D01*
X630189Y486507D01*
X630162Y486132D01*
X630216Y485757D01*
X630296Y485507D01*
X630456Y485257D01*
X630642Y485090D01*
X630829Y485007D01*
X631016D01*
X631202Y485090D01*
X631362Y485215D01*
X631496Y485382D01*
G01X632587Y482230D02*
Y494310D01*
G01X645061Y482230D02*
X632587D01*
G01X624545Y478244D02*
X624238Y478296D01*
X623970Y478502D01*
X623740Y478812D01*
X623587Y479174D01*
X623510Y479587D01*
Y480001D01*
X623587Y480414D01*
X623740Y480776D01*
X623970Y481086D01*
X624238Y481292D01*
X624545Y481344D01*
X624852Y481292D01*
X625120Y481086D01*
X625350Y480776D01*
X625503Y480414D01*
X625580Y480001D01*
Y479587D01*
X625503Y479174D01*
X625350Y478812D01*
X625120Y478502D01*
X624852Y478296D01*
X624545Y478244D01*
G01X624852Y479071D02*
X625312Y478244D01*
G01X626917Y480827D02*
X627147Y481137D01*
X627415Y481292D01*
X627722Y481344D01*
X628105Y481241D01*
X628373Y480982D01*
X628450Y480672D01*
X628412Y480362D01*
X628258Y480104D01*
X627492Y479587D01*
X627147Y479226D01*
X626917Y478709D01*
X626840Y478244D01*
X628450D01*
G01X630017Y479536D02*
X630285Y479897D01*
X630515Y480104D01*
X630822Y480207D01*
X631090Y480104D01*
X631282Y479897D01*
X631435Y479587D01*
X631473Y479226D01*
X631435Y478916D01*
X631282Y478606D01*
X631052Y478347D01*
X630783Y478244D01*
X630477Y478347D01*
X630208Y478657D01*
X630055Y479122D01*
X630017Y479639D01*
X630093Y480311D01*
X630208Y480672D01*
X630400Y481034D01*
X630668Y481292D01*
X630937Y481344D01*
X631205Y481241D01*
X631397Y480982D01*
G01X631404Y476443D02*
X631244Y476568D01*
X631057Y476651D01*
X630844D01*
X630604Y476526D01*
X630417Y476318D01*
X630284Y476068D01*
X630177Y475651D01*
X630150Y475276D01*
X630204Y474901D01*
X630284Y474651D01*
X630444Y474401D01*
X630630Y474234D01*
X630817Y474151D01*
X631004D01*
X631190Y474234D01*
X631350Y474359D01*
X631484Y474526D01*
G01X632552Y480979D02*
X645026D01*
G01X621013Y496912D02*
Y498612D01*
G01X631525Y502100D02*
X631365Y502225D01*
X631178Y502308D01*
X630965D01*
X630725Y502183D01*
X630538Y501975D01*
X630405Y501725D01*
X630298Y501308D01*
X630271Y500933D01*
X630325Y500558D01*
X630405Y500308D01*
X630565Y500058D01*
X630751Y499891D01*
X630938Y499808D01*
X631125D01*
X631311Y499891D01*
X631471Y500016D01*
X631605Y500183D01*
G01X632487Y495430D02*
Y507510D01*
G01X644961Y495430D02*
X632487D01*
G01X632587Y494310D02*
X645061D01*
G01X629409Y504665D02*
Y507165D01*
X628422Y505373D01*
X629756D01*
G01X629774Y516520D02*
X629934Y516770D01*
X630121Y516895D01*
X630334Y516937D01*
X630601Y516854D01*
X630788Y516645D01*
X630841Y516395D01*
X630814Y516145D01*
X630708Y515937D01*
X630174Y515520D01*
X629934Y515229D01*
X629774Y514812D01*
X629721Y514437D01*
X630841D01*
G01X621013Y503912D02*
Y514312D01*
G01X633161Y509030D02*
Y513430D01*
G01X643561Y509030D02*
X633161D01*
G01Y513430D02*
X643561D01*
G01X633761Y515130D02*
Y518330D01*
G01X639961Y515130D02*
X633761D01*
G01X632487Y507510D02*
X644961D01*
G01X624514Y528463D02*
X624674Y528713D01*
X624861Y528838D01*
X625074Y528880D01*
X625341Y528797D01*
X625528Y528588D01*
X625581Y528338D01*
X625554Y528088D01*
X625448Y527880D01*
X624914Y527463D01*
X624674Y527172D01*
X624514Y526755D01*
X624461Y526380D01*
X625581D01*
G01X633955Y540887D02*
Y530487D01*
G01X658355Y523487D02*
X633955D01*
G01D02*
Y525187D01*
G01X621013Y521312D02*
Y519612D01*
G01X621632Y530367D02*
Y523567D01*
G01X629537Y519356D02*
Y522456D01*
X630496D01*
X630802Y522301D01*
X630994Y522094D01*
X631071Y521681D01*
X630994Y521268D01*
X630764Y521009D01*
X630496Y520854D01*
X629537D01*
G01X630496D02*
X631071Y519356D01*
G01X633404D02*
Y522456D01*
X632944Y521836D01*
G01Y519356D02*
X633864D01*
G01X636504Y522456D02*
X636197Y522353D01*
X635967Y522094D01*
X635814Y521784D01*
X635699Y521371D01*
X635661Y520906D01*
X635699Y520441D01*
X635814Y520028D01*
X635967Y519718D01*
X636197Y519459D01*
X636504Y519356D01*
X636811Y519459D01*
X637041Y519718D01*
X637194Y520028D01*
X637309Y520441D01*
X637347Y520906D01*
X637309Y521371D01*
X637194Y521784D01*
X637041Y522094D01*
X636811Y522353D01*
X636504Y522456D01*
G01X638761Y519976D02*
X638991Y519614D01*
X639297Y519408D01*
X639642Y519356D01*
X639949Y519408D01*
X640256Y519666D01*
X640447Y519976D01*
X640486Y520286D01*
X640409Y520648D01*
X640141Y520906D01*
X639872Y521009D01*
X639527D01*
G01X639872D02*
X640102Y521164D01*
X640294Y521423D01*
X640371Y521733D01*
X640294Y522043D01*
X640102Y522301D01*
X639757Y522456D01*
X639412Y522404D01*
X639067Y522198D01*
G01X641976Y521939D02*
X642206Y522249D01*
X642474Y522404D01*
X642781Y522456D01*
X643164Y522353D01*
X643432Y522094D01*
X643509Y521784D01*
X643471Y521474D01*
X643317Y521216D01*
X642551Y520699D01*
X642206Y520338D01*
X641976Y519821D01*
X641899Y519356D01*
X643509D01*
G01X633761Y518330D02*
X639961D01*
G01X622123Y544365D02*
Y532161D01*
G01X623541Y550724D02*
X621456D01*
Y549056D01*
G01X627496Y538391D02*
Y540891D01*
X626509Y539099D01*
X627843D01*
G01X658355Y547887D02*
X633955D01*
G01D02*
Y546187D01*
G01X626057Y551401D02*
X625827Y551556D01*
X625559Y551659D01*
X625252D01*
X624907Y551504D01*
X624639Y551246D01*
X624447Y550936D01*
X624294Y550419D01*
X624256Y549954D01*
X624332Y549489D01*
X624447Y549179D01*
X624677Y548869D01*
X624946Y548662D01*
X625214Y548559D01*
X625482D01*
X625751Y548662D01*
X625981Y548817D01*
X626172Y549024D01*
G01X627471D02*
X627701Y548766D01*
X627969Y548611D01*
X628314Y548559D01*
X628659Y548662D01*
X628927Y548869D01*
X629119Y549231D01*
X629157Y549644D01*
X629081Y550057D01*
X628889Y550316D01*
X628621Y550522D01*
X628352Y550574D01*
X628084Y550522D01*
X627739Y550316D01*
X627854Y551659D01*
X628889D01*
G01X630686Y549851D02*
X630954Y550212D01*
X631184Y550419D01*
X631491Y550522D01*
X631759Y550419D01*
X631951Y550212D01*
X632104Y549902D01*
X632142Y549541D01*
X632104Y549231D01*
X631951Y548921D01*
X631721Y548662D01*
X631452Y548559D01*
X631146Y548662D01*
X630877Y548972D01*
X630724Y549437D01*
X630686Y549954D01*
X630762Y550626D01*
X630877Y550987D01*
X631069Y551349D01*
X631337Y551607D01*
X631606Y551659D01*
X631874Y551556D01*
X632066Y551297D01*
G01X633671Y549024D02*
X633901Y548766D01*
X634169Y548611D01*
X634514Y548559D01*
X634859Y548662D01*
X635127Y548869D01*
X635319Y549231D01*
X635357Y549644D01*
X635281Y550057D01*
X635089Y550316D01*
X634821Y550522D01*
X634552Y550574D01*
X634284Y550522D01*
X633939Y550316D01*
X634054Y551659D01*
X635089D01*
G01X621504Y548364D02*
Y545164D01*
G01X623127Y542221D02*
X623287Y542013D01*
X623474Y541888D01*
X623714Y541846D01*
X623954Y541929D01*
X624141Y542096D01*
X624274Y542388D01*
X624301Y542721D01*
X624247Y543054D01*
X624114Y543263D01*
X623927Y543429D01*
X623741Y543471D01*
X623554Y543429D01*
X623314Y543263D01*
X623394Y544346D01*
X624114D01*
G01X623980Y535708D02*
Y538208D01*
X622993Y536416D01*
X624327D01*
G01X623537Y565845D02*
Y559645D01*
G01X651137Y552552D02*
X624737D01*
G01D02*
Y565938D01*
G01X632953Y582245D02*
Y578245D01*
G01X623110Y582245D02*
Y580245D01*
G01X627184Y575524D02*
X626954Y575679D01*
X626686Y575782D01*
X626379D01*
X626034Y575627D01*
X625766Y575369D01*
X625574Y575059D01*
X625421Y574542D01*
X625383Y574077D01*
X625459Y573612D01*
X625574Y573302D01*
X625804Y572992D01*
X626073Y572785D01*
X626341Y572682D01*
X626609D01*
X626878Y572785D01*
X627108Y572940D01*
X627299Y573147D01*
G01X629901Y572682D02*
Y575782D01*
X628483Y573560D01*
X630399D01*
G01X631698Y573302D02*
X631928Y572940D01*
X632234Y572734D01*
X632579Y572682D01*
X632886Y572734D01*
X633193Y572992D01*
X633384Y573302D01*
X633423Y573612D01*
X633346Y573974D01*
X633078Y574232D01*
X632809Y574335D01*
X632464D01*
G01X632809D02*
X633039Y574490D01*
X633231Y574749D01*
X633308Y575059D01*
X633231Y575369D01*
X633039Y575627D01*
X632694Y575782D01*
X632349Y575730D01*
X632004Y575524D01*
G01X635641Y572682D02*
X635909Y572734D01*
X636216Y572889D01*
X636408Y573147D01*
X636484Y573509D01*
X636408Y573870D01*
X636178Y574180D01*
X635833Y574335D01*
X635449D01*
X635219Y574439D01*
X635028Y574697D01*
X634951Y575059D01*
X635066Y575420D01*
X635334Y575679D01*
X635641Y575782D01*
X635948Y575679D01*
X636216Y575420D01*
X636331Y575059D01*
X636254Y574697D01*
X636063Y574439D01*
X635833Y574335D01*
X635449D01*
X635104Y574180D01*
X634874Y573870D01*
X634798Y573509D01*
X634874Y573147D01*
X635066Y572889D01*
X635373Y572734D01*
X635641Y572682D01*
G01X637037Y567145D02*
X630837D01*
G01X633937Y567245D02*
Y570245D01*
G01X630837Y570345D02*
X637037D01*
G01X630837Y567145D02*
Y570345D01*
G01X624037Y567973D02*
X620937D01*
Y568932D01*
X621092Y569238D01*
X621299Y569430D01*
X621712Y569507D01*
X622125Y569430D01*
X622384Y569200D01*
X622539Y568932D01*
Y567973D01*
G01Y568932D02*
X624037Y569507D01*
G01X623572Y570997D02*
X623830Y571227D01*
X623985Y571495D01*
X624037Y571840D01*
X623934Y572185D01*
X623727Y572453D01*
X623365Y572645D01*
X622952Y572683D01*
X622539Y572607D01*
X622280Y572415D01*
X622074Y572147D01*
X622022Y571878D01*
X622074Y571610D01*
X622280Y571265D01*
X620937Y571380D01*
Y572415D01*
G01X622745Y574212D02*
X622384Y574480D01*
X622177Y574710D01*
X622074Y575017D01*
X622177Y575285D01*
X622384Y575477D01*
X622694Y575630D01*
X623055Y575668D01*
X623365Y575630D01*
X623675Y575477D01*
X623934Y575247D01*
X624037Y574978D01*
X623934Y574672D01*
X623624Y574403D01*
X623159Y574250D01*
X622642Y574212D01*
X621970Y574288D01*
X621609Y574403D01*
X621247Y574595D01*
X620989Y574863D01*
X620937Y575132D01*
X621040Y575400D01*
X621299Y575592D01*
G01X624037Y577963D02*
X623365Y578040D01*
X622797Y578155D01*
X622280Y578308D01*
X621712Y578500D01*
X620937Y578807D01*
Y577273D01*
G01X624737Y565938D02*
X651137D01*
G01X630984Y623245D02*
Y627245D01*
G01X621142Y623245D02*
Y625245D01*
G01X636131Y662472D02*
Y642672D01*
G01D02*
X624931D01*
G01D02*
Y662472D01*
G01X620902Y637740D02*
Y631540D01*
G01X628537Y638417D02*
X631737D01*
G01D02*
Y632217D01*
G01D02*
X628537D01*
G01D02*
Y638417D01*
G01X632537Y632217D02*
Y638417D01*
G01D02*
X635737D01*
G01D02*
Y632217D01*
G01D02*
X632537D01*
G01X628031Y660072D02*
G02I-1000J0D01*
G01X636663Y672934D02*
X631063D01*
G01X638963Y675234D02*
X636663Y672934D01*
G01X631063D02*
Y711534D01*
G01X625206Y667085D02*
Y664863D01*
X625359Y664398D01*
X625666Y664088D01*
X626049Y663985D01*
X626432Y664088D01*
X626739Y664398D01*
X626892Y664863D01*
Y667085D01*
G01X628306Y664605D02*
X628536Y664243D01*
X628842Y664037D01*
X629187Y663985D01*
X629494Y664037D01*
X629801Y664295D01*
X629992Y664605D01*
X630031Y664915D01*
X629954Y665277D01*
X629686Y665535D01*
X629417Y665638D01*
X629072D01*
G01X629417D02*
X629647Y665793D01*
X629839Y666052D01*
X629916Y666362D01*
X629839Y666672D01*
X629647Y666930D01*
X629302Y667085D01*
X628957Y667033D01*
X628612Y666827D01*
G01X632249Y663985D02*
X632517Y664037D01*
X632824Y664192D01*
X633016Y664450D01*
X633092Y664812D01*
X633016Y665173D01*
X632786Y665483D01*
X632441Y665638D01*
X632057D01*
X631827Y665742D01*
X631636Y666000D01*
X631559Y666362D01*
X631674Y666723D01*
X631942Y666982D01*
X632249Y667085D01*
X632556Y666982D01*
X632824Y666723D01*
X632939Y666362D01*
X632862Y666000D01*
X632671Y665742D01*
X632441Y665638D01*
X632057D01*
X631712Y665483D01*
X631482Y665173D01*
X631406Y664812D01*
X631482Y664450D01*
X631674Y664192D01*
X631981Y664037D01*
X632249Y663985D01*
G01X632331Y662472D02*
X636131D01*
G01X630531Y660672D02*
X632331Y662472D01*
G01X628731D02*
X630531Y660672D01*
G01X624931Y662472D02*
X628731D01*
G01X631063Y711534D02*
X646863D01*
G01X629505Y712850D02*
Y715950D01*
X630464D01*
X630770Y715795D01*
X630962Y715588D01*
X631039Y715175D01*
X630962Y714762D01*
X630732Y714503D01*
X630464Y714348D01*
X629505D01*
G01X630464D02*
X631039Y712850D01*
G01X633372D02*
Y715950D01*
X632912Y715330D01*
G01Y712850D02*
X633832D01*
G01X636472D02*
Y715950D01*
X636012Y715330D01*
G01Y712850D02*
X636932D01*
G01X638844Y714142D02*
X639112Y714503D01*
X639342Y714710D01*
X639649Y714813D01*
X639917Y714710D01*
X640109Y714503D01*
X640262Y714193D01*
X640300Y713832D01*
X640262Y713522D01*
X640109Y713212D01*
X639879Y712953D01*
X639610Y712850D01*
X639304Y712953D01*
X639035Y713263D01*
X638882Y713728D01*
X638844Y714245D01*
X638920Y714917D01*
X639035Y715278D01*
X639227Y715640D01*
X639495Y715898D01*
X639764Y715950D01*
X640032Y715847D01*
X640224Y715588D01*
G01X642020Y713212D02*
X642289Y712953D01*
X642595Y712850D01*
X642902Y712953D01*
X643170Y713263D01*
X643362Y713728D01*
X643439Y714193D01*
Y714762D01*
X643362Y715227D01*
X643170Y715640D01*
X642940Y715847D01*
X642672Y715950D01*
X642365Y715847D01*
X642135Y715640D01*
X641982Y715330D01*
X641905Y714917D01*
X641982Y714555D01*
X642174Y714193D01*
X642404Y713987D01*
X642672Y713935D01*
X642979Y714038D01*
X643209Y714297D01*
X643439Y714762D01*
G01X629545Y717662D02*
Y720762D01*
X630504D01*
X630810Y720607D01*
X631002Y720400D01*
X631079Y719987D01*
X631002Y719574D01*
X630772Y719315D01*
X630504Y719160D01*
X629545D01*
G01X630504D02*
X631079Y717662D01*
G01X633412D02*
Y720762D01*
X632952Y720142D01*
G01Y717662D02*
X633872D01*
G01X636512D02*
Y720762D01*
X636052Y720142D01*
G01Y717662D02*
X636972D01*
G01X639535D02*
X639612Y718334D01*
X639727Y718902D01*
X639880Y719419D01*
X640072Y719987D01*
X640379Y720762D01*
X638845D01*
G01X641984Y720245D02*
X642214Y720555D01*
X642482Y720710D01*
X642789Y720762D01*
X643172Y720659D01*
X643440Y720400D01*
X643517Y720090D01*
X643479Y719780D01*
X643325Y719522D01*
X642559Y719005D01*
X642214Y718644D01*
X641984Y718127D01*
X641907Y717662D01*
X643517D01*
G01X630040Y737556D02*
X626840D01*
G01X630040Y743756D02*
Y737556D01*
G01X626840D02*
Y743756D01*
G01X630783Y725700D02*
Y728800D01*
X631742D01*
X632048Y728645D01*
X632240Y728438D01*
X632317Y728025D01*
X632240Y727612D01*
X632010Y727353D01*
X631742Y727198D01*
X630783D01*
G01X631742D02*
X632317Y725700D01*
G01X634650D02*
Y728800D01*
X634190Y728180D01*
G01Y725700D02*
X635110D01*
G01X637750D02*
Y728800D01*
X637290Y728180D01*
G01Y725700D02*
X638210D01*
G01X640773D02*
X640850Y726372D01*
X640965Y726940D01*
X641118Y727457D01*
X641310Y728025D01*
X641617Y728800D01*
X640083D01*
G01X643950D02*
X643643Y728697D01*
X643413Y728438D01*
X643260Y728128D01*
X643145Y727715D01*
X643107Y727250D01*
X643145Y726785D01*
X643260Y726372D01*
X643413Y726062D01*
X643643Y725803D01*
X643950Y725700D01*
X644257Y725803D01*
X644487Y726062D01*
X644640Y726372D01*
X644755Y726785D01*
X644793Y727250D01*
X644755Y727715D01*
X644640Y728128D01*
X644487Y728438D01*
X644257Y728697D01*
X643950Y728800D01*
G01X630883Y729400D02*
Y732500D01*
X631842D01*
X632148Y732345D01*
X632340Y732138D01*
X632417Y731725D01*
X632340Y731312D01*
X632110Y731053D01*
X631842Y730898D01*
X630883D01*
G01X631842D02*
X632417Y729400D01*
G01X634750D02*
Y732500D01*
X634290Y731880D01*
G01Y729400D02*
X635210D01*
G01X637850D02*
Y732500D01*
X637390Y731880D01*
G01Y729400D02*
X638310D01*
G01X640873D02*
X640950Y730072D01*
X641065Y730640D01*
X641218Y731157D01*
X641410Y731725D01*
X641717Y732500D01*
X640183D01*
G01X644050Y729400D02*
Y732500D01*
X643590Y731880D01*
G01Y729400D02*
X644510D01*
G01X634730Y737380D02*
X631530D01*
G01X634730Y743580D02*
Y737380D01*
G01X631530D02*
Y743580D01*
G01X638730Y737380D02*
X635530D01*
G01D02*
Y743580D01*
G01X621040Y743756D02*
Y737556D01*
G01X622340D02*
Y743756D01*
G01X625540D02*
Y737556D01*
G01D02*
X622340D01*
G01X621040Y732256D02*
Y726056D01*
G01X626840Y732256D02*
X630040D01*
G01X626840Y726056D02*
Y732256D01*
G01X630040Y726056D02*
X626840D01*
G01X630040Y732256D02*
Y726056D01*
G01X622340Y732256D02*
X625540D01*
G01X622340Y726056D02*
Y732256D01*
G01X625540Y726056D02*
X622340D01*
G01X625540Y732256D02*
Y726056D01*
G01X629940Y740656D02*
X626940D01*
G01X626840Y743756D02*
X630040D01*
G01X636672Y745221D02*
X633572D01*
Y746180D01*
X633727Y746486D01*
X633934Y746678D01*
X634347Y746755D01*
X634760Y746678D01*
X635019Y746448D01*
X635174Y746180D01*
Y745221D01*
G01Y746180D02*
X636672Y746755D01*
G01Y749088D02*
X633572D01*
X634192Y748628D01*
G01X636672D02*
Y749548D01*
G01X634089Y751460D02*
X633779Y751690D01*
X633624Y751958D01*
X633572Y752265D01*
X633675Y752648D01*
X633934Y752916D01*
X634244Y752993D01*
X634554Y752955D01*
X634812Y752801D01*
X635329Y752035D01*
X635690Y751690D01*
X636207Y751460D01*
X636672Y751383D01*
Y752993D01*
G01X634089Y754560D02*
X633779Y754790D01*
X633624Y755058D01*
X633572Y755365D01*
X633675Y755748D01*
X633934Y756016D01*
X634244Y756093D01*
X634554Y756055D01*
X634812Y755901D01*
X635329Y755135D01*
X635690Y754790D01*
X636207Y754560D01*
X636672Y754483D01*
Y756093D01*
G01X636052Y757545D02*
X636414Y757775D01*
X636620Y758081D01*
X636672Y758426D01*
X636620Y758733D01*
X636362Y759040D01*
X636052Y759231D01*
X635742Y759270D01*
X635380Y759193D01*
X635122Y758925D01*
X635019Y758656D01*
Y758311D01*
G01Y758656D02*
X634864Y758886D01*
X634605Y759078D01*
X634295Y759155D01*
X633985Y759078D01*
X633727Y758886D01*
X633572Y758541D01*
X633624Y758196D01*
X633830Y757851D01*
G01X631530Y743580D02*
X634730D01*
G01X635530D02*
X638730D01*
G01X622340Y743756D02*
X625540D01*
G01X630907Y748311D02*
X627807D01*
Y749270D01*
X627962Y749576D01*
X628169Y749768D01*
X628582Y749845D01*
X628995Y749768D01*
X629254Y749538D01*
X629409Y749270D01*
Y748311D01*
G01Y749270D02*
X630907Y749845D01*
G01Y752178D02*
X630855Y752446D01*
X630700Y752753D01*
X630442Y752945D01*
X630080Y753021D01*
X629719Y752945D01*
X629409Y752715D01*
X629254Y752370D01*
Y751986D01*
X629150Y751756D01*
X628892Y751565D01*
X628530Y751488D01*
X628169Y751603D01*
X627910Y751871D01*
X627807Y752178D01*
X627910Y752485D01*
X628169Y752753D01*
X628530Y752868D01*
X628892Y752791D01*
X629150Y752600D01*
X629254Y752370D01*
Y751986D01*
X629409Y751641D01*
X629719Y751411D01*
X630080Y751335D01*
X630442Y751411D01*
X630700Y751603D01*
X630855Y751910D01*
X630907Y752178D01*
G01Y755278D02*
X627807D01*
X628427Y754818D01*
G01X630907D02*
Y755738D01*
G01X630545Y757726D02*
X630804Y757995D01*
X630907Y758301D01*
X630804Y758608D01*
X630494Y758876D01*
X630029Y759068D01*
X629564Y759145D01*
X628995D01*
X628530Y759068D01*
X628117Y758876D01*
X627910Y758646D01*
X627807Y758378D01*
X627910Y758071D01*
X628117Y757841D01*
X628427Y757688D01*
X628840Y757611D01*
X629202Y757688D01*
X629564Y757880D01*
X629770Y758110D01*
X629822Y758378D01*
X629719Y758685D01*
X629460Y758915D01*
X628995Y759145D01*
G01X626508Y748311D02*
X623408D01*
Y749270D01*
X623563Y749576D01*
X623770Y749768D01*
X624183Y749845D01*
X624596Y749768D01*
X624855Y749538D01*
X625010Y749270D01*
Y748311D01*
G01Y749270D02*
X626508Y749845D01*
G01Y752178D02*
X626456Y752446D01*
X626301Y752753D01*
X626043Y752945D01*
X625681Y753021D01*
X625320Y752945D01*
X625010Y752715D01*
X624855Y752370D01*
Y751986D01*
X624751Y751756D01*
X624493Y751565D01*
X624131Y751488D01*
X623770Y751603D01*
X623511Y751871D01*
X623408Y752178D01*
X623511Y752485D01*
X623770Y752753D01*
X624131Y752868D01*
X624493Y752791D01*
X624751Y752600D01*
X624855Y752370D01*
Y751986D01*
X625010Y751641D01*
X625320Y751411D01*
X625681Y751335D01*
X626043Y751411D01*
X626301Y751603D01*
X626456Y751910D01*
X626508Y752178D01*
G01X623925Y754550D02*
X623615Y754780D01*
X623460Y755048D01*
X623408Y755355D01*
X623511Y755738D01*
X623770Y756006D01*
X624080Y756083D01*
X624390Y756045D01*
X624648Y755891D01*
X625165Y755125D01*
X625526Y754780D01*
X626043Y754550D01*
X626508Y754473D01*
Y756083D01*
G01Y758378D02*
X623408D01*
X624028Y757918D01*
G01X626508D02*
Y758838D01*
G01X649500Y46258D02*
X646400D01*
Y47217D01*
X646555Y47523D01*
X646762Y47715D01*
X647175Y47792D01*
X647588Y47715D01*
X647847Y47485D01*
X648002Y47217D01*
Y46258D01*
G01Y47217D02*
X649500Y47792D01*
G01Y50125D02*
X646400D01*
X647020Y49665D01*
G01X649500D02*
Y50585D01*
G01X646917Y52497D02*
X646607Y52727D01*
X646452Y52995D01*
X646400Y53302D01*
X646503Y53685D01*
X646762Y53953D01*
X647072Y54030D01*
X647382Y53992D01*
X647640Y53838D01*
X648157Y53072D01*
X648518Y52727D01*
X649035Y52497D01*
X649500Y52420D01*
Y54030D01*
G01Y56325D02*
X646400D01*
X647020Y55865D01*
G01X649500D02*
Y56785D01*
G01X648880Y58582D02*
X649242Y58812D01*
X649448Y59118D01*
X649500Y59463D01*
X649448Y59770D01*
X649190Y60077D01*
X648880Y60268D01*
X648570Y60307D01*
X648208Y60230D01*
X647950Y59962D01*
X647847Y59693D01*
Y59348D01*
G01Y59693D02*
X647692Y59923D01*
X647433Y60115D01*
X647123Y60192D01*
X646813Y60115D01*
X646555Y59923D01*
X646400Y59578D01*
X646452Y59233D01*
X646658Y58888D01*
G01X653520Y46188D02*
X650420D01*
Y47147D01*
X650575Y47453D01*
X650782Y47645D01*
X651195Y47722D01*
X651608Y47645D01*
X651867Y47415D01*
X652022Y47147D01*
Y46188D01*
G01Y47147D02*
X653520Y47722D01*
G01Y50055D02*
X650420D01*
X651040Y49595D01*
G01X653520D02*
Y50515D01*
G01Y53155D02*
X650420D01*
X651040Y52695D01*
G01X653520D02*
Y53615D01*
G01X653158Y55603D02*
X653417Y55872D01*
X653520Y56178D01*
X653417Y56485D01*
X653107Y56753D01*
X652642Y56945D01*
X652177Y57022D01*
X651608D01*
X651143Y56945D01*
X650730Y56753D01*
X650523Y56523D01*
X650420Y56255D01*
X650523Y55948D01*
X650730Y55718D01*
X651040Y55565D01*
X651453Y55488D01*
X651815Y55565D01*
X652177Y55757D01*
X652383Y55987D01*
X652435Y56255D01*
X652332Y56562D01*
X652073Y56792D01*
X651608Y57022D01*
G01X653520Y59278D02*
X652848Y59355D01*
X652280Y59470D01*
X651763Y59623D01*
X651195Y59815D01*
X650420Y60122D01*
Y58588D01*
G01X642357Y46000D02*
Y52200D01*
G01X645557D02*
Y46000D01*
G01D02*
X642357D01*
G01Y52200D02*
X645557D01*
G01X638357Y46000D02*
Y52200D01*
G01X641557D02*
Y46000D01*
G01D02*
X638357D01*
G01Y52200D02*
X641557D01*
G01X637749Y133841D02*
Y130641D01*
G01X640998Y219013D02*
X648341D01*
Y170841D01*
X641071D01*
Y219013D01*
X640998D01*
G01X646085Y172757D02*
X646502Y173264D01*
X646752Y173834D01*
Y174340D01*
X646502Y174847D01*
X646085Y175227D01*
X645502Y175417D01*
X644919Y175290D01*
X644419Y174974D01*
X644085Y174404D01*
X643919Y173644D01*
X643585Y173200D01*
X643002Y173010D01*
X642419Y173137D01*
X642002Y173454D01*
X641752Y173897D01*
Y174340D01*
X641919Y174784D01*
X642335Y175164D01*
G01X646752Y177604D02*
X641752Y179187D01*
X646752Y180770D01*
G01X645002Y180200D02*
Y178174D01*
G01X641752Y184287D02*
X646752D01*
G01X641752Y182830D02*
Y185744D01*
G01X646752Y187804D02*
X641752Y189387D01*
X646752Y190970D01*
G01X645002Y190400D02*
Y188374D01*
G01X642169Y200980D02*
X641919Y200600D01*
X641752Y200157D01*
Y199650D01*
X642002Y199080D01*
X642419Y198637D01*
X642919Y198320D01*
X643752Y198067D01*
X644502Y198004D01*
X645252Y198130D01*
X645752Y198320D01*
X646252Y198700D01*
X646585Y199144D01*
X646752Y199587D01*
Y200030D01*
X646585Y200474D01*
X646335Y200854D01*
X646002Y201170D01*
G01X646752Y204687D02*
X646669Y204180D01*
X646335Y203737D01*
X645835Y203357D01*
X645252Y203104D01*
X644585Y202977D01*
X643919D01*
X643252Y203104D01*
X642669Y203357D01*
X642169Y203737D01*
X641835Y204180D01*
X641752Y204687D01*
X641835Y205194D01*
X642169Y205637D01*
X642669Y206017D01*
X643252Y206270D01*
X643919Y206397D01*
X644585D01*
X645252Y206270D01*
X645835Y206017D01*
X646335Y205637D01*
X646669Y205194D01*
X646752Y204687D01*
G01Y208330D02*
X641752D01*
X646752Y211244D01*
X641752D01*
G01X646752Y213430D02*
X641752D01*
X646752Y216344D01*
X641752D01*
G01X638430Y222950D02*
X641530D01*
Y224484D01*
G01Y227277D02*
X638430D01*
X640652Y225859D01*
Y227775D01*
G01X641530Y230377D02*
X638430D01*
X640652Y228959D01*
Y230875D01*
G01X642609Y226880D02*
Y229980D01*
X643568D01*
X643874Y229825D01*
X644066Y229618D01*
X644143Y229205D01*
X644066Y228792D01*
X643836Y228533D01*
X643568Y228378D01*
X642609D01*
G01X643568D02*
X644143Y226880D01*
G01X645748Y229463D02*
X645978Y229773D01*
X646246Y229928D01*
X646553Y229980D01*
X646936Y229877D01*
X647204Y229618D01*
X647281Y229308D01*
X647243Y228998D01*
X647089Y228740D01*
X646323Y228223D01*
X645978Y227862D01*
X645748Y227345D01*
X645671Y226880D01*
X647281D01*
G01X648848Y228172D02*
X649116Y228533D01*
X649346Y228740D01*
X649653Y228843D01*
X649921Y228740D01*
X650113Y228533D01*
X650266Y228223D01*
X650304Y227862D01*
X650266Y227552D01*
X650113Y227242D01*
X649883Y226983D01*
X649614Y226880D01*
X649308Y226983D01*
X649039Y227293D01*
X648886Y227758D01*
X648848Y228275D01*
X648924Y228947D01*
X649039Y229308D01*
X649231Y229670D01*
X649499Y229928D01*
X649768Y229980D01*
X650036Y229877D01*
X650228Y229618D01*
G01X652676Y226880D02*
X652944Y226932D01*
X653251Y227087D01*
X653443Y227345D01*
X653519Y227707D01*
X653443Y228068D01*
X653213Y228378D01*
X652868Y228533D01*
X652484D01*
X652254Y228637D01*
X652063Y228895D01*
X651986Y229257D01*
X652101Y229618D01*
X652369Y229877D01*
X652676Y229980D01*
X652983Y229877D01*
X653251Y229618D01*
X653366Y229257D01*
X653289Y228895D01*
X653098Y228637D01*
X652868Y228533D01*
X652484D01*
X652139Y228378D01*
X651909Y228068D01*
X651833Y227707D01*
X651909Y227345D01*
X652101Y227087D01*
X652408Y226932D01*
X652676Y226880D01*
G01X642609Y222880D02*
Y225980D01*
X643568D01*
X643874Y225825D01*
X644066Y225618D01*
X644143Y225205D01*
X644066Y224792D01*
X643836Y224533D01*
X643568Y224378D01*
X642609D01*
G01X643568D02*
X644143Y222880D01*
G01X645748Y225463D02*
X645978Y225773D01*
X646246Y225928D01*
X646553Y225980D01*
X646936Y225877D01*
X647204Y225618D01*
X647281Y225308D01*
X647243Y224998D01*
X647089Y224740D01*
X646323Y224223D01*
X645978Y223862D01*
X645748Y223345D01*
X645671Y222880D01*
X647281D01*
G01X648848Y224172D02*
X649116Y224533D01*
X649346Y224740D01*
X649653Y224843D01*
X649921Y224740D01*
X650113Y224533D01*
X650266Y224223D01*
X650304Y223862D01*
X650266Y223552D01*
X650113Y223242D01*
X649883Y222983D01*
X649614Y222880D01*
X649308Y222983D01*
X649039Y223293D01*
X648886Y223758D01*
X648848Y224275D01*
X648924Y224947D01*
X649039Y225308D01*
X649231Y225670D01*
X649499Y225928D01*
X649768Y225980D01*
X650036Y225877D01*
X650228Y225618D01*
G01X652024Y223242D02*
X652293Y222983D01*
X652599Y222880D01*
X652906Y222983D01*
X653174Y223293D01*
X653366Y223758D01*
X653443Y224223D01*
Y224792D01*
X653366Y225257D01*
X653174Y225670D01*
X652944Y225877D01*
X652676Y225980D01*
X652369Y225877D01*
X652139Y225670D01*
X651986Y225360D01*
X651909Y224947D01*
X651986Y224585D01*
X652178Y224223D01*
X652408Y224017D01*
X652676Y223965D01*
X652983Y224068D01*
X653213Y224327D01*
X653443Y224792D01*
G01X642600Y267183D02*
X639500D01*
Y268142D01*
X639655Y268448D01*
X639862Y268640D01*
X640275Y268717D01*
X640688Y268640D01*
X640947Y268410D01*
X641102Y268142D01*
Y267183D01*
G01Y268142D02*
X642600Y268717D01*
G01Y271050D02*
X639500D01*
X640120Y270590D01*
G01X642600D02*
Y271510D01*
G01Y274150D02*
X639500D01*
X640120Y273690D01*
G01X642600D02*
Y274610D01*
G01X641308Y276522D02*
X640947Y276790D01*
X640740Y277020D01*
X640637Y277327D01*
X640740Y277595D01*
X640947Y277787D01*
X641257Y277940D01*
X641618Y277978D01*
X641928Y277940D01*
X642238Y277787D01*
X642497Y277557D01*
X642600Y277288D01*
X642497Y276982D01*
X642187Y276713D01*
X641722Y276560D01*
X641205Y276522D01*
X640533Y276598D01*
X640172Y276713D01*
X639810Y276905D01*
X639552Y277173D01*
X639500Y277442D01*
X639603Y277710D01*
X639862Y277902D01*
G01X641980Y279507D02*
X642342Y279737D01*
X642548Y280043D01*
X642600Y280388D01*
X642548Y280695D01*
X642290Y281002D01*
X641980Y281193D01*
X641670Y281232D01*
X641308Y281155D01*
X641050Y280887D01*
X640947Y280618D01*
Y280273D01*
G01Y280618D02*
X640792Y280848D01*
X640533Y281040D01*
X640223Y281117D01*
X639913Y281040D01*
X639655Y280848D01*
X639500Y280503D01*
X639552Y280158D01*
X639758Y279813D01*
G01X646500Y267283D02*
X643400D01*
Y268242D01*
X643555Y268548D01*
X643762Y268740D01*
X644175Y268817D01*
X644588Y268740D01*
X644847Y268510D01*
X645002Y268242D01*
Y267283D01*
G01Y268242D02*
X646500Y268817D01*
G01X645208Y270422D02*
X644847Y270690D01*
X644640Y270920D01*
X644537Y271227D01*
X644640Y271495D01*
X644847Y271687D01*
X645157Y271840D01*
X645518Y271878D01*
X645828Y271840D01*
X646138Y271687D01*
X646397Y271457D01*
X646500Y271188D01*
X646397Y270882D01*
X646087Y270613D01*
X645622Y270460D01*
X645105Y270422D01*
X644433Y270498D01*
X644072Y270613D01*
X643710Y270805D01*
X643452Y271073D01*
X643400Y271342D01*
X643503Y271610D01*
X643762Y271802D01*
G01X646500Y274250D02*
X643400D01*
X644020Y273790D01*
G01X646500D02*
Y274710D01*
G01X646035Y276507D02*
X646293Y276737D01*
X646448Y277005D01*
X646500Y277350D01*
X646397Y277695D01*
X646190Y277963D01*
X645828Y278155D01*
X645415Y278193D01*
X645002Y278117D01*
X644743Y277925D01*
X644537Y277657D01*
X644485Y277388D01*
X644537Y277120D01*
X644743Y276775D01*
X643400Y276890D01*
Y277925D01*
G01X654600Y267283D02*
X651500D01*
Y268242D01*
X651655Y268548D01*
X651862Y268740D01*
X652275Y268817D01*
X652688Y268740D01*
X652947Y268510D01*
X653102Y268242D01*
Y267283D01*
G01Y268242D02*
X654600Y268817D01*
G01X653308Y270422D02*
X652947Y270690D01*
X652740Y270920D01*
X652637Y271227D01*
X652740Y271495D01*
X652947Y271687D01*
X653257Y271840D01*
X653618Y271878D01*
X653928Y271840D01*
X654238Y271687D01*
X654497Y271457D01*
X654600Y271188D01*
X654497Y270882D01*
X654187Y270613D01*
X653722Y270460D01*
X653205Y270422D01*
X652533Y270498D01*
X652172Y270613D01*
X651810Y270805D01*
X651552Y271073D01*
X651500Y271342D01*
X651603Y271610D01*
X651862Y271802D01*
G01X654600Y274250D02*
X651500D01*
X652120Y273790D01*
G01X654600D02*
Y274710D01*
G01Y277810D02*
X651500D01*
X653722Y276392D01*
Y278308D01*
G01X650700Y267283D02*
X647600D01*
Y268242D01*
X647755Y268548D01*
X647962Y268740D01*
X648375Y268817D01*
X648788Y268740D01*
X649047Y268510D01*
X649202Y268242D01*
Y267283D01*
G01Y268242D02*
X650700Y268817D01*
G01Y271150D02*
X647600D01*
X648220Y270690D01*
G01X650700D02*
Y271610D01*
G01Y274250D02*
X647600D01*
X648220Y273790D01*
G01X650700D02*
Y274710D01*
G01X650235Y276507D02*
X650493Y276737D01*
X650648Y277005D01*
X650700Y277350D01*
X650597Y277695D01*
X650390Y277963D01*
X650028Y278155D01*
X649615Y278193D01*
X649202Y278117D01*
X648943Y277925D01*
X648737Y277657D01*
X648685Y277388D01*
X648737Y277120D01*
X648943Y276775D01*
X647600Y276890D01*
Y277925D01*
G01X650338Y279798D02*
X650597Y280067D01*
X650700Y280373D01*
X650597Y280680D01*
X650287Y280948D01*
X649822Y281140D01*
X649357Y281217D01*
X648788D01*
X648323Y281140D01*
X647910Y280948D01*
X647703Y280718D01*
X647600Y280450D01*
X647703Y280143D01*
X647910Y279913D01*
X648220Y279760D01*
X648633Y279683D01*
X648995Y279760D01*
X649357Y279952D01*
X649563Y280182D01*
X649615Y280450D01*
X649512Y280757D01*
X649253Y280987D01*
X648788Y281217D01*
G01X638868Y290689D02*
Y287489D01*
G01X650283Y287106D02*
X644083D01*
G01Y290306D02*
X650283D01*
G01D02*
Y287106D01*
G01X644083D02*
Y290306D01*
G01X647183Y287206D02*
Y290206D01*
G01X638887Y286642D02*
Y283442D01*
G01X654952Y283658D02*
X651752D01*
G01D02*
Y289858D01*
G01D02*
X654952D01*
G01X650907Y297758D02*
X650720Y297467D01*
X650560Y297300D01*
X650347Y297217D01*
X650160Y297300D01*
X650027Y297467D01*
X649920Y297717D01*
X649893Y298008D01*
X649920Y298258D01*
X650027Y298508D01*
X650187Y298717D01*
X650373Y298800D01*
X650587Y298717D01*
X650773Y298467D01*
X650880Y298092D01*
X650907Y297675D01*
X650853Y297133D01*
X650773Y296842D01*
X650640Y296550D01*
X650453Y296342D01*
X650267Y296300D01*
X650080Y296383D01*
X649947Y296592D01*
G01X649427Y310702D02*
Y313202D01*
X649107Y312702D01*
G01Y310702D02*
X649747D01*
G01X651627Y313202D02*
X651414Y313119D01*
X651254Y312910D01*
X651147Y312660D01*
X651067Y312327D01*
X651040Y311952D01*
X651067Y311577D01*
X651147Y311244D01*
X651254Y310994D01*
X651414Y310785D01*
X651627Y310702D01*
X651840Y310785D01*
X652000Y310994D01*
X652107Y311244D01*
X652187Y311577D01*
X652214Y311952D01*
X652187Y312327D01*
X652107Y312660D01*
X652000Y312910D01*
X651840Y313119D01*
X651627Y313202D01*
G01X648456Y310584D02*
X646152D01*
G01X648456Y309780D02*
Y310584D01*
G01Y298576D02*
Y299380D01*
G01X646352Y298576D02*
X648456D01*
G01X649842Y320760D02*
Y313960D01*
G01X642342Y320660D02*
Y314060D01*
G01X649832Y328398D02*
Y321598D01*
G01X642332Y328298D02*
Y321698D01*
G01X643772Y346946D02*
X643542Y347101D01*
X643274Y347204D01*
X642967D01*
X642622Y347049D01*
X642354Y346791D01*
X642162Y346481D01*
X642009Y345964D01*
X641971Y345499D01*
X642047Y345034D01*
X642162Y344724D01*
X642392Y344414D01*
X642661Y344207D01*
X642929Y344104D01*
X643197D01*
X643466Y344207D01*
X643696Y344362D01*
X643887Y344569D01*
G01X645186Y344724D02*
X645416Y344362D01*
X645722Y344156D01*
X646067Y344104D01*
X646374Y344156D01*
X646681Y344414D01*
X646872Y344724D01*
X646911Y345034D01*
X646834Y345396D01*
X646566Y345654D01*
X646297Y345757D01*
X645952D01*
G01X646297D02*
X646527Y345912D01*
X646719Y346171D01*
X646796Y346481D01*
X646719Y346791D01*
X646527Y347049D01*
X646182Y347204D01*
X645837Y347152D01*
X645492Y346946D01*
G01X648401Y345396D02*
X648669Y345757D01*
X648899Y345964D01*
X649206Y346067D01*
X649474Y345964D01*
X649666Y345757D01*
X649819Y345447D01*
X649857Y345086D01*
X649819Y344776D01*
X649666Y344466D01*
X649436Y344207D01*
X649167Y344104D01*
X648861Y344207D01*
X648592Y344517D01*
X648439Y344982D01*
X648401Y345499D01*
X648477Y346171D01*
X648592Y346532D01*
X648784Y346894D01*
X649052Y347152D01*
X649321Y347204D01*
X649589Y347101D01*
X649781Y346842D01*
G01X652152Y344104D02*
X652229Y344776D01*
X652344Y345344D01*
X652497Y345861D01*
X652689Y346429D01*
X652996Y347204D01*
X651462D01*
G01X642290Y340158D02*
Y343258D01*
X643249D01*
X643555Y343103D01*
X643747Y342896D01*
X643824Y342483D01*
X643747Y342070D01*
X643517Y341811D01*
X643249Y341656D01*
X642290D01*
G01X643249D02*
X643824Y340158D01*
G01X645314Y340623D02*
X645544Y340365D01*
X645812Y340210D01*
X646157Y340158D01*
X646502Y340261D01*
X646770Y340468D01*
X646962Y340830D01*
X647000Y341243D01*
X646924Y341656D01*
X646732Y341915D01*
X646464Y342121D01*
X646195Y342173D01*
X645927Y342121D01*
X645582Y341915D01*
X645697Y343258D01*
X646732D01*
G01X648529Y342741D02*
X648759Y343051D01*
X649027Y343206D01*
X649334Y343258D01*
X649717Y343155D01*
X649985Y342896D01*
X650062Y342586D01*
X650024Y342276D01*
X649870Y342018D01*
X649104Y341501D01*
X648759Y341140D01*
X648529Y340623D01*
X648452Y340158D01*
X650062D01*
G01X651705Y340520D02*
X651974Y340261D01*
X652280Y340158D01*
X652587Y340261D01*
X652855Y340571D01*
X653047Y341036D01*
X653124Y341501D01*
Y342070D01*
X653047Y342535D01*
X652855Y342948D01*
X652625Y343155D01*
X652357Y343258D01*
X652050Y343155D01*
X651820Y342948D01*
X651667Y342638D01*
X651590Y342225D01*
X651667Y341863D01*
X651859Y341501D01*
X652089Y341295D01*
X652357Y341243D01*
X652664Y341346D01*
X652894Y341605D01*
X653124Y342070D01*
G01X641338Y353285D02*
Y356485D01*
G01X647538Y353285D02*
X641338D01*
G01Y356485D02*
X647538D01*
G01X644438Y356385D02*
Y353385D01*
G01X647538Y356485D02*
Y353285D01*
G01X641438Y348185D02*
Y351385D01*
G01X647638Y348185D02*
X641438D01*
G01Y351385D02*
X647638D01*
G01D02*
Y348185D01*
G01X648938Y375435D02*
Y378935D01*
G01X655538Y366385D02*
X652338D01*
G01D02*
Y372585D01*
G01D02*
X655538D01*
G01X643636Y366352D02*
Y372552D01*
G01X646836Y366352D02*
X643636D01*
G01X646836Y372552D02*
Y366352D01*
G01X643636Y372552D02*
X646836D01*
G01X639636Y366352D02*
Y372552D01*
G01X642836Y366352D02*
X639636D01*
G01X642836Y372552D02*
Y366352D01*
G01X639636Y372552D02*
X642836D01*
G01X647636Y366352D02*
Y372552D01*
G01X650836Y366352D02*
X647636D01*
G01X650836Y372552D02*
Y366352D01*
G01X647636Y372552D02*
X650836D01*
G01X641730Y378225D02*
Y380725D01*
X641410Y380225D01*
G01Y378225D02*
X642050D01*
G01X643930D02*
X644117Y378267D01*
X644330Y378392D01*
X644463Y378600D01*
X644517Y378892D01*
X644463Y379183D01*
X644303Y379433D01*
X644063Y379558D01*
X643797D01*
X643637Y379642D01*
X643503Y379850D01*
X643450Y380142D01*
X643530Y380433D01*
X643717Y380642D01*
X643930Y380725D01*
X644143Y380642D01*
X644330Y380433D01*
X644410Y380142D01*
X644357Y379850D01*
X644223Y379642D01*
X644063Y379558D01*
X643797D01*
X643557Y379433D01*
X643397Y379183D01*
X643343Y378892D01*
X643397Y378600D01*
X643530Y378392D01*
X643743Y378267D01*
X643930Y378225D01*
G01X637414Y382215D02*
Y384715D01*
X637094Y384215D01*
G01Y382215D02*
X637734D01*
G01X639561D02*
X639614Y382757D01*
X639694Y383215D01*
X639801Y383632D01*
X639934Y384090D01*
X640147Y384715D01*
X639081D01*
G01X642690Y381637D02*
X644990D01*
G01X642690Y383937D02*
Y381637D01*
G01X637938Y387885D02*
X639938D01*
G01X637938Y403685D02*
X639938D01*
G01X639064Y415973D02*
X639251Y416264D01*
X639411Y416431D01*
X639624Y416514D01*
X639811Y416431D01*
X639944Y416264D01*
X640051Y416014D01*
X640078Y415723D01*
X640051Y415473D01*
X639944Y415223D01*
X639784Y415014D01*
X639598Y414931D01*
X639384Y415014D01*
X639198Y415264D01*
X639091Y415639D01*
X639064Y416056D01*
X639118Y416598D01*
X639198Y416889D01*
X639331Y417181D01*
X639518Y417389D01*
X639704Y417431D01*
X639891Y417348D01*
X640024Y417139D01*
G01X641771Y414931D02*
X641958Y414973D01*
X642171Y415098D01*
X642304Y415306D01*
X642358Y415598D01*
X642304Y415889D01*
X642144Y416139D01*
X641904Y416264D01*
X641638D01*
X641478Y416348D01*
X641344Y416556D01*
X641291Y416848D01*
X641371Y417139D01*
X641558Y417348D01*
X641771Y417431D01*
X641984Y417348D01*
X642171Y417139D01*
X642251Y416848D01*
X642198Y416556D01*
X642064Y416348D01*
X641904Y416264D01*
X641638D01*
X641398Y416139D01*
X641238Y415889D01*
X641184Y415598D01*
X641238Y415306D01*
X641371Y415098D01*
X641584Y414973D01*
X641771Y414931D01*
G01X639638Y411222D02*
Y413722D01*
X639318Y413222D01*
G01Y411222D02*
X639958D01*
G01X642690Y413133D02*
Y410833D01*
G01X644990Y413133D02*
X642690D01*
G01X650538Y415885D02*
Y417885D01*
G01X645728Y438449D02*
Y441549D01*
X646687D01*
X646993Y441394D01*
X647185Y441187D01*
X647262Y440774D01*
X647185Y440361D01*
X646955Y440102D01*
X646687Y439947D01*
X645728D01*
G01X646687D02*
X647262Y438449D01*
G01X649595D02*
Y441549D01*
X649135Y440929D01*
G01Y438449D02*
X650055D01*
G01X652695Y441549D02*
X652388Y441446D01*
X652158Y441187D01*
X652005Y440877D01*
X651890Y440464D01*
X651852Y439999D01*
X651890Y439534D01*
X652005Y439121D01*
X652158Y438811D01*
X652388Y438552D01*
X652695Y438449D01*
X653002Y438552D01*
X653232Y438811D01*
X653385Y439121D01*
X653500Y439534D01*
X653538Y439999D01*
X653500Y440464D01*
X653385Y440877D01*
X653232Y441187D01*
X653002Y441446D01*
X652695Y441549D01*
G01X656255Y438449D02*
Y441549D01*
X654837Y439327D01*
X656753D01*
G01X658052Y438914D02*
X658282Y438656D01*
X658550Y438501D01*
X658895Y438449D01*
X659240Y438552D01*
X659508Y438759D01*
X659700Y439121D01*
X659738Y439534D01*
X659662Y439947D01*
X659470Y440206D01*
X659202Y440412D01*
X658933Y440464D01*
X658665Y440412D01*
X658320Y440206D01*
X658435Y441549D01*
X659470D01*
G01X645728Y434318D02*
Y437418D01*
X646687D01*
X646993Y437263D01*
X647185Y437056D01*
X647262Y436643D01*
X647185Y436230D01*
X646955Y435971D01*
X646687Y435816D01*
X645728D01*
G01X646687D02*
X647262Y434318D01*
G01X649595D02*
Y437418D01*
X649135Y436798D01*
G01Y434318D02*
X650055D01*
G01X652695Y437418D02*
X652388Y437315D01*
X652158Y437056D01*
X652005Y436746D01*
X651890Y436333D01*
X651852Y435868D01*
X651890Y435403D01*
X652005Y434990D01*
X652158Y434680D01*
X652388Y434421D01*
X652695Y434318D01*
X653002Y434421D01*
X653232Y434680D01*
X653385Y434990D01*
X653500Y435403D01*
X653538Y435868D01*
X653500Y436333D01*
X653385Y436746D01*
X653232Y437056D01*
X653002Y437315D01*
X652695Y437418D01*
G01X654952Y434938D02*
X655182Y434576D01*
X655488Y434370D01*
X655833Y434318D01*
X656140Y434370D01*
X656447Y434628D01*
X656638Y434938D01*
X656677Y435248D01*
X656600Y435610D01*
X656332Y435868D01*
X656063Y435971D01*
X655718D01*
G01X656063D02*
X656293Y436126D01*
X656485Y436385D01*
X656562Y436695D01*
X656485Y437005D01*
X656293Y437263D01*
X655948Y437418D01*
X655603Y437366D01*
X655258Y437160D01*
G01X658895Y437418D02*
X658588Y437315D01*
X658358Y437056D01*
X658205Y436746D01*
X658090Y436333D01*
X658052Y435868D01*
X658090Y435403D01*
X658205Y434990D01*
X658358Y434680D01*
X658588Y434421D01*
X658895Y434318D01*
X659202Y434421D01*
X659432Y434680D01*
X659585Y434990D01*
X659700Y435403D01*
X659738Y435868D01*
X659700Y436333D01*
X659585Y436746D01*
X659432Y437056D01*
X659202Y437315D01*
X658895Y437418D01*
G01X645728Y447084D02*
Y450184D01*
X646687D01*
X646993Y450029D01*
X647185Y449822D01*
X647262Y449409D01*
X647185Y448996D01*
X646955Y448737D01*
X646687Y448582D01*
X645728D01*
G01X646687D02*
X647262Y447084D01*
G01X649595D02*
Y450184D01*
X649135Y449564D01*
G01Y447084D02*
X650055D01*
G01X652695Y450184D02*
X652388Y450081D01*
X652158Y449822D01*
X652005Y449512D01*
X651890Y449099D01*
X651852Y448634D01*
X651890Y448169D01*
X652005Y447756D01*
X652158Y447446D01*
X652388Y447187D01*
X652695Y447084D01*
X653002Y447187D01*
X653232Y447446D01*
X653385Y447756D01*
X653500Y448169D01*
X653538Y448634D01*
X653500Y449099D01*
X653385Y449512D01*
X653232Y449822D01*
X653002Y450081D01*
X652695Y450184D01*
G01X654952Y447704D02*
X655182Y447342D01*
X655488Y447136D01*
X655833Y447084D01*
X656140Y447136D01*
X656447Y447394D01*
X656638Y447704D01*
X656677Y448014D01*
X656600Y448376D01*
X656332Y448634D01*
X656063Y448737D01*
X655718D01*
G01X656063D02*
X656293Y448892D01*
X656485Y449151D01*
X656562Y449461D01*
X656485Y449771D01*
X656293Y450029D01*
X655948Y450184D01*
X655603Y450132D01*
X655258Y449926D01*
G01X658895Y447084D02*
Y450184D01*
X658435Y449564D01*
G01Y447084D02*
X659355D01*
G01X645728Y442749D02*
Y445849D01*
X646687D01*
X646993Y445694D01*
X647185Y445487D01*
X647262Y445074D01*
X647185Y444661D01*
X646955Y444402D01*
X646687Y444247D01*
X645728D01*
G01X646687D02*
X647262Y442749D01*
G01X649595D02*
Y445849D01*
X649135Y445229D01*
G01Y442749D02*
X650055D01*
G01X652695Y445849D02*
X652388Y445746D01*
X652158Y445487D01*
X652005Y445177D01*
X651890Y444764D01*
X651852Y444299D01*
X651890Y443834D01*
X652005Y443421D01*
X652158Y443111D01*
X652388Y442852D01*
X652695Y442749D01*
X653002Y442852D01*
X653232Y443111D01*
X653385Y443421D01*
X653500Y443834D01*
X653538Y444299D01*
X653500Y444764D01*
X653385Y445177D01*
X653232Y445487D01*
X653002Y445746D01*
X652695Y445849D01*
G01X656255Y442749D02*
Y445849D01*
X654837Y443627D01*
X656753D01*
G01X658167Y445332D02*
X658397Y445642D01*
X658665Y445797D01*
X658972Y445849D01*
X659355Y445746D01*
X659623Y445487D01*
X659700Y445177D01*
X659662Y444867D01*
X659508Y444609D01*
X658742Y444092D01*
X658397Y443731D01*
X658167Y443214D01*
X658090Y442749D01*
X659700D01*
G01X645728Y451484D02*
Y454584D01*
X646687D01*
X646993Y454429D01*
X647185Y454222D01*
X647262Y453809D01*
X647185Y453396D01*
X646955Y453137D01*
X646687Y452982D01*
X645728D01*
G01X646687D02*
X647262Y451484D01*
G01X649595D02*
Y454584D01*
X649135Y453964D01*
G01Y451484D02*
X650055D01*
G01X652695Y454584D02*
X652388Y454481D01*
X652158Y454222D01*
X652005Y453912D01*
X651890Y453499D01*
X651852Y453034D01*
X651890Y452569D01*
X652005Y452156D01*
X652158Y451846D01*
X652388Y451587D01*
X652695Y451484D01*
X653002Y451587D01*
X653232Y451846D01*
X653385Y452156D01*
X653500Y452569D01*
X653538Y453034D01*
X653500Y453499D01*
X653385Y453912D01*
X653232Y454222D01*
X653002Y454481D01*
X652695Y454584D01*
G01X654952Y451949D02*
X655182Y451691D01*
X655450Y451536D01*
X655795Y451484D01*
X656140Y451587D01*
X656408Y451794D01*
X656600Y452156D01*
X656638Y452569D01*
X656562Y452982D01*
X656370Y453241D01*
X656102Y453447D01*
X655833Y453499D01*
X655565Y453447D01*
X655220Y453241D01*
X655335Y454584D01*
X656370D01*
G01X658895D02*
X658588Y454481D01*
X658358Y454222D01*
X658205Y453912D01*
X658090Y453499D01*
X658052Y453034D01*
X658090Y452569D01*
X658205Y452156D01*
X658358Y451846D01*
X658588Y451587D01*
X658895Y451484D01*
X659202Y451587D01*
X659432Y451846D01*
X659585Y452156D01*
X659700Y452569D01*
X659738Y453034D01*
X659700Y453499D01*
X659585Y453912D01*
X659432Y454222D01*
X659202Y454481D01*
X658895Y454584D01*
G01X643639Y467488D02*
Y464288D01*
G01X637439Y467488D02*
X643639D01*
G01X637439Y464288D02*
Y467488D01*
G01X643639Y464288D02*
X637439D01*
G01X643639Y460288D02*
X637439D01*
G01X643639Y463488D02*
Y460288D01*
G01X637439Y463488D02*
X643639D01*
G01X637439Y460288D02*
Y463488D01*
G01Y456288D02*
Y459488D01*
G01X643639Y456288D02*
X637439D01*
G01X643639Y459488D02*
Y456288D01*
G01X637439Y459488D02*
X643639D01*
G01X646700Y471241D02*
X646807Y471366D01*
X646887Y471575D01*
X646940Y471866D01*
X646887Y472116D01*
X646780Y472283D01*
X646594Y472408D01*
X645874D01*
Y469908D01*
X646754D01*
X646940Y470075D01*
X647047Y470325D01*
X647100Y470616D01*
X647047Y470908D01*
X646887Y471158D01*
X646700Y471241D01*
X645874D01*
G01X645026Y480979D02*
Y468899D01*
G01X646676Y484347D02*
X646783Y484472D01*
X646863Y484681D01*
X646916Y484972D01*
X646863Y485222D01*
X646756Y485389D01*
X646570Y485514D01*
X645850D01*
Y483014D01*
X646730D01*
X646916Y483181D01*
X647023Y483431D01*
X647076Y483722D01*
X647023Y484014D01*
X646863Y484264D01*
X646676Y484347D01*
X645850D01*
G01X645061Y494310D02*
Y482230D01*
G01X648435Y477525D02*
X647369D01*
Y480025D01*
X648435D01*
G01X648009Y478817D02*
X647369D01*
G01X649325Y500349D02*
X649018Y500401D01*
X648750Y500607D01*
X648520Y500917D01*
X648367Y501279D01*
X648290Y501692D01*
Y502106D01*
X648367Y502519D01*
X648520Y502881D01*
X648750Y503191D01*
X649018Y503397D01*
X649325Y503449D01*
X649632Y503397D01*
X649900Y503191D01*
X650130Y502881D01*
X650283Y502519D01*
X650360Y502106D01*
Y501692D01*
X650283Y501279D01*
X650130Y500917D01*
X649900Y500607D01*
X649632Y500401D01*
X649325Y500349D01*
G01X649632Y501176D02*
X650092Y500349D01*
G01X651697Y502932D02*
X651927Y503242D01*
X652195Y503397D01*
X652502Y503449D01*
X652885Y503346D01*
X653153Y503087D01*
X653230Y502777D01*
X653192Y502467D01*
X653038Y502209D01*
X652272Y501692D01*
X651927Y501331D01*
X651697Y500814D01*
X651620Y500349D01*
X653230D01*
G01X655525D02*
X655793Y500401D01*
X656100Y500556D01*
X656292Y500814D01*
X656368Y501176D01*
X656292Y501537D01*
X656062Y501847D01*
X655717Y502002D01*
X655333D01*
X655103Y502106D01*
X654912Y502364D01*
X654835Y502726D01*
X654950Y503087D01*
X655218Y503346D01*
X655525Y503449D01*
X655832Y503346D01*
X656100Y503087D01*
X656215Y502726D01*
X656138Y502364D01*
X655947Y502106D01*
X655717Y502002D01*
X655333D01*
X654988Y501847D01*
X654758Y501537D01*
X654682Y501176D01*
X654758Y500814D01*
X654950Y500556D01*
X655257Y500401D01*
X655525Y500349D01*
G01X646602Y497659D02*
X646709Y497784D01*
X646789Y497993D01*
X646842Y498284D01*
X646789Y498534D01*
X646682Y498701D01*
X646496Y498826D01*
X645776D01*
Y496326D01*
X646656D01*
X646842Y496493D01*
X646949Y496743D01*
X647002Y497034D01*
X646949Y497326D01*
X646789Y497576D01*
X646602Y497659D01*
X645776D01*
G01X647031Y501440D02*
X645965D01*
Y503940D01*
X647031D01*
G01X646605Y502732D02*
X645965D01*
G01X644961Y507510D02*
Y495430D01*
G01X647250Y488237D02*
X646184D01*
Y490737D01*
X647250D01*
G01X646824Y489529D02*
X646184D01*
G01X650222Y505605D02*
Y508705D01*
X650988D01*
X651295Y508550D01*
X651525Y508343D01*
X651717Y508033D01*
X651870Y507672D01*
X651908Y507155D01*
X651870Y506638D01*
X651717Y506277D01*
X651525Y505967D01*
X651295Y505760D01*
X650988Y505605D01*
X650222D01*
G01X653437Y508188D02*
X653667Y508498D01*
X653935Y508653D01*
X654242Y508705D01*
X654625Y508602D01*
X654893Y508343D01*
X654970Y508033D01*
X654932Y507723D01*
X654778Y507465D01*
X654012Y506948D01*
X653667Y506587D01*
X653437Y506070D01*
X653360Y505605D01*
X654970D01*
G01X657265D02*
Y508705D01*
X656805Y508085D01*
G01Y505605D02*
X657725D01*
G01X649869Y508360D02*
G02I-1628J0D01*
G01X643561Y513430D02*
Y509030D01*
G01X644161Y513430D02*
Y509030D01*
G01X644761D02*
Y513430D01*
G01X645361D02*
Y509030D01*
G01D02*
X643561D01*
G01X645361Y513430D02*
X643561D01*
G01X639961Y518330D02*
Y515130D01*
G01X653534Y511017D02*
X650434D01*
Y511976D01*
X650589Y512282D01*
X650796Y512474D01*
X651209Y512551D01*
X651622Y512474D01*
X651881Y512244D01*
X652036Y511976D01*
Y511017D01*
G01Y511976D02*
X653534Y512551D01*
G01X652242Y514156D02*
X651881Y514424D01*
X651674Y514654D01*
X651571Y514961D01*
X651674Y515229D01*
X651881Y515421D01*
X652191Y515574D01*
X652552Y515612D01*
X652862Y515574D01*
X653172Y515421D01*
X653431Y515191D01*
X653534Y514922D01*
X653431Y514616D01*
X653121Y514347D01*
X652656Y514194D01*
X652139Y514156D01*
X651467Y514232D01*
X651106Y514347D01*
X650744Y514539D01*
X650486Y514807D01*
X650434Y515076D01*
X650537Y515344D01*
X650796Y515536D01*
G01X652242Y517256D02*
X651881Y517524D01*
X651674Y517754D01*
X651571Y518061D01*
X651674Y518329D01*
X651881Y518521D01*
X652191Y518674D01*
X652552Y518712D01*
X652862Y518674D01*
X653172Y518521D01*
X653431Y518291D01*
X653534Y518022D01*
X653431Y517716D01*
X653121Y517447D01*
X652656Y517294D01*
X652139Y517256D01*
X651467Y517332D01*
X651106Y517447D01*
X650744Y517639D01*
X650486Y517907D01*
X650434Y518176D01*
X650537Y518444D01*
X650796Y518636D01*
G01X650434Y521084D02*
X650537Y520777D01*
X650796Y520547D01*
X651106Y520394D01*
X651519Y520279D01*
X651984Y520241D01*
X652449Y520279D01*
X652862Y520394D01*
X653172Y520547D01*
X653431Y520777D01*
X653534Y521084D01*
X653431Y521391D01*
X653172Y521621D01*
X652862Y521774D01*
X652449Y521889D01*
X651984Y521927D01*
X651519Y521889D01*
X651106Y521774D01*
X650796Y521621D01*
X650537Y521391D01*
X650434Y521084D01*
G01X649504Y511017D02*
X646404D01*
Y511976D01*
X646559Y512282D01*
X646766Y512474D01*
X647179Y512551D01*
X647592Y512474D01*
X647851Y512244D01*
X648006Y511976D01*
Y511017D01*
G01Y511976D02*
X649504Y512551D01*
G01X648212Y514156D02*
X647851Y514424D01*
X647644Y514654D01*
X647541Y514961D01*
X647644Y515229D01*
X647851Y515421D01*
X648161Y515574D01*
X648522Y515612D01*
X648832Y515574D01*
X649142Y515421D01*
X649401Y515191D01*
X649504Y514922D01*
X649401Y514616D01*
X649091Y514347D01*
X648626Y514194D01*
X648109Y514156D01*
X647437Y514232D01*
X647076Y514347D01*
X646714Y514539D01*
X646456Y514807D01*
X646404Y515076D01*
X646507Y515344D01*
X646766Y515536D01*
G01X646921Y517256D02*
X646611Y517486D01*
X646456Y517754D01*
X646404Y518061D01*
X646507Y518444D01*
X646766Y518712D01*
X647076Y518789D01*
X647386Y518751D01*
X647644Y518597D01*
X648161Y517831D01*
X648522Y517486D01*
X649039Y517256D01*
X649504Y517179D01*
Y518789D01*
G01Y521007D02*
X648832Y521084D01*
X648264Y521199D01*
X647747Y521352D01*
X647179Y521544D01*
X646404Y521851D01*
Y520317D01*
G01X648315Y548884D02*
X648622Y548626D01*
X648967Y548471D01*
X649273D01*
X649580Y548626D01*
X649810Y548884D01*
X649925Y549246D01*
X649848Y549608D01*
X649657Y549918D01*
X649312Y550124D01*
X648852Y550228D01*
X648583Y550434D01*
X648468Y550796D01*
X648545Y551158D01*
X648737Y551416D01*
X649005Y551571D01*
X649273D01*
X649542Y551468D01*
X649772Y551209D01*
G01X652220Y548471D02*
Y551571D01*
X651760Y550951D01*
G01Y548471D02*
X652680D01*
G01X640348Y548470D02*
Y549865D01*
X639581Y551570D01*
G01X641115D02*
X640348Y549865D01*
G01X642605Y548935D02*
X642835Y548677D01*
X643103Y548522D01*
X643448Y548470D01*
X643793Y548573D01*
X644061Y548780D01*
X644253Y549142D01*
X644291Y549555D01*
X644215Y549968D01*
X644023Y550227D01*
X643755Y550433D01*
X643486Y550485D01*
X643218Y550433D01*
X642873Y550227D01*
X642988Y551570D01*
X644023D01*
G01X651137Y565938D02*
Y552552D01*
G01X651201Y580487D02*
Y582987D01*
X650214Y581195D01*
X651548D01*
G01X653081Y580487D02*
X653268Y580529D01*
X653481Y580654D01*
X653614Y580862D01*
X653668Y581154D01*
X653614Y581445D01*
X653454Y581695D01*
X653214Y581820D01*
X652948D01*
X652788Y581904D01*
X652654Y582112D01*
X652601Y582404D01*
X652681Y582695D01*
X652868Y582904D01*
X653081Y582987D01*
X653294Y582904D01*
X653481Y582695D01*
X653561Y582404D01*
X653508Y582112D01*
X653374Y581904D01*
X653214Y581820D01*
X652948D01*
X652708Y581695D01*
X652548Y581445D01*
X652494Y581154D01*
X652548Y580862D01*
X652681Y580654D01*
X652894Y580529D01*
X653081Y580487D01*
G01X640827Y582245D02*
Y580245D01*
G01X637037Y570345D02*
Y567145D01*
G01X640119Y574104D02*
X639889Y574259D01*
X639621Y574362D01*
X639314D01*
X638969Y574207D01*
X638701Y573949D01*
X638509Y573639D01*
X638356Y573122D01*
X638318Y572657D01*
X638394Y572192D01*
X638509Y571882D01*
X638739Y571572D01*
X639008Y571365D01*
X639276Y571262D01*
X639544D01*
X639813Y571365D01*
X640043Y571520D01*
X640234Y571727D01*
G01X642836Y571262D02*
Y574362D01*
X641418Y572140D01*
X643334D01*
G01X644633Y571882D02*
X644863Y571520D01*
X645169Y571314D01*
X645514Y571262D01*
X645821Y571314D01*
X646128Y571572D01*
X646319Y571882D01*
X646358Y572192D01*
X646281Y572554D01*
X646013Y572812D01*
X645744Y572915D01*
X645399D01*
G01X645744D02*
X645974Y573070D01*
X646166Y573329D01*
X646243Y573639D01*
X646166Y573949D01*
X645974Y574207D01*
X645629Y574362D01*
X645284Y574310D01*
X644939Y574104D01*
G01X648499Y571262D02*
X648576Y571934D01*
X648691Y572502D01*
X648844Y573019D01*
X649036Y573587D01*
X649343Y574362D01*
X647809D01*
G01X644537Y567145D02*
X638337D01*
G01X641437Y570245D02*
Y567245D01*
G01X644537Y570345D02*
Y567145D01*
G01X638337D02*
Y570345D01*
G01D02*
X644537D01*
G01X641207Y577212D02*
Y579712D01*
X641873D01*
X642087Y579587D01*
X642220Y579420D01*
X642273Y579087D01*
X642220Y578754D01*
X642060Y578545D01*
X641873Y578420D01*
X641207D01*
G01X641873D02*
X642273Y577212D01*
G01X643353Y577587D02*
X643513Y577379D01*
X643700Y577254D01*
X643940Y577212D01*
X644180Y577295D01*
X644367Y577462D01*
X644500Y577754D01*
X644527Y578087D01*
X644473Y578420D01*
X644340Y578629D01*
X644153Y578795D01*
X643967Y578837D01*
X643780Y578795D01*
X643540Y578629D01*
X643620Y579712D01*
X644340D01*
G01X646140Y577212D02*
X646327Y577254D01*
X646540Y577379D01*
X646673Y577587D01*
X646727Y577879D01*
X646673Y578170D01*
X646513Y578420D01*
X646273Y578545D01*
X646007D01*
X645847Y578629D01*
X645713Y578837D01*
X645660Y579129D01*
X645740Y579420D01*
X645927Y579629D01*
X646140Y579712D01*
X646353Y579629D01*
X646540Y579420D01*
X646620Y579129D01*
X646567Y578837D01*
X646433Y578629D01*
X646273Y578545D01*
X646007D01*
X645767Y578420D01*
X645607Y578170D01*
X645553Y577879D01*
X645607Y577587D01*
X645740Y577379D01*
X645953Y577254D01*
X646140Y577212D01*
G01X647887Y577504D02*
X648073Y577295D01*
X648287Y577212D01*
X648500Y577295D01*
X648687Y577545D01*
X648820Y577920D01*
X648873Y578295D01*
Y578754D01*
X648820Y579129D01*
X648687Y579462D01*
X648527Y579629D01*
X648340Y579712D01*
X648127Y579629D01*
X647967Y579462D01*
X647860Y579212D01*
X647807Y578879D01*
X647860Y578587D01*
X647993Y578295D01*
X648153Y578129D01*
X648340Y578087D01*
X648553Y578170D01*
X648713Y578379D01*
X648873Y578754D01*
G01X649837Y571045D02*
Y577245D01*
G01D02*
X653037D01*
G01Y571045D02*
X649837D01*
G01X651654Y585028D02*
X649737D01*
G01X651654Y586845D02*
Y585028D01*
G01X649704Y620412D02*
X651604Y618512D01*
G01X640827Y623245D02*
Y625245D01*
G01X649701Y643472D02*
Y646672D01*
G01X655901Y643472D02*
X649701D01*
G01X641137Y632317D02*
Y638517D01*
G01D02*
X644337D01*
G01D02*
Y632317D01*
G01D02*
X641137D01*
G01X645137Y638517D02*
X648337D01*
G01D02*
Y632317D01*
G01D02*
X645137D01*
G01D02*
Y638517D01*
G01X649370Y632215D02*
Y638415D01*
G01D02*
X652570D01*
G01Y632215D02*
X649370D01*
G01X640070Y638415D02*
Y632215D01*
G01X636870D02*
Y638415D01*
G01D02*
X640070D01*
G01Y632215D02*
X636870D01*
G01X649701Y658892D02*
Y662092D01*
G01X655901Y658892D02*
X649701D01*
G01Y656672D02*
X655901D01*
G01X649701Y653472D02*
Y656672D01*
G01X655901Y653472D02*
X649701D01*
G01Y648472D02*
Y651672D01*
G01D02*
X655901D01*
G01Y648472D02*
X649701D01*
G01Y646672D02*
X655901D01*
G01X638187Y670637D02*
Y668415D01*
X638340Y667950D01*
X638647Y667640D01*
X639030Y667537D01*
X639413Y667640D01*
X639720Y667950D01*
X639873Y668415D01*
Y670637D01*
G01X641287Y668002D02*
X641517Y667744D01*
X641785Y667589D01*
X642130Y667537D01*
X642475Y667640D01*
X642743Y667847D01*
X642935Y668209D01*
X642973Y668622D01*
X642897Y669035D01*
X642705Y669294D01*
X642437Y669500D01*
X642168Y669552D01*
X641900Y669500D01*
X641555Y669294D01*
X641670Y670637D01*
X642705D01*
G01X645153Y667537D02*
X645230Y668209D01*
X645345Y668777D01*
X645498Y669294D01*
X645690Y669862D01*
X645997Y670637D01*
X644463D01*
G01X645963Y675234D02*
G02I-1000J0D01*
G01X641263Y672934D02*
X638963Y675234D01*
G01X646863Y672934D02*
X641263D01*
G01X646863Y711534D02*
Y672934D01*
G01X649701Y662092D02*
X655901D01*
G01X652751Y715075D02*
X646551D01*
G01D02*
Y718273D01*
G01D02*
X652751D01*
G01X646551Y719074D02*
Y722274D01*
G01X652751Y719074D02*
X646551D01*
G01Y722274D02*
X652751D01*
G01Y723074D02*
X646551D01*
G01D02*
Y726274D01*
G01D02*
X652751D01*
G01X646551Y727074D02*
Y730274D01*
G01X652751Y727074D02*
X646551D01*
G01Y730274D02*
X652751D01*
G01X638730Y743580D02*
Y737380D01*
G01X645100Y743600D02*
Y737400D01*
X641900D01*
Y743600D01*
X645100D01*
G01X643083Y745267D02*
X639983D01*
Y746226D01*
X640138Y746532D01*
X640345Y746724D01*
X640758Y746801D01*
X641171Y746724D01*
X641430Y746494D01*
X641585Y746226D01*
Y745267D01*
G01Y746226D02*
X643083Y746801D01*
G01Y749134D02*
X639983D01*
X640603Y748674D01*
G01X643083D02*
Y749594D01*
G01X640500Y751506D02*
X640190Y751736D01*
X640035Y752004D01*
X639983Y752311D01*
X640086Y752694D01*
X640345Y752962D01*
X640655Y753039D01*
X640965Y753001D01*
X641223Y752847D01*
X641740Y752081D01*
X642101Y751736D01*
X642618Y751506D01*
X643083Y751429D01*
Y753039D01*
G01X640500Y754606D02*
X640190Y754836D01*
X640035Y755104D01*
X639983Y755411D01*
X640086Y755794D01*
X640345Y756062D01*
X640655Y756139D01*
X640965Y756101D01*
X641223Y755947D01*
X641740Y755181D01*
X642101Y754836D01*
X642618Y754606D01*
X643083Y754529D01*
Y756139D01*
G01X640500Y757706D02*
X640190Y757936D01*
X640035Y758204D01*
X639983Y758511D01*
X640086Y758894D01*
X640345Y759162D01*
X640655Y759239D01*
X640965Y759201D01*
X641223Y759047D01*
X641740Y758281D01*
X642101Y757936D01*
X642618Y757706D01*
X643083Y757629D01*
Y759239D01*
G01X651000Y745483D02*
X647900D01*
Y746442D01*
X648055Y746748D01*
X648262Y746940D01*
X648675Y747017D01*
X649088Y746940D01*
X649347Y746710D01*
X649502Y746442D01*
Y745483D01*
G01Y746442D02*
X651000Y747017D01*
G01Y749350D02*
X647900D01*
X648520Y748890D01*
G01X651000D02*
Y749810D01*
G01X650380Y751607D02*
X650742Y751837D01*
X650948Y752143D01*
X651000Y752488D01*
X650948Y752795D01*
X650690Y753102D01*
X650380Y753293D01*
X650070Y753332D01*
X649708Y753255D01*
X649450Y752987D01*
X649347Y752718D01*
Y752373D01*
G01Y752718D02*
X649192Y752948D01*
X648933Y753140D01*
X648623Y753217D01*
X648313Y753140D01*
X648055Y752948D01*
X647900Y752603D01*
X647952Y752258D01*
X648158Y751913D01*
G01X650380Y754707D02*
X650742Y754937D01*
X650948Y755243D01*
X651000Y755588D01*
X650948Y755895D01*
X650690Y756202D01*
X650380Y756393D01*
X650070Y756432D01*
X649708Y756355D01*
X649450Y756087D01*
X649347Y755818D01*
Y755473D01*
G01Y755818D02*
X649192Y756048D01*
X648933Y756240D01*
X648623Y756317D01*
X648313Y756240D01*
X648055Y756048D01*
X647900Y755703D01*
X647952Y755358D01*
X648158Y755013D01*
G01X651000Y759110D02*
X647900D01*
X650122Y757692D01*
Y759608D01*
G01X662183Y12870D02*
Y19553D01*
X662204D01*
X664397Y17360D01*
X664376Y17339D01*
X659548D01*
X661783Y19574D01*
X662120D01*
G01X667450Y45793D02*
X664350D01*
Y46752D01*
X664505Y47058D01*
X664712Y47250D01*
X665125Y47327D01*
X665538Y47250D01*
X665797Y47020D01*
X665952Y46752D01*
Y45793D01*
G01Y46752D02*
X667450Y47327D01*
G01Y49660D02*
X664350D01*
X664970Y49200D01*
G01X667450D02*
Y50120D01*
G01Y52760D02*
X664350D01*
X664970Y52300D01*
G01X667450D02*
Y53220D01*
G01X667088Y55208D02*
X667347Y55477D01*
X667450Y55783D01*
X667347Y56090D01*
X667037Y56358D01*
X666572Y56550D01*
X666107Y56627D01*
X665538D01*
X665073Y56550D01*
X664660Y56358D01*
X664453Y56128D01*
X664350Y55860D01*
X664453Y55553D01*
X664660Y55323D01*
X664970Y55170D01*
X665383Y55093D01*
X665745Y55170D01*
X666107Y55362D01*
X666313Y55592D01*
X666365Y55860D01*
X666262Y56167D01*
X666003Y56397D01*
X665538Y56627D01*
G01X667088Y58308D02*
X667347Y58577D01*
X667450Y58883D01*
X667347Y59190D01*
X667037Y59458D01*
X666572Y59650D01*
X666107Y59727D01*
X665538D01*
X665073Y59650D01*
X664660Y59458D01*
X664453Y59228D01*
X664350Y58960D01*
X664453Y58653D01*
X664660Y58423D01*
X664970Y58270D01*
X665383Y58193D01*
X665745Y58270D01*
X666107Y58462D01*
X666313Y58692D01*
X666365Y58960D01*
X666262Y59267D01*
X666003Y59497D01*
X665538Y59727D01*
G01X654347Y46081D02*
Y52281D01*
G01X657547D02*
Y46081D01*
G01D02*
X654347D01*
G01Y52281D02*
X657547D01*
G01X661547D02*
Y46081D01*
G01D02*
X658347D01*
G01D02*
Y52281D01*
G01D02*
X661547D01*
G01X658166Y134429D02*
X661266D01*
Y135963D01*
G01Y138756D02*
X658166D01*
X660388Y137338D01*
Y139254D01*
G01X658683Y140668D02*
X658373Y140898D01*
X658218Y141166D01*
X658166Y141473D01*
X658269Y141856D01*
X658528Y142124D01*
X658838Y142201D01*
X659148Y142163D01*
X659406Y142009D01*
X659923Y141243D01*
X660284Y140898D01*
X660801Y140668D01*
X661266Y140591D01*
Y142201D01*
G01X662405Y139360D02*
Y142460D01*
X663364D01*
X663670Y142305D01*
X663862Y142098D01*
X663939Y141685D01*
X663862Y141272D01*
X663632Y141013D01*
X663364Y140858D01*
X662405D01*
G01X663364D02*
X663939Y139360D01*
G01X665544Y141943D02*
X665774Y142253D01*
X666042Y142408D01*
X666349Y142460D01*
X666732Y142357D01*
X667000Y142098D01*
X667077Y141788D01*
X667039Y141478D01*
X666885Y141220D01*
X666119Y140703D01*
X665774Y140342D01*
X665544Y139825D01*
X665467Y139360D01*
X667077D01*
G01X668644Y140652D02*
X668912Y141013D01*
X669142Y141220D01*
X669449Y141323D01*
X669717Y141220D01*
X669909Y141013D01*
X670062Y140703D01*
X670100Y140342D01*
X670062Y140032D01*
X669909Y139722D01*
X669679Y139463D01*
X669410Y139360D01*
X669104Y139463D01*
X668835Y139773D01*
X668682Y140238D01*
X668644Y140755D01*
X668720Y141427D01*
X668835Y141788D01*
X669027Y142150D01*
X669295Y142408D01*
X669564Y142460D01*
X669832Y142357D01*
X670024Y142098D01*
G01X672932Y139360D02*
Y142460D01*
X671514Y140238D01*
X673430D01*
G01X662405Y135360D02*
Y138460D01*
X663364D01*
X663670Y138305D01*
X663862Y138098D01*
X663939Y137685D01*
X663862Y137272D01*
X663632Y137013D01*
X663364Y136858D01*
X662405D01*
G01X663364D02*
X663939Y135360D01*
G01X665544Y137943D02*
X665774Y138253D01*
X666042Y138408D01*
X666349Y138460D01*
X666732Y138357D01*
X667000Y138098D01*
X667077Y137788D01*
X667039Y137478D01*
X666885Y137220D01*
X666119Y136703D01*
X665774Y136342D01*
X665544Y135825D01*
X665467Y135360D01*
X667077D01*
G01X668644Y136652D02*
X668912Y137013D01*
X669142Y137220D01*
X669449Y137323D01*
X669717Y137220D01*
X669909Y137013D01*
X670062Y136703D01*
X670100Y136342D01*
X670062Y136032D01*
X669909Y135722D01*
X669679Y135463D01*
X669410Y135360D01*
X669104Y135463D01*
X668835Y135773D01*
X668682Y136238D01*
X668644Y136755D01*
X668720Y137427D01*
X668835Y137788D01*
X669027Y138150D01*
X669295Y138408D01*
X669564Y138460D01*
X669832Y138357D01*
X670024Y138098D01*
G01X671629Y135825D02*
X671859Y135567D01*
X672127Y135412D01*
X672472Y135360D01*
X672817Y135463D01*
X673085Y135670D01*
X673277Y136032D01*
X673315Y136445D01*
X673239Y136858D01*
X673047Y137117D01*
X672779Y137323D01*
X672510Y137375D01*
X672242Y137323D01*
X671897Y137117D01*
X672012Y138460D01*
X673047D01*
G01X663360Y156784D02*
Y153684D01*
X664894D01*
G01X667687D02*
Y156784D01*
X666269Y154562D01*
X668185D01*
G01X669484Y154304D02*
X669714Y153942D01*
X670020Y153736D01*
X670365Y153684D01*
X670672Y153736D01*
X670979Y153994D01*
X671170Y154304D01*
X671209Y154614D01*
X671132Y154976D01*
X670864Y155234D01*
X670595Y155337D01*
X670250D01*
G01X670595D02*
X670825Y155492D01*
X671017Y155751D01*
X671094Y156061D01*
X671017Y156371D01*
X670825Y156629D01*
X670480Y156784D01*
X670135Y156732D01*
X669790Y156526D01*
G01X660072Y143467D02*
Y151361D01*
G01X675872Y143467D02*
X660072D01*
G01Y151361D02*
X675872D01*
G01X664811Y147828D02*
Y151028D01*
G01X671011Y147828D02*
X664811D01*
G01Y151028D02*
X671011D01*
G01X664811Y143828D02*
Y147028D01*
G01X671011Y143828D02*
X664811D01*
G01Y147028D02*
X671011D01*
G01X660285Y158070D02*
Y165964D01*
G01X676085Y158070D02*
X660285D01*
G01Y165964D02*
X676085D01*
G01X663966Y171233D02*
Y174333D01*
X664925D01*
X665231Y174178D01*
X665423Y173971D01*
X665500Y173558D01*
X665423Y173145D01*
X665193Y172886D01*
X664925Y172731D01*
X663966D01*
G01X664925D02*
X665500Y171233D01*
G01X667105Y173816D02*
X667335Y174126D01*
X667603Y174281D01*
X667910Y174333D01*
X668293Y174230D01*
X668561Y173971D01*
X668638Y173661D01*
X668600Y173351D01*
X668446Y173093D01*
X667680Y172576D01*
X667335Y172215D01*
X667105Y171698D01*
X667028Y171233D01*
X668638D01*
G01X670205Y172525D02*
X670473Y172886D01*
X670703Y173093D01*
X671010Y173196D01*
X671278Y173093D01*
X671470Y172886D01*
X671623Y172576D01*
X671661Y172215D01*
X671623Y171905D01*
X671470Y171595D01*
X671240Y171336D01*
X670971Y171233D01*
X670665Y171336D01*
X670396Y171646D01*
X670243Y172111D01*
X670205Y172628D01*
X670281Y173300D01*
X670396Y173661D01*
X670588Y174023D01*
X670856Y174281D01*
X671125Y174333D01*
X671393Y174230D01*
X671585Y173971D01*
G01X673305Y172525D02*
X673573Y172886D01*
X673803Y173093D01*
X674110Y173196D01*
X674378Y173093D01*
X674570Y172886D01*
X674723Y172576D01*
X674761Y172215D01*
X674723Y171905D01*
X674570Y171595D01*
X674340Y171336D01*
X674071Y171233D01*
X673765Y171336D01*
X673496Y171646D01*
X673343Y172111D01*
X673305Y172628D01*
X673381Y173300D01*
X673496Y173661D01*
X673688Y174023D01*
X673956Y174281D01*
X674225Y174333D01*
X674493Y174230D01*
X674685Y173971D01*
G01X665124Y162491D02*
Y165691D01*
G01X671324Y162491D02*
X665124D01*
G01Y165691D02*
X671324D01*
G01X663966Y167233D02*
Y170333D01*
X664925D01*
X665231Y170178D01*
X665423Y169971D01*
X665500Y169558D01*
X665423Y169145D01*
X665193Y168886D01*
X664925Y168731D01*
X663966D01*
G01X664925D02*
X665500Y167233D01*
G01X667105Y169816D02*
X667335Y170126D01*
X667603Y170281D01*
X667910Y170333D01*
X668293Y170230D01*
X668561Y169971D01*
X668638Y169661D01*
X668600Y169351D01*
X668446Y169093D01*
X667680Y168576D01*
X667335Y168215D01*
X667105Y167698D01*
X667028Y167233D01*
X668638D01*
G01X670205Y168525D02*
X670473Y168886D01*
X670703Y169093D01*
X671010Y169196D01*
X671278Y169093D01*
X671470Y168886D01*
X671623Y168576D01*
X671661Y168215D01*
X671623Y167905D01*
X671470Y167595D01*
X671240Y167336D01*
X670971Y167233D01*
X670665Y167336D01*
X670396Y167646D01*
X670243Y168111D01*
X670205Y168628D01*
X670281Y169300D01*
X670396Y169661D01*
X670588Y170023D01*
X670856Y170281D01*
X671125Y170333D01*
X671393Y170230D01*
X671585Y169971D01*
G01X673956Y167233D02*
X674033Y167905D01*
X674148Y168473D01*
X674301Y168990D01*
X674493Y169558D01*
X674800Y170333D01*
X673266D01*
G01X665124Y158491D02*
Y161691D01*
G01X671324Y158491D02*
X665124D01*
G01Y161691D02*
X671324D01*
G01X660082Y182259D02*
X659852Y182414D01*
X659584Y182517D01*
X659277D01*
X658932Y182362D01*
X658664Y182104D01*
X658472Y181794D01*
X658319Y181277D01*
X658281Y180812D01*
X658357Y180347D01*
X658472Y180037D01*
X658702Y179727D01*
X658971Y179520D01*
X659239Y179417D01*
X659507D01*
X659776Y179520D01*
X660006Y179675D01*
X660197Y179882D01*
G01X661496D02*
X661726Y179624D01*
X661994Y179469D01*
X662339Y179417D01*
X662684Y179520D01*
X662952Y179727D01*
X663144Y180089D01*
X663182Y180502D01*
X663106Y180915D01*
X662914Y181174D01*
X662646Y181380D01*
X662377Y181432D01*
X662109Y181380D01*
X661764Y181174D01*
X661879Y182517D01*
X662914D01*
G01X664596Y180037D02*
X664826Y179675D01*
X665132Y179469D01*
X665477Y179417D01*
X665784Y179469D01*
X666091Y179727D01*
X666282Y180037D01*
X666321Y180347D01*
X666244Y180709D01*
X665976Y180967D01*
X665707Y181070D01*
X665362D01*
G01X665707D02*
X665937Y181225D01*
X666129Y181484D01*
X666206Y181794D01*
X666129Y182104D01*
X665937Y182362D01*
X665592Y182517D01*
X665247Y182465D01*
X664902Y182259D01*
G01X667696Y179882D02*
X667926Y179624D01*
X668194Y179469D01*
X668539Y179417D01*
X668884Y179520D01*
X669152Y179727D01*
X669344Y180089D01*
X669382Y180502D01*
X669306Y180915D01*
X669114Y181174D01*
X668846Y181380D01*
X668577Y181432D01*
X668309Y181380D01*
X667964Y181174D01*
X668079Y182517D01*
X669114D01*
G01X660082Y186153D02*
X659852Y186308D01*
X659584Y186411D01*
X659277D01*
X658932Y186256D01*
X658664Y185998D01*
X658472Y185688D01*
X658319Y185171D01*
X658281Y184706D01*
X658357Y184241D01*
X658472Y183931D01*
X658702Y183621D01*
X658971Y183414D01*
X659239Y183311D01*
X659507D01*
X659776Y183414D01*
X660006Y183569D01*
X660197Y183776D01*
G01X661496D02*
X661726Y183518D01*
X661994Y183363D01*
X662339Y183311D01*
X662684Y183414D01*
X662952Y183621D01*
X663144Y183983D01*
X663182Y184396D01*
X663106Y184809D01*
X662914Y185068D01*
X662646Y185274D01*
X662377Y185326D01*
X662109Y185274D01*
X661764Y185068D01*
X661879Y186411D01*
X662914D01*
G01X664596Y183776D02*
X664826Y183518D01*
X665094Y183363D01*
X665439Y183311D01*
X665784Y183414D01*
X666052Y183621D01*
X666244Y183983D01*
X666282Y184396D01*
X666206Y184809D01*
X666014Y185068D01*
X665746Y185274D01*
X665477Y185326D01*
X665209Y185274D01*
X664864Y185068D01*
X664979Y186411D01*
X666014D01*
G01X667887Y183673D02*
X668156Y183414D01*
X668462Y183311D01*
X668769Y183414D01*
X669037Y183724D01*
X669229Y184189D01*
X669306Y184654D01*
Y185223D01*
X669229Y185688D01*
X669037Y186101D01*
X668807Y186308D01*
X668539Y186411D01*
X668232Y186308D01*
X668002Y186101D01*
X667849Y185791D01*
X667772Y185378D01*
X667849Y185016D01*
X668041Y184654D01*
X668271Y184448D01*
X668539Y184396D01*
X668846Y184499D01*
X669076Y184758D01*
X669306Y185223D01*
G01X655856Y197510D02*
X655701Y197280D01*
X655598Y197012D01*
Y196705D01*
X655753Y196360D01*
X656011Y196092D01*
X656321Y195900D01*
X656838Y195747D01*
X657303Y195709D01*
X657768Y195785D01*
X658078Y195900D01*
X658388Y196130D01*
X658595Y196399D01*
X658698Y196667D01*
Y196935D01*
X658595Y197204D01*
X658440Y197434D01*
X658233Y197625D01*
G01X658698Y200534D02*
Y199000D01*
X655598D01*
Y200534D01*
G01X657096Y199920D02*
Y199000D01*
G01X658078Y202024D02*
X658440Y202254D01*
X658646Y202560D01*
X658698Y202905D01*
X658646Y203212D01*
X658388Y203519D01*
X658078Y203710D01*
X657768Y203749D01*
X657406Y203672D01*
X657148Y203404D01*
X657045Y203135D01*
Y202790D01*
G01Y203135D02*
X656890Y203365D01*
X656631Y203557D01*
X656321Y203634D01*
X656011Y203557D01*
X655753Y203365D01*
X655598Y203020D01*
X655650Y202675D01*
X655856Y202330D01*
G01X663291Y219900D02*
Y198246D01*
G01D02*
X680945D01*
G01X665930Y196515D02*
X680930D01*
G01Y189715D02*
X665930D01*
G01D02*
Y196515D01*
G01X657011Y209923D02*
X657171Y210173D01*
X657358Y210298D01*
X657571Y210340D01*
X657838Y210257D01*
X658025Y210048D01*
X658078Y209798D01*
X658051Y209548D01*
X657945Y209340D01*
X657411Y208923D01*
X657171Y208632D01*
X657011Y208215D01*
X656958Y207840D01*
X658078D01*
G01X659906Y222273D02*
Y230167D01*
G01X675706Y222273D02*
X659906D01*
G01Y230167D02*
X675706D01*
G01X680945Y219900D02*
X663291D01*
G01X664788Y226735D02*
Y229935D01*
G01X670988Y226735D02*
X664788D01*
G01Y229935D02*
X670988D01*
G01X664788Y222735D02*
Y225935D01*
G01X670988Y222735D02*
X664788D01*
G01Y225935D02*
X670988D01*
G01X663013Y246204D02*
X666113D01*
Y247738D01*
G01Y250531D02*
X663013D01*
X665235Y249113D01*
Y251029D01*
G01X665648Y252328D02*
X665906Y252558D01*
X666061Y252826D01*
X666113Y253171D01*
X666010Y253516D01*
X665803Y253784D01*
X665441Y253976D01*
X665028Y254014D01*
X664615Y253938D01*
X664356Y253746D01*
X664150Y253478D01*
X664098Y253209D01*
X664150Y252941D01*
X664356Y252596D01*
X663013Y252711D01*
Y253746D01*
G01X660520Y236876D02*
Y244770D01*
G01X676320Y236876D02*
X660520D01*
G01Y244770D02*
X676320D01*
G01X667173Y250188D02*
Y253288D01*
X668132D01*
X668438Y253133D01*
X668630Y252926D01*
X668707Y252513D01*
X668630Y252100D01*
X668400Y251841D01*
X668132Y251686D01*
X667173D01*
G01X668132D02*
X668707Y250188D01*
G01X670312Y252771D02*
X670542Y253081D01*
X670810Y253236D01*
X671117Y253288D01*
X671500Y253185D01*
X671768Y252926D01*
X671845Y252616D01*
X671807Y252306D01*
X671653Y252048D01*
X670887Y251531D01*
X670542Y251170D01*
X670312Y250653D01*
X670235Y250188D01*
X671845D01*
G01X674063D02*
X674140Y250860D01*
X674255Y251428D01*
X674408Y251945D01*
X674600Y252513D01*
X674907Y253288D01*
X673373D01*
G01X677240D02*
X676933Y253185D01*
X676703Y252926D01*
X676550Y252616D01*
X676435Y252203D01*
X676397Y251738D01*
X676435Y251273D01*
X676550Y250860D01*
X676703Y250550D01*
X676933Y250291D01*
X677240Y250188D01*
X677547Y250291D01*
X677777Y250550D01*
X677930Y250860D01*
X678045Y251273D01*
X678083Y251738D01*
X678045Y252203D01*
X677930Y252616D01*
X677777Y252926D01*
X677547Y253185D01*
X677240Y253288D01*
G01X665374Y241245D02*
Y244445D01*
G01X671574Y241245D02*
X665374D01*
G01Y244445D02*
X671574D01*
G01X667173Y246188D02*
Y249288D01*
X668132D01*
X668438Y249133D01*
X668630Y248926D01*
X668707Y248513D01*
X668630Y248100D01*
X668400Y247841D01*
X668132Y247686D01*
X667173D01*
G01X668132D02*
X668707Y246188D01*
G01X670312Y248771D02*
X670542Y249081D01*
X670810Y249236D01*
X671117Y249288D01*
X671500Y249185D01*
X671768Y248926D01*
X671845Y248616D01*
X671807Y248306D01*
X671653Y248048D01*
X670887Y247531D01*
X670542Y247170D01*
X670312Y246653D01*
X670235Y246188D01*
X671845D01*
G01X674063D02*
X674140Y246860D01*
X674255Y247428D01*
X674408Y247945D01*
X674600Y248513D01*
X674907Y249288D01*
X673373D01*
G01X677240Y246188D02*
Y249288D01*
X676780Y248668D01*
G01Y246188D02*
X677700D01*
G01X665374Y237245D02*
Y240445D01*
G01X671574Y237245D02*
X665374D01*
G01Y240445D02*
X671574D01*
G01X671096Y267316D02*
X667996D01*
Y268275D01*
X668151Y268581D01*
X668358Y268773D01*
X668771Y268850D01*
X669184Y268773D01*
X669443Y268543D01*
X669598Y268275D01*
Y267316D01*
G01Y268275D02*
X671096Y268850D01*
G01Y271183D02*
X667996D01*
X668616Y270723D01*
G01X671096D02*
Y271643D01*
G01X667996Y274283D02*
X668099Y273976D01*
X668358Y273746D01*
X668668Y273593D01*
X669081Y273478D01*
X669546Y273440D01*
X670011Y273478D01*
X670424Y273593D01*
X670734Y273746D01*
X670993Y273976D01*
X671096Y274283D01*
X670993Y274590D01*
X670734Y274820D01*
X670424Y274973D01*
X670011Y275088D01*
X669546Y275126D01*
X669081Y275088D01*
X668668Y274973D01*
X668358Y274820D01*
X668099Y274590D01*
X667996Y274283D01*
G01X668513Y276655D02*
X668203Y276885D01*
X668048Y277153D01*
X667996Y277460D01*
X668099Y277843D01*
X668358Y278111D01*
X668668Y278188D01*
X668978Y278150D01*
X669236Y277996D01*
X669753Y277230D01*
X670114Y276885D01*
X670631Y276655D01*
X671096Y276578D01*
Y278188D01*
G01X667996Y280483D02*
X668099Y280176D01*
X668358Y279946D01*
X668668Y279793D01*
X669081Y279678D01*
X669546Y279640D01*
X670011Y279678D01*
X670424Y279793D01*
X670734Y279946D01*
X670993Y280176D01*
X671096Y280483D01*
X670993Y280790D01*
X670734Y281020D01*
X670424Y281173D01*
X670011Y281288D01*
X669546Y281326D01*
X669081Y281288D01*
X668668Y281173D01*
X668358Y281020D01*
X668099Y280790D01*
X667996Y280483D01*
G01X662700Y267183D02*
X659600D01*
Y268142D01*
X659755Y268448D01*
X659962Y268640D01*
X660375Y268717D01*
X660788Y268640D01*
X661047Y268410D01*
X661202Y268142D01*
Y267183D01*
G01Y268142D02*
X662700Y268717D01*
G01Y271050D02*
X659600D01*
X660220Y270590D01*
G01X662700D02*
Y271510D01*
G01Y274150D02*
X659600D01*
X660220Y273690D01*
G01X662700D02*
Y274610D01*
G01X662235Y276407D02*
X662493Y276637D01*
X662648Y276905D01*
X662700Y277250D01*
X662597Y277595D01*
X662390Y277863D01*
X662028Y278055D01*
X661615Y278093D01*
X661202Y278017D01*
X660943Y277825D01*
X660737Y277557D01*
X660685Y277288D01*
X660737Y277020D01*
X660943Y276675D01*
X659600Y276790D01*
Y277825D01*
G01X662235Y279507D02*
X662493Y279737D01*
X662648Y280005D01*
X662700Y280350D01*
X662597Y280695D01*
X662390Y280963D01*
X662028Y281155D01*
X661615Y281193D01*
X661202Y281117D01*
X660943Y280925D01*
X660737Y280657D01*
X660685Y280388D01*
X660737Y280120D01*
X660943Y279775D01*
X659600Y279890D01*
Y280925D01*
G01X658700Y267083D02*
X655600D01*
Y268042D01*
X655755Y268348D01*
X655962Y268540D01*
X656375Y268617D01*
X656788Y268540D01*
X657047Y268310D01*
X657202Y268042D01*
Y267083D01*
G01Y268042D02*
X658700Y268617D01*
G01Y270950D02*
X655600D01*
X656220Y270490D01*
G01X658700D02*
Y271410D01*
G01Y274050D02*
X655600D01*
X656220Y273590D01*
G01X658700D02*
Y274510D01*
G01X658235Y276307D02*
X658493Y276537D01*
X658648Y276805D01*
X658700Y277150D01*
X658597Y277495D01*
X658390Y277763D01*
X658028Y277955D01*
X657615Y277993D01*
X657202Y277917D01*
X656943Y277725D01*
X656737Y277457D01*
X656685Y277188D01*
X656737Y276920D01*
X656943Y276575D01*
X655600Y276690D01*
Y277725D01*
G01X658700Y280173D02*
X658028Y280250D01*
X657460Y280365D01*
X656943Y280518D01*
X656375Y280710D01*
X655600Y281017D01*
Y279483D01*
G01X666800Y267383D02*
X663700D01*
Y268342D01*
X663855Y268648D01*
X664062Y268840D01*
X664475Y268917D01*
X664888Y268840D01*
X665147Y268610D01*
X665302Y268342D01*
Y267383D01*
G01Y268342D02*
X666800Y268917D01*
G01Y271173D02*
X666128Y271250D01*
X665560Y271365D01*
X665043Y271518D01*
X664475Y271710D01*
X663700Y272017D01*
Y270483D01*
G01X666800Y274273D02*
X666128Y274350D01*
X665560Y274465D01*
X665043Y274618D01*
X664475Y274810D01*
X663700Y275117D01*
Y273583D01*
G01X666800Y277373D02*
X666128Y277450D01*
X665560Y277565D01*
X665043Y277718D01*
X664475Y277910D01*
X663700Y278217D01*
Y276683D01*
G01X659441Y291249D02*
X659211Y291404D01*
X658943Y291507D01*
X658636D01*
X658291Y291352D01*
X658023Y291094D01*
X657831Y290784D01*
X657678Y290267D01*
X657640Y289802D01*
X657716Y289337D01*
X657831Y289027D01*
X658061Y288717D01*
X658330Y288510D01*
X658598Y288407D01*
X658866D01*
X659135Y288510D01*
X659365Y288665D01*
X659556Y288872D01*
G01X661698Y288407D02*
X661966Y288459D01*
X662273Y288614D01*
X662465Y288872D01*
X662541Y289234D01*
X662465Y289595D01*
X662235Y289905D01*
X661890Y290060D01*
X661506D01*
X661276Y290164D01*
X661085Y290422D01*
X661008Y290784D01*
X661123Y291145D01*
X661391Y291404D01*
X661698Y291507D01*
X662005Y291404D01*
X662273Y291145D01*
X662388Y290784D01*
X662311Y290422D01*
X662120Y290164D01*
X661890Y290060D01*
X661506D01*
X661161Y289905D01*
X660931Y289595D01*
X660855Y289234D01*
X660931Y288872D01*
X661123Y288614D01*
X661430Y288459D01*
X661698Y288407D01*
G01X663955Y288872D02*
X664185Y288614D01*
X664453Y288459D01*
X664798Y288407D01*
X665143Y288510D01*
X665411Y288717D01*
X665603Y289079D01*
X665641Y289492D01*
X665565Y289905D01*
X665373Y290164D01*
X665105Y290370D01*
X664836Y290422D01*
X664568Y290370D01*
X664223Y290164D01*
X664338Y291507D01*
X665373D01*
G01X667170Y290990D02*
X667400Y291300D01*
X667668Y291455D01*
X667975Y291507D01*
X668358Y291404D01*
X668626Y291145D01*
X668703Y290835D01*
X668665Y290525D01*
X668511Y290267D01*
X667745Y289750D01*
X667400Y289389D01*
X667170Y288872D01*
X667093Y288407D01*
X668703D01*
G01X654952Y289858D02*
Y283658D01*
G01X657858Y284263D02*
Y287363D01*
X658778D01*
X659085Y287208D01*
X659315Y286846D01*
X659392Y286433D01*
X659315Y286020D01*
X659123Y285710D01*
X658778Y285555D01*
X657858D01*
G01X660958Y284883D02*
X661150Y284573D01*
X661380Y284366D01*
X661648Y284263D01*
X661955Y284366D01*
X662185Y284573D01*
X662415Y284883D01*
X662492Y285296D01*
Y287363D01*
G01X663982Y284883D02*
X664212Y284521D01*
X664518Y284315D01*
X664863Y284263D01*
X665170Y284315D01*
X665477Y284573D01*
X665668Y284883D01*
X665707Y285193D01*
X665630Y285555D01*
X665362Y285813D01*
X665093Y285916D01*
X664748D01*
G01X665093D02*
X665323Y286071D01*
X665515Y286330D01*
X665592Y286640D01*
X665515Y286950D01*
X665323Y287208D01*
X664978Y287363D01*
X664633Y287311D01*
X664288Y287105D01*
G01X669878Y301044D02*
X654878D01*
G01Y307844D02*
X669878D01*
G01X662378Y307744D02*
Y301144D01*
G01X654878Y301044D02*
Y307844D01*
G01X664774Y313064D02*
X664544Y313219D01*
X664276Y313322D01*
X663969D01*
X663624Y313167D01*
X663356Y312909D01*
X663164Y312599D01*
X663011Y312082D01*
X662973Y311617D01*
X663049Y311152D01*
X663164Y310842D01*
X663394Y310532D01*
X663663Y310325D01*
X663931Y310222D01*
X664199D01*
X664468Y310325D01*
X664698Y310480D01*
X664889Y310687D01*
G01X667031Y310222D02*
X667299Y310274D01*
X667606Y310429D01*
X667798Y310687D01*
X667874Y311049D01*
X667798Y311410D01*
X667568Y311720D01*
X667223Y311875D01*
X666839D01*
X666609Y311979D01*
X666418Y312237D01*
X666341Y312599D01*
X666456Y312960D01*
X666724Y313219D01*
X667031Y313322D01*
X667338Y313219D01*
X667606Y312960D01*
X667721Y312599D01*
X667644Y312237D01*
X667453Y311979D01*
X667223Y311875D01*
X666839D01*
X666494Y311720D01*
X666264Y311410D01*
X666188Y311049D01*
X666264Y310687D01*
X666456Y310429D01*
X666763Y310274D01*
X667031Y310222D01*
G01X670131D02*
X670399Y310274D01*
X670706Y310429D01*
X670898Y310687D01*
X670974Y311049D01*
X670898Y311410D01*
X670668Y311720D01*
X670323Y311875D01*
X669939D01*
X669709Y311979D01*
X669518Y312237D01*
X669441Y312599D01*
X669556Y312960D01*
X669824Y313219D01*
X670131Y313322D01*
X670438Y313219D01*
X670706Y312960D01*
X670821Y312599D01*
X670744Y312237D01*
X670553Y311979D01*
X670323Y311875D01*
X669939D01*
X669594Y311720D01*
X669364Y311410D01*
X669288Y311049D01*
X669364Y310687D01*
X669556Y310429D01*
X669863Y310274D01*
X670131Y310222D01*
G01X672388Y310842D02*
X672618Y310480D01*
X672924Y310274D01*
X673269Y310222D01*
X673576Y310274D01*
X673883Y310532D01*
X674074Y310842D01*
X674113Y311152D01*
X674036Y311514D01*
X673768Y311772D01*
X673499Y311875D01*
X673154D01*
G01X673499D02*
X673729Y312030D01*
X673921Y312289D01*
X673998Y312599D01*
X673921Y312909D01*
X673729Y313167D01*
X673384Y313322D01*
X673039Y313270D01*
X672694Y313064D01*
G01X656697Y312865D02*
Y309865D01*
G01X659797Y312965D02*
Y309765D01*
G01X653597Y312965D02*
X659797D01*
G01X653597Y309765D02*
Y312965D01*
G01X659797Y309765D02*
X653597D01*
G01X656651Y320096D02*
Y323196D01*
X657571D01*
X657878Y323041D01*
X658108Y322679D01*
X658185Y322266D01*
X658108Y321853D01*
X657916Y321543D01*
X657571Y321388D01*
X656651D01*
G01X661361Y322938D02*
X661131Y323093D01*
X660863Y323196D01*
X660556D01*
X660211Y323041D01*
X659943Y322783D01*
X659751Y322473D01*
X659598Y321956D01*
X659560Y321491D01*
X659636Y321026D01*
X659751Y320716D01*
X659981Y320406D01*
X660250Y320199D01*
X660518Y320096D01*
X660786D01*
X661055Y320199D01*
X661285Y320354D01*
X661476Y320561D01*
G01X662890Y322679D02*
X663120Y322989D01*
X663388Y323144D01*
X663695Y323196D01*
X664078Y323093D01*
X664346Y322834D01*
X664423Y322524D01*
X664385Y322214D01*
X664231Y321956D01*
X663465Y321439D01*
X663120Y321078D01*
X662890Y320561D01*
X662813Y320096D01*
X664423D01*
G01X666641D02*
X666718Y320768D01*
X666833Y321336D01*
X666986Y321853D01*
X667178Y322421D01*
X667485Y323196D01*
X665951D01*
G01X656651Y324096D02*
Y327196D01*
X657571D01*
X657878Y327041D01*
X658108Y326679D01*
X658185Y326266D01*
X658108Y325853D01*
X657916Y325543D01*
X657571Y325388D01*
X656651D01*
G01X661361Y326938D02*
X661131Y327093D01*
X660863Y327196D01*
X660556D01*
X660211Y327041D01*
X659943Y326783D01*
X659751Y326473D01*
X659598Y325956D01*
X659560Y325491D01*
X659636Y325026D01*
X659751Y324716D01*
X659981Y324406D01*
X660250Y324199D01*
X660518Y324096D01*
X660786D01*
X661055Y324199D01*
X661285Y324354D01*
X661476Y324561D01*
G01X662890Y326679D02*
X663120Y326989D01*
X663388Y327144D01*
X663695Y327196D01*
X664078Y327093D01*
X664346Y326834D01*
X664423Y326524D01*
X664385Y326214D01*
X664231Y325956D01*
X663465Y325439D01*
X663120Y325078D01*
X662890Y324561D01*
X662813Y324096D01*
X664423D01*
G01X666718D02*
X666986Y324148D01*
X667293Y324303D01*
X667485Y324561D01*
X667561Y324923D01*
X667485Y325284D01*
X667255Y325594D01*
X666910Y325749D01*
X666526D01*
X666296Y325853D01*
X666105Y326111D01*
X666028Y326473D01*
X666143Y326834D01*
X666411Y327093D01*
X666718Y327196D01*
X667025Y327093D01*
X667293Y326834D01*
X667408Y326473D01*
X667331Y326111D01*
X667140Y325853D01*
X666910Y325749D01*
X666526D01*
X666181Y325594D01*
X665951Y325284D01*
X665875Y324923D01*
X665951Y324561D01*
X666143Y324303D01*
X666450Y324148D01*
X666718Y324096D01*
G01X654004Y360695D02*
Y363195D01*
X653684Y362695D01*
G01Y360695D02*
X654324D01*
G01X664788Y348985D02*
Y350380D01*
X664021Y352085D01*
G01X665555D02*
X664788Y350380D01*
G01X667045Y349605D02*
X667275Y349243D01*
X667581Y349037D01*
X667926Y348985D01*
X668233Y349037D01*
X668540Y349295D01*
X668731Y349605D01*
X668770Y349915D01*
X668693Y350277D01*
X668425Y350535D01*
X668156Y350638D01*
X667811D01*
G01X668156D02*
X668386Y350793D01*
X668578Y351052D01*
X668655Y351362D01*
X668578Y351672D01*
X668386Y351930D01*
X668041Y352085D01*
X667696Y352033D01*
X667351Y351827D01*
G01X656180Y352859D02*
X676652D01*
G01X656180Y354052D02*
Y352859D01*
G01Y366245D02*
Y364952D01*
G01X676652Y366245D02*
X656180D01*
G01X664738Y375435D02*
Y378935D01*
G01X662436Y368052D02*
Y371052D01*
G01X659336Y367952D02*
Y371152D01*
G01X665536Y367952D02*
X659336D01*
G01X665536Y371152D02*
Y367952D01*
G01X659336Y371152D02*
X665536D01*
G01X666336D02*
X672536D01*
G01X666336Y367952D02*
Y371152D01*
G01X672536Y367952D02*
X666336D01*
G01X655538Y372585D02*
Y366385D01*
G01X656838Y376885D02*
Y378885D01*
G01X659195Y423119D02*
Y420897D01*
X659348Y420432D01*
X659655Y420122D01*
X660038Y420019D01*
X660421Y420122D01*
X660728Y420432D01*
X660881Y420897D01*
Y423119D01*
G01X662295Y420639D02*
X662525Y420277D01*
X662831Y420071D01*
X663176Y420019D01*
X663483Y420071D01*
X663790Y420329D01*
X663981Y420639D01*
X664020Y420949D01*
X663943Y421311D01*
X663675Y421569D01*
X663406Y421672D01*
X663061D01*
G01X663406D02*
X663636Y421827D01*
X663828Y422086D01*
X663905Y422396D01*
X663828Y422706D01*
X663636Y422964D01*
X663291Y423119D01*
X662946Y423067D01*
X662601Y422861D01*
G01X665510Y422602D02*
X665740Y422912D01*
X666008Y423067D01*
X666315Y423119D01*
X666698Y423016D01*
X666966Y422757D01*
X667043Y422447D01*
X667005Y422137D01*
X666851Y421879D01*
X666085Y421362D01*
X665740Y421001D01*
X665510Y420484D01*
X665433Y420019D01*
X667043D01*
G01X658338Y415835D02*
Y419335D01*
G01X666238Y415785D02*
Y417785D01*
G01X661065Y441991D02*
Y509707D01*
G01X728781Y441991D02*
X661065D01*
G01X653330Y468465D02*
Y471665D01*
G01X659530Y468465D02*
X653330D01*
G01X659530Y471665D02*
Y468465D01*
G01X659430Y488865D02*
Y485665D01*
G01X653230D02*
Y488865D01*
G01X659430Y485665D02*
X653230D01*
G01X659461Y484530D02*
Y481330D01*
G01X653261Y484530D02*
X659461D01*
G01X653261Y481330D02*
Y484530D01*
G01X659461Y481330D02*
X653261D01*
G01X659461Y480230D02*
Y477030D01*
G01X653261Y480230D02*
X659461D01*
G01X653261Y477030D02*
Y480230D01*
G01X659461Y477030D02*
X653261D01*
G01X653330Y471665D02*
X659530D01*
G01X653230Y488865D02*
X659430D01*
G01X659530Y493265D02*
Y490065D01*
G01X653330Y493265D02*
X659530D01*
G01X653330Y490065D02*
Y493265D01*
G01X659530Y490065D02*
X653330D01*
G01X657724Y511017D02*
X654624D01*
Y511976D01*
X654779Y512282D01*
X654986Y512474D01*
X655399Y512551D01*
X655812Y512474D01*
X656071Y512244D01*
X656226Y511976D01*
Y511017D01*
G01Y511976D02*
X657724Y512551D01*
G01X656432Y514156D02*
X656071Y514424D01*
X655864Y514654D01*
X655761Y514961D01*
X655864Y515229D01*
X656071Y515421D01*
X656381Y515574D01*
X656742Y515612D01*
X657052Y515574D01*
X657362Y515421D01*
X657621Y515191D01*
X657724Y514922D01*
X657621Y514616D01*
X657311Y514347D01*
X656846Y514194D01*
X656329Y514156D01*
X655657Y514232D01*
X655296Y514347D01*
X654934Y514539D01*
X654676Y514807D01*
X654624Y515076D01*
X654727Y515344D01*
X654986Y515536D01*
G01X656432Y517256D02*
X656071Y517524D01*
X655864Y517754D01*
X655761Y518061D01*
X655864Y518329D01*
X656071Y518521D01*
X656381Y518674D01*
X656742Y518712D01*
X657052Y518674D01*
X657362Y518521D01*
X657621Y518291D01*
X657724Y518022D01*
X657621Y517716D01*
X657311Y517447D01*
X656846Y517294D01*
X656329Y517256D01*
X655657Y517332D01*
X655296Y517447D01*
X654934Y517639D01*
X654676Y517907D01*
X654624Y518176D01*
X654727Y518444D01*
X654986Y518636D01*
G01X657724Y521084D02*
X654624D01*
X655244Y520624D01*
G01X657724D02*
Y521544D01*
G01X670173Y515489D02*
X666973D01*
G01D02*
Y521689D01*
G01X665624Y515466D02*
X662424D01*
G01X665624Y521666D02*
Y515466D01*
G01X662424D02*
Y521666D01*
G01X661533Y515672D02*
X658333D01*
G01D02*
Y521872D01*
G01X661533D02*
Y515672D01*
G01X661065Y509707D02*
X728781D01*
G01X667531Y526888D02*
Y529388D01*
X667211Y528888D01*
G01Y526888D02*
X667851D01*
G01X658355Y530387D02*
Y540887D01*
G01Y525187D02*
Y523487D01*
G01X666973Y521689D02*
X670173D01*
G01X662424Y521666D02*
X665624D01*
G01X658333Y521872D02*
X661533D01*
G01X659801Y549434D02*
X654801D01*
Y550954D01*
X655051Y551461D01*
X655634Y551841D01*
X656301Y551968D01*
X656968Y551841D01*
X657468Y551524D01*
X657718Y550954D01*
Y549434D01*
G01X654801Y553901D02*
X659801Y554788D01*
X654801Y555801D01*
X659801Y556814D01*
X654801Y557701D01*
G01X659801Y559634D02*
X654801D01*
Y561218D01*
X655051Y561724D01*
X655384Y562041D01*
X656051Y562168D01*
X656718Y562041D01*
X657134Y561661D01*
X657384Y561218D01*
Y559634D01*
G01Y561218D02*
X659801Y562168D01*
G01X661468Y564101D02*
Y567901D01*
G01X657134Y571608D02*
X656884Y571861D01*
X656468Y572051D01*
X655884Y572178D01*
X655384Y572051D01*
X655051Y571798D01*
X654801Y571354D01*
Y569644D01*
X659801D01*
Y571734D01*
X659468Y572178D01*
X658968Y572431D01*
X658384Y572558D01*
X657801Y572431D01*
X657301Y572051D01*
X657134Y571608D01*
Y569644D01*
G01X654801Y576201D02*
X659801D01*
G01X654801Y574744D02*
Y577658D01*
G01X659801Y579844D02*
X654801D01*
X659801Y582758D01*
X654801D01*
G01X654270Y548591D02*
X660637D01*
Y584050D01*
X654185D01*
Y548591D01*
X654270D01*
G01X666799Y543492D02*
X666959Y543200D01*
X667173Y543034D01*
X667413Y542992D01*
X667626Y543034D01*
X667839Y543242D01*
X667973Y543492D01*
X667999Y543742D01*
X667946Y544034D01*
X667759Y544242D01*
X667573Y544325D01*
X667333D01*
G01X667573D02*
X667733Y544450D01*
X667866Y544659D01*
X667919Y544909D01*
X667866Y545159D01*
X667733Y545367D01*
X667493Y545492D01*
X667253Y545450D01*
X667013Y545284D01*
G01X658355Y546087D02*
Y547887D01*
G01X661200Y587072D02*
X661379D01*
Y566066D01*
X667363D01*
Y550605D01*
X669304D01*
Y522301D01*
X672521D01*
Y510410D01*
X682950D01*
G01X661322Y558109D02*
X664906D01*
Y551321D01*
X664927D01*
X667120Y553514D01*
X667099Y553535D01*
X662271D01*
X664506Y551300D01*
X664843D01*
G01X664233Y579090D02*
X664003Y579245D01*
X663735Y579348D01*
X663428D01*
X663083Y579193D01*
X662815Y578935D01*
X662623Y578625D01*
X662470Y578108D01*
X662432Y577643D01*
X662508Y577178D01*
X662623Y576868D01*
X662853Y576558D01*
X663122Y576351D01*
X663390Y576248D01*
X663658D01*
X663927Y576351D01*
X664157Y576506D01*
X664348Y576713D01*
G01X666413Y576248D02*
X666490Y576920D01*
X666605Y577488D01*
X666758Y578005D01*
X666950Y578573D01*
X667257Y579348D01*
X665723D01*
G01X668938Y576610D02*
X669207Y576351D01*
X669513Y576248D01*
X669820Y576351D01*
X670088Y576661D01*
X670280Y577126D01*
X670357Y577591D01*
Y578160D01*
X670280Y578625D01*
X670088Y579038D01*
X669858Y579245D01*
X669590Y579348D01*
X669283Y579245D01*
X669053Y579038D01*
X668900Y578728D01*
X668823Y578315D01*
X668900Y577953D01*
X669092Y577591D01*
X669322Y577385D01*
X669590Y577333D01*
X669897Y577436D01*
X670127Y577695D01*
X670357Y578160D01*
G01X672613Y576248D02*
X672690Y576920D01*
X672805Y577488D01*
X672958Y578005D01*
X673150Y578573D01*
X673457Y579348D01*
X671923D01*
G01X662623Y572377D02*
Y575477D01*
X663582D01*
X663888Y575322D01*
X664080Y575115D01*
X664157Y574702D01*
X664080Y574289D01*
X663850Y574030D01*
X663582Y573875D01*
X662623D01*
G01X663582D02*
X664157Y572377D01*
G01X666490D02*
Y575477D01*
X666030Y574857D01*
G01Y572377D02*
X666950D01*
G01X669590Y575477D02*
X669283Y575374D01*
X669053Y575115D01*
X668900Y574805D01*
X668785Y574392D01*
X668747Y573927D01*
X668785Y573462D01*
X668900Y573049D01*
X669053Y572739D01*
X669283Y572480D01*
X669590Y572377D01*
X669897Y572480D01*
X670127Y572739D01*
X670280Y573049D01*
X670395Y573462D01*
X670433Y573927D01*
X670395Y574392D01*
X670280Y574805D01*
X670127Y575115D01*
X669897Y575374D01*
X669590Y575477D01*
G01X671847Y572842D02*
X672077Y572584D01*
X672345Y572429D01*
X672690Y572377D01*
X673035Y572480D01*
X673303Y572687D01*
X673495Y573049D01*
X673533Y573462D01*
X673457Y573875D01*
X673265Y574134D01*
X672997Y574340D01*
X672728Y574392D01*
X672460Y574340D01*
X672115Y574134D01*
X672230Y575477D01*
X673265D01*
G01X674947Y572997D02*
X675177Y572635D01*
X675483Y572429D01*
X675828Y572377D01*
X676135Y572429D01*
X676442Y572687D01*
X676633Y572997D01*
X676672Y573307D01*
X676595Y573669D01*
X676327Y573927D01*
X676058Y574030D01*
X675713D01*
G01X676058D02*
X676288Y574185D01*
X676480Y574444D01*
X676557Y574754D01*
X676480Y575064D01*
X676288Y575322D01*
X675943Y575477D01*
X675598Y575425D01*
X675253Y575219D01*
G01X662623Y580329D02*
Y583429D01*
X663582D01*
X663888Y583274D01*
X664080Y583067D01*
X664157Y582654D01*
X664080Y582241D01*
X663850Y581982D01*
X663582Y581827D01*
X662623D01*
G01X663582D02*
X664157Y580329D01*
G01X666490D02*
Y583429D01*
X666030Y582809D01*
G01Y580329D02*
X666950D01*
G01X669590Y583429D02*
X669283Y583326D01*
X669053Y583067D01*
X668900Y582757D01*
X668785Y582344D01*
X668747Y581879D01*
X668785Y581414D01*
X668900Y581001D01*
X669053Y580691D01*
X669283Y580432D01*
X669590Y580329D01*
X669897Y580432D01*
X670127Y580691D01*
X670280Y581001D01*
X670395Y581414D01*
X670433Y581879D01*
X670395Y582344D01*
X670280Y582757D01*
X670127Y583067D01*
X669897Y583326D01*
X669590Y583429D01*
G01X671847Y580794D02*
X672077Y580536D01*
X672345Y580381D01*
X672690Y580329D01*
X673035Y580432D01*
X673303Y580639D01*
X673495Y581001D01*
X673533Y581414D01*
X673457Y581827D01*
X673265Y582086D01*
X672997Y582292D01*
X672728Y582344D01*
X672460Y582292D01*
X672115Y582086D01*
X672230Y583429D01*
X673265D01*
G01X676250Y580329D02*
Y583429D01*
X674832Y581207D01*
X676748D01*
G01X662623Y568112D02*
Y571212D01*
X663582D01*
X663888Y571057D01*
X664080Y570850D01*
X664157Y570437D01*
X664080Y570024D01*
X663850Y569765D01*
X663582Y569610D01*
X662623D01*
G01X663582D02*
X664157Y568112D01*
G01X666490D02*
Y571212D01*
X666030Y570592D01*
G01Y568112D02*
X666950D01*
G01X669590D02*
Y571212D01*
X669130Y570592D01*
G01Y568112D02*
X670050D01*
G01X671962Y570695D02*
X672192Y571005D01*
X672460Y571160D01*
X672767Y571212D01*
X673150Y571109D01*
X673418Y570850D01*
X673495Y570540D01*
X673457Y570230D01*
X673303Y569972D01*
X672537Y569455D01*
X672192Y569094D01*
X671962Y568577D01*
X671885Y568112D01*
X673495D01*
G01X675062Y570695D02*
X675292Y571005D01*
X675560Y571160D01*
X675867Y571212D01*
X676250Y571109D01*
X676518Y570850D01*
X676595Y570540D01*
X676557Y570230D01*
X676403Y569972D01*
X675637Y569455D01*
X675292Y569094D01*
X675062Y568577D01*
X674985Y568112D01*
X676595D01*
G01X653037Y577245D02*
Y571045D01*
G01X663583Y589813D02*
X678064D01*
Y521646D01*
X682950D01*
Y510410D01*
X730500D01*
Y509000D01*
X785000D01*
Y532500D01*
X731330D01*
Y528340D01*
G01X659158Y594508D02*
X661380D01*
X661845Y594661D01*
X662155Y594968D01*
X662258Y595351D01*
X662155Y595734D01*
X661845Y596041D01*
X661380Y596194D01*
X659158D01*
G01X661638Y597608D02*
X662000Y597838D01*
X662206Y598144D01*
X662258Y598489D01*
X662206Y598796D01*
X661948Y599103D01*
X661638Y599294D01*
X661328Y599333D01*
X660966Y599256D01*
X660708Y598988D01*
X660605Y598719D01*
Y598374D01*
G01Y598719D02*
X660450Y598949D01*
X660191Y599141D01*
X659881Y599218D01*
X659571Y599141D01*
X659313Y598949D01*
X659158Y598604D01*
X659210Y598259D01*
X659416Y597914D01*
G01X662258Y601474D02*
X661586Y601551D01*
X661018Y601666D01*
X660501Y601819D01*
X659933Y602011D01*
X659158Y602318D01*
Y600784D01*
G01X656335Y585725D02*
Y588225D01*
X655348Y586433D01*
X656682D01*
G01X657762Y586017D02*
X657948Y585808D01*
X658162Y585725D01*
X658375Y585808D01*
X658562Y586058D01*
X658695Y586433D01*
X658748Y586808D01*
Y587267D01*
X658695Y587642D01*
X658562Y587975D01*
X658402Y588142D01*
X658215Y588225D01*
X658002Y588142D01*
X657842Y587975D01*
X657735Y587725D01*
X657682Y587392D01*
X657735Y587100D01*
X657868Y586808D01*
X658028Y586642D01*
X658215Y586600D01*
X658428Y586683D01*
X658588Y586892D01*
X658748Y587267D01*
G01X654737Y589950D02*
X658737D01*
G01X662745Y585937D02*
Y589037D01*
X663704D01*
X664010Y588882D01*
X664202Y588675D01*
X664279Y588262D01*
X664202Y587849D01*
X663972Y587590D01*
X663704Y587435D01*
X662745D01*
G01X663704D02*
X664279Y585937D01*
G01X666612D02*
Y589037D01*
X666152Y588417D01*
G01Y585937D02*
X667072D01*
G01X669712Y589037D02*
X669405Y588934D01*
X669175Y588675D01*
X669022Y588365D01*
X668907Y587952D01*
X668869Y587487D01*
X668907Y587022D01*
X669022Y586609D01*
X669175Y586299D01*
X669405Y586040D01*
X669712Y585937D01*
X670019Y586040D01*
X670249Y586299D01*
X670402Y586609D01*
X670517Y587022D01*
X670555Y587487D01*
X670517Y587952D01*
X670402Y588365D01*
X670249Y588675D01*
X670019Y588934D01*
X669712Y589037D01*
G01X672084Y587229D02*
X672352Y587590D01*
X672582Y587797D01*
X672889Y587900D01*
X673157Y587797D01*
X673349Y587590D01*
X673502Y587280D01*
X673540Y586919D01*
X673502Y586609D01*
X673349Y586299D01*
X673119Y586040D01*
X672850Y585937D01*
X672544Y586040D01*
X672275Y586350D01*
X672122Y586815D01*
X672084Y587332D01*
X672160Y588004D01*
X672275Y588365D01*
X672467Y588727D01*
X672735Y588985D01*
X673004Y589037D01*
X673272Y588934D01*
X673464Y588675D01*
G01X675184Y587229D02*
X675452Y587590D01*
X675682Y587797D01*
X675989Y587900D01*
X676257Y587797D01*
X676449Y587590D01*
X676602Y587280D01*
X676640Y586919D01*
X676602Y586609D01*
X676449Y586299D01*
X676219Y586040D01*
X675950Y585937D01*
X675644Y586040D01*
X675375Y586350D01*
X675222Y586815D01*
X675184Y587332D01*
X675260Y588004D01*
X675375Y588365D01*
X675567Y588727D01*
X675835Y588985D01*
X676104Y589037D01*
X676372Y588934D01*
X676564Y588675D01*
G01X654737Y609635D02*
X658737D01*
G01X654437Y599792D02*
X656437D01*
G01X662013Y606924D02*
Y610024D01*
X662972D01*
X663278Y609869D01*
X663470Y609662D01*
X663547Y609249D01*
X663470Y608836D01*
X663240Y608577D01*
X662972Y608422D01*
X662013D01*
G01X662972D02*
X663547Y606924D01*
G01X665037Y607389D02*
X665267Y607131D01*
X665535Y606976D01*
X665880Y606924D01*
X666225Y607027D01*
X666493Y607234D01*
X666685Y607596D01*
X666723Y608009D01*
X666647Y608422D01*
X666455Y608681D01*
X666187Y608887D01*
X665918Y608939D01*
X665650Y608887D01*
X665305Y608681D01*
X665420Y610024D01*
X666455D01*
G01X668980Y606924D02*
X669248Y606976D01*
X669555Y607131D01*
X669747Y607389D01*
X669823Y607751D01*
X669747Y608112D01*
X669517Y608422D01*
X669172Y608577D01*
X668788D01*
X668558Y608681D01*
X668367Y608939D01*
X668290Y609301D01*
X668405Y609662D01*
X668673Y609921D01*
X668980Y610024D01*
X669287Y609921D01*
X669555Y609662D01*
X669670Y609301D01*
X669593Y608939D01*
X669402Y608681D01*
X669172Y608577D01*
X668788D01*
X668443Y608422D01*
X668213Y608112D01*
X668137Y607751D01*
X668213Y607389D01*
X668405Y607131D01*
X668712Y606976D01*
X668980Y606924D01*
G01X671352Y609507D02*
X671582Y609817D01*
X671850Y609972D01*
X672157Y610024D01*
X672540Y609921D01*
X672808Y609662D01*
X672885Y609352D01*
X672847Y609042D01*
X672693Y608784D01*
X671927Y608267D01*
X671582Y607906D01*
X671352Y607389D01*
X671275Y606924D01*
X672885D01*
G01X660323Y619031D02*
X666523D01*
G01D02*
Y615831D01*
G01D02*
X660323D01*
G01D02*
Y619031D01*
G01X658024Y642944D02*
Y646044D01*
X658983D01*
X659289Y645889D01*
X659481Y645682D01*
X659558Y645269D01*
X659481Y644856D01*
X659251Y644597D01*
X658983Y644442D01*
X658024D01*
G01X658983D02*
X659558Y642944D01*
G01X661048Y643409D02*
X661278Y643151D01*
X661546Y642996D01*
X661891Y642944D01*
X662236Y643047D01*
X662504Y643254D01*
X662696Y643616D01*
X662734Y644029D01*
X662658Y644442D01*
X662466Y644701D01*
X662198Y644907D01*
X661929Y644959D01*
X661661Y644907D01*
X661316Y644701D01*
X661431Y646044D01*
X662466D01*
G01X664914Y642944D02*
X664991Y643616D01*
X665106Y644184D01*
X665259Y644701D01*
X665451Y645269D01*
X665758Y646044D01*
X664224D01*
G01X668014Y642944D02*
X668091Y643616D01*
X668206Y644184D01*
X668359Y644701D01*
X668551Y645269D01*
X668858Y646044D01*
X667324D01*
G01X655901Y646672D02*
Y643472D01*
G01X652570Y638415D02*
Y632215D01*
G01X656770Y638515D02*
Y632315D01*
G01X653570D02*
Y638515D01*
G01D02*
X656770D01*
G01Y632315D02*
X653570D01*
G01X659896Y660207D02*
X659666Y660362D01*
X659398Y660465D01*
X659091D01*
X658746Y660310D01*
X658478Y660052D01*
X658286Y659742D01*
X658133Y659225D01*
X658095Y658760D01*
X658171Y658295D01*
X658286Y657985D01*
X658516Y657675D01*
X658785Y657468D01*
X659053Y657365D01*
X659321D01*
X659590Y657468D01*
X659820Y657623D01*
X660011Y657830D01*
G01X662613Y657365D02*
Y660465D01*
X661195Y658243D01*
X663111D01*
G01X664410Y657985D02*
X664640Y657623D01*
X664946Y657417D01*
X665291Y657365D01*
X665598Y657417D01*
X665905Y657675D01*
X666096Y657985D01*
X666135Y658295D01*
X666058Y658657D01*
X665790Y658915D01*
X665521Y659018D01*
X665176D01*
G01X665521D02*
X665751Y659173D01*
X665943Y659432D01*
X666020Y659742D01*
X665943Y660052D01*
X665751Y660310D01*
X665406Y660465D01*
X665061Y660413D01*
X664716Y660207D01*
G01X668813Y657365D02*
Y660465D01*
X667395Y658243D01*
X669311D01*
G01X652801Y661992D02*
Y658992D01*
G01X655901Y662092D02*
Y658892D01*
G01X658024Y651353D02*
Y654453D01*
X658983D01*
X659289Y654298D01*
X659481Y654091D01*
X659558Y653678D01*
X659481Y653265D01*
X659251Y653006D01*
X658983Y652851D01*
X658024D01*
G01X658983D02*
X659558Y651353D01*
G01X661048Y651818D02*
X661278Y651560D01*
X661546Y651405D01*
X661891Y651353D01*
X662236Y651456D01*
X662504Y651663D01*
X662696Y652025D01*
X662734Y652438D01*
X662658Y652851D01*
X662466Y653110D01*
X662198Y653316D01*
X661929Y653368D01*
X661661Y653316D01*
X661316Y653110D01*
X661431Y654453D01*
X662466D01*
G01X664991Y651353D02*
X665259Y651405D01*
X665566Y651560D01*
X665758Y651818D01*
X665834Y652180D01*
X665758Y652541D01*
X665528Y652851D01*
X665183Y653006D01*
X664799D01*
X664569Y653110D01*
X664378Y653368D01*
X664301Y653730D01*
X664416Y654091D01*
X664684Y654350D01*
X664991Y654453D01*
X665298Y654350D01*
X665566Y654091D01*
X665681Y653730D01*
X665604Y653368D01*
X665413Y653110D01*
X665183Y653006D01*
X664799D01*
X664454Y652851D01*
X664224Y652541D01*
X664148Y652180D01*
X664224Y651818D01*
X664416Y651560D01*
X664723Y651405D01*
X664991Y651353D01*
G01X667248Y651973D02*
X667478Y651611D01*
X667784Y651405D01*
X668129Y651353D01*
X668436Y651405D01*
X668743Y651663D01*
X668934Y651973D01*
X668973Y652283D01*
X668896Y652645D01*
X668628Y652903D01*
X668359Y653006D01*
X668014D01*
G01X668359D02*
X668589Y653161D01*
X668781Y653420D01*
X668858Y653730D01*
X668781Y654040D01*
X668589Y654298D01*
X668244Y654453D01*
X667899Y654401D01*
X667554Y654195D01*
G01X655901Y656672D02*
Y653472D01*
G01X658024Y647127D02*
Y650227D01*
X658983D01*
X659289Y650072D01*
X659481Y649865D01*
X659558Y649452D01*
X659481Y649039D01*
X659251Y648780D01*
X658983Y648625D01*
X658024D01*
G01X658983D02*
X659558Y647127D01*
G01X661048Y647592D02*
X661278Y647334D01*
X661546Y647179D01*
X661891Y647127D01*
X662236Y647230D01*
X662504Y647437D01*
X662696Y647799D01*
X662734Y648212D01*
X662658Y648625D01*
X662466Y648884D01*
X662198Y649090D01*
X661929Y649142D01*
X661661Y649090D01*
X661316Y648884D01*
X661431Y650227D01*
X662466D01*
G01X664914Y647127D02*
X664991Y647799D01*
X665106Y648367D01*
X665259Y648884D01*
X665451Y649452D01*
X665758Y650227D01*
X664224D01*
G01X667248Y647592D02*
X667478Y647334D01*
X667746Y647179D01*
X668091Y647127D01*
X668436Y647230D01*
X668704Y647437D01*
X668896Y647799D01*
X668934Y648212D01*
X668858Y648625D01*
X668666Y648884D01*
X668398Y649090D01*
X668129Y649142D01*
X667861Y649090D01*
X667516Y648884D01*
X667631Y650227D01*
X668666D01*
G01X655901Y651672D02*
Y648472D01*
G01X669994Y675270D02*
X669764Y675425D01*
X669496Y675528D01*
X669189D01*
X668844Y675373D01*
X668576Y675115D01*
X668384Y674805D01*
X668231Y674288D01*
X668193Y673823D01*
X668269Y673358D01*
X668384Y673048D01*
X668614Y672738D01*
X668883Y672531D01*
X669151Y672428D01*
X669419D01*
X669688Y672531D01*
X669918Y672686D01*
X670109Y672893D01*
G01X671408D02*
X671638Y672635D01*
X671906Y672480D01*
X672251Y672428D01*
X672596Y672531D01*
X672864Y672738D01*
X673056Y673100D01*
X673094Y673513D01*
X673018Y673926D01*
X672826Y674185D01*
X672558Y674391D01*
X672289Y674443D01*
X672021Y674391D01*
X671676Y674185D01*
X671791Y675528D01*
X672826D01*
G01X674623Y673720D02*
X674891Y674081D01*
X675121Y674288D01*
X675428Y674391D01*
X675696Y674288D01*
X675888Y674081D01*
X676041Y673771D01*
X676079Y673410D01*
X676041Y673100D01*
X675888Y672790D01*
X675658Y672531D01*
X675389Y672428D01*
X675083Y672531D01*
X674814Y672841D01*
X674661Y673306D01*
X674623Y673823D01*
X674699Y674495D01*
X674814Y674856D01*
X675006Y675218D01*
X675274Y675476D01*
X675543Y675528D01*
X675811Y675425D01*
X676003Y675166D01*
G01X678911Y672428D02*
Y675528D01*
X677493Y673306D01*
X679409D01*
G01X666370Y675405D02*
X663370D01*
G01X666470Y672305D02*
X663270D01*
G01X666470Y678505D02*
Y672305D01*
G01X663270D02*
Y678505D01*
G01X663370Y667849D02*
X666370D01*
G01X663270Y670949D02*
X666470D01*
G01X663270Y664749D02*
Y670949D01*
G01X666470Y664749D02*
X663270D01*
G01X666470Y670949D02*
Y664749D01*
G01X663270Y678505D02*
X666470D01*
G01X661591Y691104D02*
X658491D01*
Y692063D01*
X658646Y692369D01*
X658853Y692561D01*
X659266Y692638D01*
X659679Y692561D01*
X659938Y692331D01*
X660093Y692063D01*
Y691104D01*
G01Y692063D02*
X661591Y692638D01*
G01Y694971D02*
X658491D01*
X659111Y694511D01*
G01X661591D02*
Y695431D01*
G01X660971Y697228D02*
X661333Y697458D01*
X661539Y697764D01*
X661591Y698109D01*
X661539Y698416D01*
X661281Y698723D01*
X660971Y698914D01*
X660661Y698953D01*
X660299Y698876D01*
X660041Y698608D01*
X659938Y698339D01*
Y697994D01*
G01Y698339D02*
X659783Y698569D01*
X659524Y698761D01*
X659214Y698838D01*
X658904Y698761D01*
X658646Y698569D01*
X658491Y698224D01*
X658543Y697879D01*
X658749Y697534D01*
G01X658491Y701171D02*
X658594Y700864D01*
X658853Y700634D01*
X659163Y700481D01*
X659576Y700366D01*
X660041Y700328D01*
X660506Y700366D01*
X660919Y700481D01*
X661229Y700634D01*
X661488Y700864D01*
X661591Y701171D01*
X661488Y701478D01*
X661229Y701708D01*
X660919Y701861D01*
X660506Y701976D01*
X660041Y702014D01*
X659576Y701976D01*
X659163Y701861D01*
X658853Y701708D01*
X658594Y701478D01*
X658491Y701171D01*
G01X660971Y703428D02*
X661333Y703658D01*
X661539Y703964D01*
X661591Y704309D01*
X661539Y704616D01*
X661281Y704923D01*
X660971Y705114D01*
X660661Y705153D01*
X660299Y705076D01*
X660041Y704808D01*
X659938Y704539D01*
Y704194D01*
G01Y704539D02*
X659783Y704769D01*
X659524Y704961D01*
X659214Y705038D01*
X658904Y704961D01*
X658646Y704769D01*
X658491Y704424D01*
X658543Y704079D01*
X658749Y703734D01*
G01X661278Y683382D02*
X658078D01*
G01X661278Y689582D02*
Y683382D01*
G01X658078Y689582D02*
X661278D01*
G01X658078Y683382D02*
Y689582D01*
G01X652751Y718273D02*
Y715075D01*
G01Y722274D02*
Y719074D01*
G01Y726274D02*
Y723074D01*
G01Y730274D02*
Y727074D01*
G01X659060Y737835D02*
Y744035D01*
G01X662260Y737835D02*
X659060D01*
G01X662260Y744035D02*
Y737835D01*
G01X653060D02*
Y744035D01*
G01X656260Y737835D02*
X653060D01*
G01X656260Y744035D02*
Y737835D01*
G01X661200Y745083D02*
X658100D01*
Y746042D01*
X658255Y746348D01*
X658462Y746540D01*
X658875Y746617D01*
X659288Y746540D01*
X659547Y746310D01*
X659702Y746042D01*
Y745083D01*
G01Y746042D02*
X661200Y746617D01*
G01Y748950D02*
X661148Y749218D01*
X660993Y749525D01*
X660735Y749717D01*
X660373Y749793D01*
X660012Y749717D01*
X659702Y749487D01*
X659547Y749142D01*
Y748758D01*
X659443Y748528D01*
X659185Y748337D01*
X658823Y748260D01*
X658462Y748375D01*
X658203Y748643D01*
X658100Y748950D01*
X658203Y749257D01*
X658462Y749525D01*
X658823Y749640D01*
X659185Y749563D01*
X659443Y749372D01*
X659547Y749142D01*
Y748758D01*
X659702Y748413D01*
X660012Y748183D01*
X660373Y748107D01*
X660735Y748183D01*
X660993Y748375D01*
X661148Y748682D01*
X661200Y748950D01*
G01Y752510D02*
X658100D01*
X660322Y751092D01*
Y753008D01*
G01X661200Y755150D02*
X658100D01*
X658720Y754690D01*
G01X661200D02*
Y755610D01*
G01X659060Y744035D02*
X662260D01*
G01X657000Y745083D02*
X653900D01*
Y746042D01*
X654055Y746348D01*
X654262Y746540D01*
X654675Y746617D01*
X655088Y746540D01*
X655347Y746310D01*
X655502Y746042D01*
Y745083D01*
G01Y746042D02*
X657000Y746617D01*
G01Y748950D02*
X656948Y749218D01*
X656793Y749525D01*
X656535Y749717D01*
X656173Y749793D01*
X655812Y749717D01*
X655502Y749487D01*
X655347Y749142D01*
Y748758D01*
X655243Y748528D01*
X654985Y748337D01*
X654623Y748260D01*
X654262Y748375D01*
X654003Y748643D01*
X653900Y748950D01*
X654003Y749257D01*
X654262Y749525D01*
X654623Y749640D01*
X654985Y749563D01*
X655243Y749372D01*
X655347Y749142D01*
Y748758D01*
X655502Y748413D01*
X655812Y748183D01*
X656173Y748107D01*
X656535Y748183D01*
X656793Y748375D01*
X656948Y748682D01*
X657000Y748950D01*
G01Y752510D02*
X653900D01*
X656122Y751092D01*
Y753008D01*
G01X657000Y755610D02*
X653900D01*
X656122Y754192D01*
Y756108D01*
G01X653060Y744035D02*
X656260D01*
G01X685480Y45631D02*
X682380D01*
Y46590D01*
X682535Y46896D01*
X682742Y47088D01*
X683155Y47165D01*
X683568Y47088D01*
X683827Y46858D01*
X683982Y46590D01*
Y45631D01*
G01Y46590D02*
X685480Y47165D01*
G01Y49498D02*
X682380D01*
X683000Y49038D01*
G01X685480D02*
Y49958D01*
G01X682897Y51870D02*
X682587Y52100D01*
X682432Y52368D01*
X682380Y52675D01*
X682483Y53058D01*
X682742Y53326D01*
X683052Y53403D01*
X683362Y53365D01*
X683620Y53211D01*
X684137Y52445D01*
X684498Y52100D01*
X685015Y51870D01*
X685480Y51793D01*
Y53403D01*
G01X682380Y55698D02*
X682483Y55391D01*
X682742Y55161D01*
X683052Y55008D01*
X683465Y54893D01*
X683930Y54855D01*
X684395Y54893D01*
X684808Y55008D01*
X685118Y55161D01*
X685377Y55391D01*
X685480Y55698D01*
X685377Y56005D01*
X685118Y56235D01*
X684808Y56388D01*
X684395Y56503D01*
X683930Y56541D01*
X683465Y56503D01*
X683052Y56388D01*
X682742Y56235D01*
X682483Y56005D01*
X682380Y55698D01*
G01Y58798D02*
X682483Y58491D01*
X682742Y58261D01*
X683052Y58108D01*
X683465Y57993D01*
X683930Y57955D01*
X684395Y57993D01*
X684808Y58108D01*
X685118Y58261D01*
X685377Y58491D01*
X685480Y58798D01*
X685377Y59105D01*
X685118Y59335D01*
X684808Y59488D01*
X684395Y59603D01*
X683930Y59641D01*
X683465Y59603D01*
X683052Y59488D01*
X682742Y59335D01*
X682483Y59105D01*
X682380Y58798D01*
G01X668387Y46011D02*
Y52211D01*
G01X671587D02*
Y46011D01*
G01D02*
X668387D01*
G01Y52211D02*
X671587D01*
G01X674327Y46011D02*
Y52211D01*
G01X677527Y46011D02*
X674327D01*
G01Y52211D02*
X677527D01*
G01D02*
Y46011D01*
G01X678327D02*
Y52211D01*
G01X681527Y46011D02*
X678327D01*
G01X681527Y52211D02*
Y46011D01*
G01X678327Y52211D02*
X681527D01*
G01X680121Y137208D02*
Y140308D01*
X680887D01*
X681194Y140153D01*
X681424Y139946D01*
X681616Y139636D01*
X681769Y139275D01*
X681807Y138758D01*
X681769Y138241D01*
X681616Y137880D01*
X681424Y137570D01*
X681194Y137363D01*
X680887Y137208D01*
X680121D01*
G01X683412Y137570D02*
X683681Y137311D01*
X683987Y137208D01*
X684294Y137311D01*
X684562Y137621D01*
X684754Y138086D01*
X684831Y138551D01*
Y139120D01*
X684754Y139585D01*
X684562Y139998D01*
X684332Y140205D01*
X684064Y140308D01*
X683757Y140205D01*
X683527Y139998D01*
X683374Y139688D01*
X683297Y139275D01*
X683374Y138913D01*
X683566Y138551D01*
X683796Y138345D01*
X684064Y138293D01*
X684371Y138396D01*
X684601Y138655D01*
X684831Y139120D01*
G01X675872Y151361D02*
Y143467D01*
G01X681444Y155359D02*
Y171359D01*
G01X693648Y155359D02*
X681444D01*
G01X681207Y144105D02*
X680977Y144260D01*
X680709Y144363D01*
X680402D01*
X680057Y144208D01*
X679789Y143950D01*
X679597Y143640D01*
X679444Y143123D01*
X679406Y142658D01*
X679482Y142193D01*
X679597Y141883D01*
X679827Y141573D01*
X680096Y141366D01*
X680364Y141263D01*
X680632D01*
X680901Y141366D01*
X681131Y141521D01*
X681322Y141728D01*
G01X682621D02*
X682851Y141470D01*
X683119Y141315D01*
X683464Y141263D01*
X683809Y141366D01*
X684077Y141573D01*
X684269Y141935D01*
X684307Y142348D01*
X684231Y142761D01*
X684039Y143020D01*
X683771Y143226D01*
X683502Y143278D01*
X683234Y143226D01*
X682889Y143020D01*
X683004Y144363D01*
X684039D01*
G01X685721Y141728D02*
X685951Y141470D01*
X686219Y141315D01*
X686564Y141263D01*
X686909Y141366D01*
X687177Y141573D01*
X687369Y141935D01*
X687407Y142348D01*
X687331Y142761D01*
X687139Y143020D01*
X686871Y143226D01*
X686602Y143278D01*
X686334Y143226D01*
X685989Y143020D01*
X686104Y144363D01*
X687139D01*
G01X689664Y141263D02*
X689932Y141315D01*
X690239Y141470D01*
X690431Y141728D01*
X690507Y142090D01*
X690431Y142451D01*
X690201Y142761D01*
X689856Y142916D01*
X689472D01*
X689242Y143020D01*
X689051Y143278D01*
X688974Y143640D01*
X689089Y144001D01*
X689357Y144260D01*
X689664Y144363D01*
X689971Y144260D01*
X690239Y144001D01*
X690354Y143640D01*
X690277Y143278D01*
X690086Y143020D01*
X689856Y142916D01*
X689472D01*
X689127Y142761D01*
X688897Y142451D01*
X688821Y142090D01*
X688897Y141728D01*
X689089Y141470D01*
X689396Y141315D01*
X689664Y141263D01*
G01X681207Y148240D02*
X680977Y148395D01*
X680709Y148498D01*
X680402D01*
X680057Y148343D01*
X679789Y148085D01*
X679597Y147775D01*
X679444Y147258D01*
X679406Y146793D01*
X679482Y146328D01*
X679597Y146018D01*
X679827Y145708D01*
X680096Y145501D01*
X680364Y145398D01*
X680632D01*
X680901Y145501D01*
X681131Y145656D01*
X681322Y145863D01*
G01X682621D02*
X682851Y145605D01*
X683119Y145450D01*
X683464Y145398D01*
X683809Y145501D01*
X684077Y145708D01*
X684269Y146070D01*
X684307Y146483D01*
X684231Y146896D01*
X684039Y147155D01*
X683771Y147361D01*
X683502Y147413D01*
X683234Y147361D01*
X682889Y147155D01*
X683004Y148498D01*
X684039D01*
G01X685721Y145863D02*
X685951Y145605D01*
X686219Y145450D01*
X686564Y145398D01*
X686909Y145501D01*
X687177Y145708D01*
X687369Y146070D01*
X687407Y146483D01*
X687331Y146896D01*
X687139Y147155D01*
X686871Y147361D01*
X686602Y147413D01*
X686334Y147361D01*
X685989Y147155D01*
X686104Y148498D01*
X687139D01*
G01X689587Y145398D02*
X689664Y146070D01*
X689779Y146638D01*
X689932Y147155D01*
X690124Y147723D01*
X690431Y148498D01*
X688897D01*
G01X671011Y151028D02*
Y147828D01*
G01Y147028D02*
Y143828D01*
G01X676085Y165964D02*
Y158070D01*
G01X681444Y171359D02*
X693648D01*
G01X671324Y165691D02*
Y162491D01*
G01Y161691D02*
Y158491D01*
G01X670495Y186859D02*
X676695D01*
G01Y183659D02*
X670495D01*
G01D02*
Y186859D01*
G01X673595Y183759D02*
Y186759D01*
G01X676695Y186859D02*
Y183659D01*
G01X680945Y198246D02*
X684945Y202246D01*
G01X680930Y196515D02*
Y189715D01*
G01X673430Y189815D02*
Y196415D01*
G01X684945Y215900D02*
X680945Y219900D01*
G01X675706Y230167D02*
Y222273D01*
G01X681482Y234165D02*
Y250165D01*
G01X693686Y234165D02*
X681482D01*
G01X681992Y220141D02*
Y223241D01*
X682758D01*
X683065Y223086D01*
X683295Y222879D01*
X683487Y222569D01*
X683640Y222208D01*
X683678Y221691D01*
X683640Y221174D01*
X683487Y220813D01*
X683295Y220503D01*
X683065Y220296D01*
X682758Y220141D01*
X681992D01*
G01X685935D02*
Y223241D01*
X685475Y222621D01*
G01Y220141D02*
X686395D01*
G01X689035Y223241D02*
X688728Y223138D01*
X688498Y222879D01*
X688345Y222569D01*
X688230Y222156D01*
X688192Y221691D01*
X688230Y221226D01*
X688345Y220813D01*
X688498Y220503D01*
X688728Y220244D01*
X689035Y220141D01*
X689342Y220244D01*
X689572Y220503D01*
X689725Y220813D01*
X689840Y221226D01*
X689878Y221691D01*
X689840Y222156D01*
X689725Y222569D01*
X689572Y222879D01*
X689342Y223138D01*
X689035Y223241D01*
G01X683678Y227276D02*
X683448Y227431D01*
X683180Y227534D01*
X682873D01*
X682528Y227379D01*
X682260Y227121D01*
X682068Y226811D01*
X681915Y226294D01*
X681877Y225829D01*
X681953Y225364D01*
X682068Y225054D01*
X682298Y224744D01*
X682567Y224537D01*
X682835Y224434D01*
X683103D01*
X683372Y224537D01*
X683602Y224692D01*
X683793Y224899D01*
G01X685092D02*
X685322Y224641D01*
X685590Y224486D01*
X685935Y224434D01*
X686280Y224537D01*
X686548Y224744D01*
X686740Y225106D01*
X686778Y225519D01*
X686702Y225932D01*
X686510Y226191D01*
X686242Y226397D01*
X685973Y226449D01*
X685705Y226397D01*
X685360Y226191D01*
X685475Y227534D01*
X686510D01*
G01X688307Y225726D02*
X688575Y226087D01*
X688805Y226294D01*
X689112Y226397D01*
X689380Y226294D01*
X689572Y226087D01*
X689725Y225777D01*
X689763Y225416D01*
X689725Y225106D01*
X689572Y224796D01*
X689342Y224537D01*
X689073Y224434D01*
X688767Y224537D01*
X688498Y224847D01*
X688345Y225312D01*
X688307Y225829D01*
X688383Y226501D01*
X688498Y226862D01*
X688690Y227224D01*
X688958Y227482D01*
X689227Y227534D01*
X689495Y227431D01*
X689687Y227172D01*
G01X692135Y227534D02*
X691828Y227431D01*
X691598Y227172D01*
X691445Y226862D01*
X691330Y226449D01*
X691292Y225984D01*
X691330Y225519D01*
X691445Y225106D01*
X691598Y224796D01*
X691828Y224537D01*
X692135Y224434D01*
X692442Y224537D01*
X692672Y224796D01*
X692825Y225106D01*
X692940Y225519D01*
X692978Y225984D01*
X692940Y226449D01*
X692825Y226862D01*
X692672Y227172D01*
X692442Y227431D01*
X692135Y227534D01*
G01X683678Y231302D02*
X683448Y231457D01*
X683180Y231560D01*
X682873D01*
X682528Y231405D01*
X682260Y231147D01*
X682068Y230837D01*
X681915Y230320D01*
X681877Y229855D01*
X681953Y229390D01*
X682068Y229080D01*
X682298Y228770D01*
X682567Y228563D01*
X682835Y228460D01*
X683103D01*
X683372Y228563D01*
X683602Y228718D01*
X683793Y228925D01*
G01X685092D02*
X685322Y228667D01*
X685590Y228512D01*
X685935Y228460D01*
X686280Y228563D01*
X686548Y228770D01*
X686740Y229132D01*
X686778Y229545D01*
X686702Y229958D01*
X686510Y230217D01*
X686242Y230423D01*
X685973Y230475D01*
X685705Y230423D01*
X685360Y230217D01*
X685475Y231560D01*
X686510D01*
G01X688307Y229752D02*
X688575Y230113D01*
X688805Y230320D01*
X689112Y230423D01*
X689380Y230320D01*
X689572Y230113D01*
X689725Y229803D01*
X689763Y229442D01*
X689725Y229132D01*
X689572Y228822D01*
X689342Y228563D01*
X689073Y228460D01*
X688767Y228563D01*
X688498Y228873D01*
X688345Y229338D01*
X688307Y229855D01*
X688383Y230527D01*
X688498Y230888D01*
X688690Y231250D01*
X688958Y231508D01*
X689227Y231560D01*
X689495Y231457D01*
X689687Y231198D01*
G01X692135Y228460D02*
Y231560D01*
X691675Y230940D01*
G01Y228460D02*
X692595D01*
G01X670988Y229935D02*
Y226735D01*
G01Y225935D02*
Y222735D01*
G01X676320Y244770D02*
Y236876D01*
G01X681482Y250165D02*
X693686D01*
G01X671574Y244445D02*
Y241245D01*
G01Y240445D02*
Y237245D01*
G01X683197Y267316D02*
X680097D01*
Y268275D01*
X680252Y268581D01*
X680459Y268773D01*
X680872Y268850D01*
X681285Y268773D01*
X681544Y268543D01*
X681699Y268275D01*
Y267316D01*
G01Y268275D02*
X683197Y268850D01*
G01Y271183D02*
X680097D01*
X680717Y270723D01*
G01X683197D02*
Y271643D01*
G01X680097Y274283D02*
X680200Y273976D01*
X680459Y273746D01*
X680769Y273593D01*
X681182Y273478D01*
X681647Y273440D01*
X682112Y273478D01*
X682525Y273593D01*
X682835Y273746D01*
X683094Y273976D01*
X683197Y274283D01*
X683094Y274590D01*
X682835Y274820D01*
X682525Y274973D01*
X682112Y275088D01*
X681647Y275126D01*
X681182Y275088D01*
X680769Y274973D01*
X680459Y274820D01*
X680200Y274590D01*
X680097Y274283D01*
G01X683197Y277383D02*
X680097D01*
X680717Y276923D01*
G01X683197D02*
Y277843D01*
G01Y280483D02*
X683145Y280751D01*
X682990Y281058D01*
X682732Y281250D01*
X682370Y281326D01*
X682009Y281250D01*
X681699Y281020D01*
X681544Y280675D01*
Y280291D01*
X681440Y280061D01*
X681182Y279870D01*
X680820Y279793D01*
X680459Y279908D01*
X680200Y280176D01*
X680097Y280483D01*
X680200Y280790D01*
X680459Y281058D01*
X680820Y281173D01*
X681182Y281096D01*
X681440Y280905D01*
X681544Y280675D01*
Y280291D01*
X681699Y279946D01*
X682009Y279716D01*
X682370Y279640D01*
X682732Y279716D01*
X682990Y279908D01*
X683145Y280215D01*
X683197Y280483D01*
G01X675127Y267316D02*
X672027D01*
Y268275D01*
X672182Y268581D01*
X672389Y268773D01*
X672802Y268850D01*
X673215Y268773D01*
X673474Y268543D01*
X673629Y268275D01*
Y267316D01*
G01Y268275D02*
X675127Y268850D01*
G01Y271183D02*
X672027D01*
X672647Y270723D01*
G01X675127D02*
Y271643D01*
G01X672027Y274283D02*
X672130Y273976D01*
X672389Y273746D01*
X672699Y273593D01*
X673112Y273478D01*
X673577Y273440D01*
X674042Y273478D01*
X674455Y273593D01*
X674765Y273746D01*
X675024Y273976D01*
X675127Y274283D01*
X675024Y274590D01*
X674765Y274820D01*
X674455Y274973D01*
X674042Y275088D01*
X673577Y275126D01*
X673112Y275088D01*
X672699Y274973D01*
X672389Y274820D01*
X672130Y274590D01*
X672027Y274283D01*
G01X672544Y276655D02*
X672234Y276885D01*
X672079Y277153D01*
X672027Y277460D01*
X672130Y277843D01*
X672389Y278111D01*
X672699Y278188D01*
X673009Y278150D01*
X673267Y277996D01*
X673784Y277230D01*
X674145Y276885D01*
X674662Y276655D01*
X675127Y276578D01*
Y278188D01*
G01Y280943D02*
X672027D01*
X674249Y279525D01*
Y281441D01*
G01X679127Y267316D02*
X676027D01*
Y268275D01*
X676182Y268581D01*
X676389Y268773D01*
X676802Y268850D01*
X677215Y268773D01*
X677474Y268543D01*
X677629Y268275D01*
Y267316D01*
G01Y268275D02*
X679127Y268850D01*
G01Y271183D02*
X676027D01*
X676647Y270723D01*
G01X679127D02*
Y271643D01*
G01X676027Y274283D02*
X676130Y273976D01*
X676389Y273746D01*
X676699Y273593D01*
X677112Y273478D01*
X677577Y273440D01*
X678042Y273478D01*
X678455Y273593D01*
X678765Y273746D01*
X679024Y273976D01*
X679127Y274283D01*
X679024Y274590D01*
X678765Y274820D01*
X678455Y274973D01*
X678042Y275088D01*
X677577Y275126D01*
X677112Y275088D01*
X676699Y274973D01*
X676389Y274820D01*
X676130Y274590D01*
X676027Y274283D01*
G01X679127Y277383D02*
X676027D01*
X676647Y276923D01*
G01X679127D02*
Y277843D01*
G01Y280406D02*
X678455Y280483D01*
X677887Y280598D01*
X677370Y280751D01*
X676802Y280943D01*
X676027Y281250D01*
Y279716D01*
G01X686899Y267616D02*
X683799D01*
Y268575D01*
X683954Y268881D01*
X684161Y269073D01*
X684574Y269150D01*
X684987Y269073D01*
X685246Y268843D01*
X685401Y268575D01*
Y267616D01*
G01Y268575D02*
X686899Y269150D01*
G01X685607Y270755D02*
X685246Y271023D01*
X685039Y271253D01*
X684936Y271560D01*
X685039Y271828D01*
X685246Y272020D01*
X685556Y272173D01*
X685917Y272211D01*
X686227Y272173D01*
X686537Y272020D01*
X686796Y271790D01*
X686899Y271521D01*
X686796Y271215D01*
X686486Y270946D01*
X686021Y270793D01*
X685504Y270755D01*
X684832Y270831D01*
X684471Y270946D01*
X684109Y271138D01*
X683851Y271406D01*
X683799Y271675D01*
X683902Y271943D01*
X684161Y272135D01*
G01X684316Y273855D02*
X684006Y274085D01*
X683851Y274353D01*
X683799Y274660D01*
X683902Y275043D01*
X684161Y275311D01*
X684471Y275388D01*
X684781Y275350D01*
X685039Y275196D01*
X685556Y274430D01*
X685917Y274085D01*
X686434Y273855D01*
X686899Y273778D01*
Y275388D01*
G01X686537Y277031D02*
X686796Y277300D01*
X686899Y277606D01*
X686796Y277913D01*
X686486Y278181D01*
X686021Y278373D01*
X685556Y278450D01*
X684987D01*
X684522Y278373D01*
X684109Y278181D01*
X683902Y277951D01*
X683799Y277683D01*
X683902Y277376D01*
X684109Y277146D01*
X684419Y276993D01*
X684832Y276916D01*
X685194Y276993D01*
X685556Y277185D01*
X685762Y277415D01*
X685814Y277683D01*
X685711Y277990D01*
X685452Y278220D01*
X684987Y278450D01*
G01X679140Y294360D02*
X680400D01*
G01X679140Y283200D02*
Y294360D01*
G01X680400D02*
X700690D01*
G01X683802Y282871D02*
X680702D01*
Y283830D01*
X680857Y284136D01*
X681064Y284328D01*
X681477Y284405D01*
X681890Y284328D01*
X682149Y284098D01*
X682304Y283830D01*
Y282871D01*
G01Y283830D02*
X683802Y284405D01*
G01X683337Y285895D02*
X683595Y286125D01*
X683750Y286393D01*
X683802Y286738D01*
X683699Y287083D01*
X683492Y287351D01*
X683130Y287543D01*
X682717Y287581D01*
X682304Y287505D01*
X682045Y287313D01*
X681839Y287045D01*
X681787Y286776D01*
X681839Y286508D01*
X682045Y286163D01*
X680702Y286278D01*
Y287313D01*
G01X683802Y289838D02*
X680702D01*
X681322Y289378D01*
G01X683802D02*
Y290298D01*
G01X683337Y292095D02*
X683595Y292325D01*
X683750Y292593D01*
X683802Y292938D01*
X683699Y293283D01*
X683492Y293551D01*
X683130Y293743D01*
X682717Y293781D01*
X682304Y293705D01*
X682045Y293513D01*
X681839Y293245D01*
X681787Y292976D01*
X681839Y292708D01*
X682045Y292363D01*
X680702Y292478D01*
Y293513D01*
G01X673808Y283973D02*
X670708D01*
Y284932D01*
X670863Y285238D01*
X671070Y285430D01*
X671483Y285507D01*
X671896Y285430D01*
X672155Y285200D01*
X672310Y284932D01*
Y283973D01*
G01Y284932D02*
X673808Y285507D01*
G01Y287840D02*
X670708D01*
X671328Y287380D01*
G01X673808D02*
Y288300D01*
G01Y290940D02*
X670708D01*
X671328Y290480D01*
G01X673808D02*
Y291400D01*
G01X670708Y294040D02*
X670811Y293733D01*
X671070Y293503D01*
X671380Y293350D01*
X671793Y293235D01*
X672258Y293197D01*
X672723Y293235D01*
X673136Y293350D01*
X673446Y293503D01*
X673705Y293733D01*
X673808Y294040D01*
X673705Y294347D01*
X673446Y294577D01*
X673136Y294730D01*
X672723Y294845D01*
X672258Y294883D01*
X671793Y294845D01*
X671380Y294730D01*
X671070Y294577D01*
X670811Y294347D01*
X670708Y294040D01*
G01X673343Y296297D02*
X673601Y296527D01*
X673756Y296795D01*
X673808Y297140D01*
X673705Y297485D01*
X673498Y297753D01*
X673136Y297945D01*
X672723Y297983D01*
X672310Y297907D01*
X672051Y297715D01*
X671845Y297447D01*
X671793Y297178D01*
X671845Y296910D01*
X672051Y296565D01*
X670708Y296680D01*
Y297715D01*
G01X673132Y302102D02*
Y305202D01*
X674052D01*
X674359Y305047D01*
X674589Y304685D01*
X674666Y304272D01*
X674589Y303859D01*
X674397Y303549D01*
X674052Y303394D01*
X673132D01*
G01X677842Y304944D02*
X677612Y305099D01*
X677344Y305202D01*
X677037D01*
X676692Y305047D01*
X676424Y304789D01*
X676232Y304479D01*
X676079Y303962D01*
X676041Y303497D01*
X676117Y303032D01*
X676232Y302722D01*
X676462Y302412D01*
X676731Y302205D01*
X676999Y302102D01*
X677267D01*
X677536Y302205D01*
X677766Y302360D01*
X677957Y302567D01*
G01X679371Y304685D02*
X679601Y304995D01*
X679869Y305150D01*
X680176Y305202D01*
X680559Y305099D01*
X680827Y304840D01*
X680904Y304530D01*
X680866Y304220D01*
X680712Y303962D01*
X679946Y303445D01*
X679601Y303084D01*
X679371Y302567D01*
X679294Y302102D01*
X680904D01*
G01X682471Y304685D02*
X682701Y304995D01*
X682969Y305150D01*
X683276Y305202D01*
X683659Y305099D01*
X683927Y304840D01*
X684004Y304530D01*
X683966Y304220D01*
X683812Y303962D01*
X683046Y303445D01*
X682701Y303084D01*
X682471Y302567D01*
X682394Y302102D01*
X684004D01*
G01X669878Y307844D02*
Y301044D01*
G01X678270Y362306D02*
X678430Y362556D01*
X678617Y362681D01*
X678830Y362723D01*
X679097Y362640D01*
X679284Y362431D01*
X679337Y362181D01*
X679310Y361931D01*
X679204Y361723D01*
X678670Y361306D01*
X678430Y361015D01*
X678270Y360598D01*
X678217Y360223D01*
X679337D01*
G01X676652Y352859D02*
Y354052D01*
G01Y364902D02*
Y366245D01*
G01X670940Y375197D02*
X671100Y374905D01*
X671314Y374739D01*
X671554Y374697D01*
X671767Y374739D01*
X671980Y374947D01*
X672114Y375197D01*
X672140Y375447D01*
X672087Y375739D01*
X671900Y375947D01*
X671714Y376030D01*
X671474D01*
G01X671714D02*
X671874Y376155D01*
X672007Y376364D01*
X672060Y376614D01*
X672007Y376864D01*
X671874Y377072D01*
X671634Y377197D01*
X671394Y377155D01*
X671154Y376989D01*
G01X674047Y374697D02*
Y377197D01*
X673060Y375405D01*
X674394D01*
G01X681013Y369380D02*
X680858Y369150D01*
X680755Y368882D01*
Y368575D01*
X680910Y368230D01*
X681168Y367962D01*
X681478Y367770D01*
X681995Y367617D01*
X682460Y367579D01*
X682925Y367655D01*
X683235Y367770D01*
X683545Y368000D01*
X683752Y368269D01*
X683855Y368537D01*
Y368805D01*
X683752Y369074D01*
X683597Y369304D01*
X683390Y369495D01*
G01X683235Y370794D02*
X683597Y371024D01*
X683803Y371330D01*
X683855Y371675D01*
X683803Y371982D01*
X683545Y372289D01*
X683235Y372480D01*
X682925Y372519D01*
X682563Y372442D01*
X682305Y372174D01*
X682202Y371905D01*
Y371560D01*
G01Y371905D02*
X682047Y372135D01*
X681788Y372327D01*
X681478Y372404D01*
X681168Y372327D01*
X680910Y372135D01*
X680755Y371790D01*
X680807Y371445D01*
X681013Y371100D01*
G01X682563Y374009D02*
X682202Y374277D01*
X681995Y374507D01*
X681892Y374814D01*
X681995Y375082D01*
X682202Y375274D01*
X682512Y375427D01*
X682873Y375465D01*
X683183Y375427D01*
X683493Y375274D01*
X683752Y375044D01*
X683855Y374775D01*
X683752Y374469D01*
X683442Y374200D01*
X682977Y374047D01*
X682460Y374009D01*
X681788Y374085D01*
X681427Y374200D01*
X681065Y374392D01*
X680807Y374660D01*
X680755Y374929D01*
X680858Y375197D01*
X681117Y375389D01*
G01X682563Y377109D02*
X682202Y377377D01*
X681995Y377607D01*
X681892Y377914D01*
X681995Y378182D01*
X682202Y378374D01*
X682512Y378527D01*
X682873Y378565D01*
X683183Y378527D01*
X683493Y378374D01*
X683752Y378144D01*
X683855Y377875D01*
X683752Y377569D01*
X683442Y377300D01*
X682977Y377147D01*
X682460Y377109D01*
X681788Y377185D01*
X681427Y377300D01*
X681065Y377492D01*
X680807Y377760D01*
X680755Y378029D01*
X680858Y378297D01*
X681117Y378489D01*
G01X669436Y371052D02*
Y368052D01*
G01X672536Y371152D02*
Y367952D01*
G01X673589Y371198D02*
X679789D01*
G01X673589Y367998D02*
Y371198D01*
G01X679789Y367998D02*
X673589D01*
G01X679789Y371198D02*
Y367998D01*
G01X675274Y381724D02*
X675434Y381432D01*
X675648Y381266D01*
X675888Y381224D01*
X676101Y381266D01*
X676314Y381474D01*
X676448Y381724D01*
X676474Y381974D01*
X676421Y382266D01*
X676234Y382474D01*
X676048Y382557D01*
X675808D01*
G01X676048D02*
X676208Y382682D01*
X676341Y382891D01*
X676394Y383141D01*
X676341Y383391D01*
X676208Y383599D01*
X675968Y383724D01*
X675728Y383682D01*
X675488Y383516D01*
G01X677474Y381599D02*
X677634Y381391D01*
X677821Y381266D01*
X678061Y381224D01*
X678301Y381307D01*
X678488Y381474D01*
X678621Y381766D01*
X678648Y382099D01*
X678594Y382432D01*
X678461Y382641D01*
X678274Y382807D01*
X678088Y382849D01*
X677901Y382807D01*
X677661Y382641D01*
X677741Y383724D01*
X678461D01*
G01X674186Y381637D02*
Y383937D01*
G01X671886Y381637D02*
X674186D01*
G01X676838Y384785D02*
X678838D01*
G01X676788Y392685D02*
X680288D01*
G01X676838Y400485D02*
X678838D01*
G01X671974Y414244D02*
X672134Y414036D01*
X672321Y413911D01*
X672561Y413869D01*
X672801Y413952D01*
X672988Y414119D01*
X673121Y414411D01*
X673148Y414744D01*
X673094Y415077D01*
X672961Y415286D01*
X672774Y415452D01*
X672588Y415494D01*
X672401Y415452D01*
X672161Y415286D01*
X672241Y416369D01*
X672961D01*
G01X674254Y415952D02*
X674414Y416202D01*
X674601Y416327D01*
X674814Y416369D01*
X675081Y416286D01*
X675268Y416077D01*
X675321Y415827D01*
X675294Y415577D01*
X675188Y415369D01*
X674654Y414952D01*
X674414Y414661D01*
X674254Y414244D01*
X674201Y413869D01*
X675321D01*
G01X676834Y410073D02*
X676994Y409865D01*
X677181Y409740D01*
X677421Y409698D01*
X677661Y409781D01*
X677848Y409948D01*
X677981Y410240D01*
X678008Y410573D01*
X677954Y410906D01*
X677821Y411115D01*
X677634Y411281D01*
X677448Y411323D01*
X677261Y411281D01*
X677021Y411115D01*
X677101Y412198D01*
X677821D01*
G01X679621Y409698D02*
Y412198D01*
X679301Y411698D01*
G01Y409698D02*
X679941D01*
G01X674186Y410833D02*
Y413133D01*
G01D02*
X671886D01*
G01X676888Y408385D02*
X680388D01*
G01X677291Y443685D02*
X677560Y443426D01*
X677866Y443323D01*
X678173Y443426D01*
X678441Y443736D01*
X678633Y444201D01*
X678710Y444666D01*
Y445235D01*
X678633Y445700D01*
X678441Y446113D01*
X678211Y446320D01*
X677943Y446423D01*
X677636Y446320D01*
X677406Y446113D01*
X677253Y445803D01*
X677176Y445390D01*
X677253Y445028D01*
X677445Y444666D01*
X677675Y444460D01*
X677943Y444408D01*
X678250Y444511D01*
X678480Y444770D01*
X678710Y445235D01*
G01X675556Y447260D02*
Y450360D01*
X675096Y449740D01*
G01Y447260D02*
X676016D01*
G01X678656Y450360D02*
X678349Y450257D01*
X678119Y449998D01*
X677966Y449688D01*
X677851Y449275D01*
X677813Y448810D01*
X677851Y448345D01*
X677966Y447932D01*
X678119Y447622D01*
X678349Y447363D01*
X678656Y447260D01*
X678963Y447363D01*
X679193Y447622D01*
X679346Y447932D01*
X679461Y448345D01*
X679499Y448810D01*
X679461Y449275D01*
X679346Y449688D01*
X679193Y449998D01*
X678963Y450257D01*
X678656Y450360D01*
G01X681880Y447260D02*
X682148Y447312D01*
X682455Y447467D01*
X682647Y447725D01*
X682723Y448087D01*
X682647Y448448D01*
X682417Y448758D01*
X682072Y448913D01*
X681688D01*
X681458Y449017D01*
X681267Y449275D01*
X681190Y449637D01*
X681305Y449998D01*
X681573Y450257D01*
X681880Y450360D01*
X682187Y450257D01*
X682455Y449998D01*
X682570Y449637D01*
X682493Y449275D01*
X682302Y449017D01*
X682072Y448913D01*
X681688D01*
X681343Y448758D01*
X681113Y448448D01*
X681037Y448087D01*
X681113Y447725D01*
X681305Y447467D01*
X681612Y447312D01*
X681880Y447260D01*
G01X672876Y453802D02*
Y497896D01*
G01X716970Y453802D02*
X672876D01*
G01Y497896D02*
X716970D01*
G01X670173Y521689D02*
Y515489D01*
G01X673484Y517775D02*
Y520975D01*
G01X679684Y517775D02*
X673484D01*
G01X679684Y520975D02*
Y517775D01*
G01X670723Y530870D02*
Y534070D01*
G01X676923Y530870D02*
X670723D01*
G01X676923Y534070D02*
Y530870D01*
G01X670706Y529243D02*
X673906D01*
G01X670706Y523043D02*
Y529243D01*
G01X673906Y523043D02*
X670706D01*
G01X673906Y529243D02*
Y523043D01*
G01X673484Y520975D02*
X679684D01*
G01X684894Y523178D02*
X683828D01*
Y525678D01*
X684894D01*
G01X684468Y524470D02*
X683828D01*
G01X678649Y522236D02*
Y534316D01*
G01X691123Y522236D02*
X678649D01*
G01X673823Y539252D02*
Y542252D01*
G01X670723Y539152D02*
Y542352D01*
G01X676923Y539152D02*
X670723D01*
G01X676923Y542352D02*
Y539152D01*
G01X670723Y542352D02*
X676923D01*
G01Y538352D02*
Y535152D01*
G01X670723Y538352D02*
X676923D01*
G01X670723Y535152D02*
Y538352D01*
G01X676923Y535152D02*
X670723D01*
G01Y543152D02*
Y546352D01*
G01X676923Y543152D02*
X670723D01*
G01X676923Y546352D02*
Y543152D01*
G01X670723Y546352D02*
X676923D01*
G01Y547152D02*
X670723D01*
G01X676923Y550352D02*
Y547152D01*
G01X670723D02*
Y550352D01*
G01Y534070D02*
X676923D01*
G01X684328Y534738D02*
X684536Y534898D01*
X684661Y535085D01*
X684703Y535325D01*
X684620Y535565D01*
X684453Y535752D01*
X684161Y535885D01*
X683828Y535912D01*
X683495Y535858D01*
X683286Y535725D01*
X683120Y535538D01*
X683078Y535352D01*
X683120Y535165D01*
X683286Y534925D01*
X682203Y535005D01*
Y535725D01*
G01X695703Y537223D02*
X679703D01*
G01Y549427D02*
X695703D01*
G01X679703Y537223D02*
Y549427D01*
G01X680650Y536421D02*
X680757Y536546D01*
X680837Y536755D01*
X680890Y537046D01*
X680837Y537296D01*
X680730Y537463D01*
X680544Y537588D01*
X679824D01*
Y535088D01*
X680704D01*
X680890Y535255D01*
X680997Y535505D01*
X681050Y535796D01*
X680997Y536088D01*
X680837Y536338D01*
X680650Y536421D01*
X679824D01*
G01X678649Y534316D02*
X691123D01*
G01X681008Y563265D02*
X680778Y563420D01*
X680510Y563523D01*
X680203D01*
X679858Y563368D01*
X679590Y563110D01*
X679398Y562800D01*
X679245Y562283D01*
X679207Y561818D01*
X679283Y561353D01*
X679398Y561043D01*
X679628Y560733D01*
X679897Y560526D01*
X680165Y560423D01*
X680433D01*
X680702Y560526D01*
X680932Y560681D01*
X681123Y560888D01*
G01X683725Y560423D02*
Y563523D01*
X682307Y561301D01*
X684223D01*
G01X685522Y561043D02*
X685752Y560681D01*
X686058Y560475D01*
X686403Y560423D01*
X686710Y560475D01*
X687017Y560733D01*
X687208Y561043D01*
X687247Y561353D01*
X687170Y561715D01*
X686902Y561973D01*
X686633Y562076D01*
X686288D01*
G01X686633D02*
X686863Y562231D01*
X687055Y562490D01*
X687132Y562800D01*
X687055Y563110D01*
X686863Y563368D01*
X686518Y563523D01*
X686173Y563471D01*
X685828Y563265D01*
G01X688813Y560785D02*
X689082Y560526D01*
X689388Y560423D01*
X689695Y560526D01*
X689963Y560836D01*
X690155Y561301D01*
X690232Y561766D01*
Y562335D01*
X690155Y562800D01*
X689963Y563213D01*
X689733Y563420D01*
X689465Y563523D01*
X689158Y563420D01*
X688928Y563213D01*
X688775Y562903D01*
X688698Y562490D01*
X688775Y562128D01*
X688967Y561766D01*
X689197Y561560D01*
X689465Y561508D01*
X689772Y561611D01*
X690002Y561870D01*
X690232Y562335D01*
G01X670723Y550352D02*
X676923D01*
G01X672953Y556487D02*
X669853D01*
Y557446D01*
X670008Y557752D01*
X670215Y557944D01*
X670628Y558021D01*
X671041Y557944D01*
X671300Y557714D01*
X671455Y557446D01*
Y556487D01*
G01Y557446D02*
X672953Y558021D01*
G01Y560354D02*
X669853D01*
X670473Y559894D01*
G01X672953D02*
Y560814D01*
G01Y563454D02*
X669853D01*
X670473Y562994D01*
G01X672953D02*
Y563914D01*
G01X671661Y565826D02*
X671300Y566094D01*
X671093Y566324D01*
X670990Y566631D01*
X671093Y566899D01*
X671300Y567091D01*
X671610Y567244D01*
X671971Y567282D01*
X672281Y567244D01*
X672591Y567091D01*
X672850Y566861D01*
X672953Y566592D01*
X672850Y566286D01*
X672540Y566017D01*
X672075Y565864D01*
X671558Y565826D01*
X670886Y565902D01*
X670525Y566017D01*
X670163Y566209D01*
X669905Y566477D01*
X669853Y566746D01*
X669956Y567014D01*
X670215Y567206D01*
G01X669229Y551704D02*
Y554804D01*
X670188D01*
X670494Y554649D01*
X670686Y554442D01*
X670763Y554029D01*
X670686Y553616D01*
X670456Y553357D01*
X670188Y553202D01*
X669229D01*
G01X670188D02*
X670763Y551704D01*
G01X672444Y552066D02*
X672713Y551807D01*
X673019Y551704D01*
X673326Y551807D01*
X673594Y552117D01*
X673786Y552582D01*
X673863Y553047D01*
Y553616D01*
X673786Y554081D01*
X673594Y554494D01*
X673364Y554701D01*
X673096Y554804D01*
X672789Y554701D01*
X672559Y554494D01*
X672406Y554184D01*
X672329Y553771D01*
X672406Y553409D01*
X672598Y553047D01*
X672828Y552841D01*
X673096Y552789D01*
X673403Y552892D01*
X673633Y553151D01*
X673863Y553616D01*
G01X675353Y552324D02*
X675583Y551962D01*
X675889Y551756D01*
X676234Y551704D01*
X676541Y551756D01*
X676848Y552014D01*
X677039Y552324D01*
X677078Y552634D01*
X677001Y552996D01*
X676733Y553254D01*
X676464Y553357D01*
X676119D01*
G01X676464D02*
X676694Y553512D01*
X676886Y553771D01*
X676963Y554081D01*
X676886Y554391D01*
X676694Y554649D01*
X676349Y554804D01*
X676004Y554752D01*
X675659Y554546D01*
G01X681255Y550802D02*
Y553302D01*
X680268Y551510D01*
X681602D01*
G01X681018Y579205D02*
X680788Y579360D01*
X680520Y579463D01*
X680213D01*
X679868Y579308D01*
X679600Y579050D01*
X679408Y578740D01*
X679255Y578223D01*
X679217Y577758D01*
X679293Y577293D01*
X679408Y576983D01*
X679638Y576673D01*
X679907Y576466D01*
X680175Y576363D01*
X680443D01*
X680712Y576466D01*
X680942Y576621D01*
X681133Y576828D01*
G01X683735Y576363D02*
Y579463D01*
X682317Y577241D01*
X684233D01*
G01X686835Y576363D02*
Y579463D01*
X685417Y577241D01*
X687333D01*
G01X689398Y576363D02*
X689475Y577035D01*
X689590Y577603D01*
X689743Y578120D01*
X689935Y578688D01*
X690242Y579463D01*
X688708D01*
G01X680888Y571545D02*
X680658Y571700D01*
X680390Y571803D01*
X680083D01*
X679738Y571648D01*
X679470Y571390D01*
X679278Y571080D01*
X679125Y570563D01*
X679087Y570098D01*
X679163Y569633D01*
X679278Y569323D01*
X679508Y569013D01*
X679777Y568806D01*
X680045Y568703D01*
X680313D01*
X680582Y568806D01*
X680812Y568961D01*
X681003Y569168D01*
G01X683605Y568703D02*
Y571803D01*
X682187Y569581D01*
X684103D01*
G01X686705Y568703D02*
Y571803D01*
X685287Y569581D01*
X687203D01*
G01X688617Y569995D02*
X688885Y570356D01*
X689115Y570563D01*
X689422Y570666D01*
X689690Y570563D01*
X689882Y570356D01*
X690035Y570046D01*
X690073Y569685D01*
X690035Y569375D01*
X689882Y569065D01*
X689652Y568806D01*
X689383Y568703D01*
X689077Y568806D01*
X688808Y569116D01*
X688655Y569581D01*
X688617Y570098D01*
X688693Y570770D01*
X688808Y571131D01*
X689000Y571493D01*
X689268Y571751D01*
X689537Y571803D01*
X689805Y571700D01*
X689997Y571441D01*
G01X680828Y586795D02*
X680598Y586950D01*
X680330Y587053D01*
X680023D01*
X679678Y586898D01*
X679410Y586640D01*
X679218Y586330D01*
X679065Y585813D01*
X679027Y585348D01*
X679103Y584883D01*
X679218Y584573D01*
X679448Y584263D01*
X679717Y584056D01*
X679985Y583953D01*
X680253D01*
X680522Y584056D01*
X680752Y584211D01*
X680943Y584418D01*
G01X683545Y583953D02*
Y587053D01*
X682127Y584831D01*
X684043D01*
G01X686645Y583953D02*
Y587053D01*
X685227Y584831D01*
X687143D01*
G01X688442Y584418D02*
X688672Y584160D01*
X688940Y584005D01*
X689285Y583953D01*
X689630Y584056D01*
X689898Y584263D01*
X690090Y584625D01*
X690128Y585038D01*
X690052Y585451D01*
X689860Y585710D01*
X689592Y585916D01*
X689323Y585968D01*
X689055Y585916D01*
X688710Y585710D01*
X688825Y587053D01*
X689860D01*
G01X670177Y636681D02*
X677264Y643768D01*
G01D02*
X670177Y650855D01*
G01Y629736D02*
Y636681D01*
G01X731595Y629736D02*
X670177D01*
G01Y650855D02*
Y657800D01*
G01D02*
X731595D01*
G01X677832Y670992D02*
X677602Y671147D01*
X677334Y671250D01*
X677027D01*
X676682Y671095D01*
X676414Y670837D01*
X676222Y670527D01*
X676069Y670010D01*
X676031Y669545D01*
X676107Y669080D01*
X676222Y668770D01*
X676452Y668460D01*
X676721Y668253D01*
X676989Y668150D01*
X677257D01*
X677526Y668253D01*
X677756Y668408D01*
X677947Y668615D01*
G01X679246D02*
X679476Y668357D01*
X679744Y668202D01*
X680089Y668150D01*
X680434Y668253D01*
X680702Y668460D01*
X680894Y668822D01*
X680932Y669235D01*
X680856Y669648D01*
X680664Y669907D01*
X680396Y670113D01*
X680127Y670165D01*
X679859Y670113D01*
X679514Y669907D01*
X679629Y671250D01*
X680664D01*
G01X682461Y669442D02*
X682729Y669803D01*
X682959Y670010D01*
X683266Y670113D01*
X683534Y670010D01*
X683726Y669803D01*
X683879Y669493D01*
X683917Y669132D01*
X683879Y668822D01*
X683726Y668512D01*
X683496Y668253D01*
X683227Y668150D01*
X682921Y668253D01*
X682652Y668563D01*
X682499Y669028D01*
X682461Y669545D01*
X682537Y670217D01*
X682652Y670578D01*
X682844Y670940D01*
X683112Y671198D01*
X683381Y671250D01*
X683649Y671147D01*
X683841Y670888D01*
G01X685446Y668770D02*
X685676Y668408D01*
X685982Y668202D01*
X686327Y668150D01*
X686634Y668202D01*
X686941Y668460D01*
X687132Y668770D01*
X687171Y669080D01*
X687094Y669442D01*
X686826Y669700D01*
X686557Y669803D01*
X686212D01*
G01X686557D02*
X686787Y669958D01*
X686979Y670217D01*
X687056Y670527D01*
X686979Y670837D01*
X686787Y671095D01*
X686442Y671250D01*
X686097Y671198D01*
X685752Y670992D01*
G01X670645Y740300D02*
Y743400D01*
G01X672255D02*
Y740300D01*
G01Y741850D02*
X670645D01*
G01X673822Y741592D02*
X674090Y741953D01*
X674320Y742160D01*
X674627Y742263D01*
X674895Y742160D01*
X675087Y741953D01*
X675240Y741643D01*
X675278Y741282D01*
X675240Y740972D01*
X675087Y740662D01*
X674857Y740403D01*
X674588Y740300D01*
X674282Y740403D01*
X674013Y740713D01*
X673860Y741178D01*
X673822Y741695D01*
X673898Y742367D01*
X674013Y742728D01*
X674205Y743090D01*
X674473Y743348D01*
X674742Y743400D01*
X675010Y743297D01*
X675202Y743038D01*
G01X681864Y785258D02*
X681971Y785383D01*
X682051Y785592D01*
X682104Y785883D01*
X682051Y786133D01*
X681944Y786300D01*
X681758Y786425D01*
X681038D01*
Y783925D01*
X681918D01*
X682104Y784092D01*
X682211Y784342D01*
X682264Y784633D01*
X682211Y784925D01*
X682051Y785175D01*
X681864Y785258D01*
X681038D01*
G01X683851Y783925D02*
Y786425D01*
X683531Y785925D01*
G01Y783925D02*
X684171D01*
G01X685544Y786008D02*
X685704Y786258D01*
X685891Y786383D01*
X686104Y786425D01*
X686371Y786342D01*
X686558Y786133D01*
X686611Y785883D01*
X686584Y785633D01*
X686478Y785425D01*
X685944Y785008D01*
X685704Y784717D01*
X685544Y784300D01*
X685491Y783925D01*
X686611D01*
G01X698819Y236D02*
Y-9607D01*
G01D02*
G03X718503I9842J0D01*
G01X696417Y236D02*
X698819D01*
G01X696417Y27508D02*
Y236D01*
G01X694868Y22704D02*
Y25204D01*
X694548Y24704D01*
G01Y22704D02*
X695188D01*
G01X696417Y36220D02*
Y26008D01*
G01X687443Y29288D02*
X687673Y29598D01*
X687941Y29753D01*
X688248Y29805D01*
X688631Y29702D01*
X688899Y29443D01*
X688976Y29133D01*
X688938Y28823D01*
X688784Y28565D01*
X688018Y28048D01*
X687673Y27687D01*
X687443Y27170D01*
X687366Y26705D01*
X688976D01*
G01X685947Y44197D02*
Y23409D01*
G01X689610Y45631D02*
X686510D01*
Y46590D01*
X686665Y46896D01*
X686872Y47088D01*
X687285Y47165D01*
X687698Y47088D01*
X687957Y46858D01*
X688112Y46590D01*
Y45631D01*
G01Y46590D02*
X689610Y47165D01*
G01Y49498D02*
X686510D01*
X687130Y49038D01*
G01X689610D02*
Y49958D01*
G01X687027Y51870D02*
X686717Y52100D01*
X686562Y52368D01*
X686510Y52675D01*
X686613Y53058D01*
X686872Y53326D01*
X687182Y53403D01*
X687492Y53365D01*
X687750Y53211D01*
X688267Y52445D01*
X688628Y52100D01*
X689145Y51870D01*
X689610Y51793D01*
Y53403D01*
G01Y55698D02*
X686510D01*
X687130Y55238D01*
G01X689610D02*
Y56158D01*
G01X687027Y58070D02*
X686717Y58300D01*
X686562Y58568D01*
X686510Y58875D01*
X686613Y59258D01*
X686872Y59526D01*
X687182Y59603D01*
X687492Y59565D01*
X687750Y59411D01*
X688267Y58645D01*
X688628Y58300D01*
X689145Y58070D01*
X689610Y57993D01*
Y59603D01*
G01X700415Y42403D02*
X697315D01*
Y43362D01*
X697470Y43668D01*
X697677Y43860D01*
X698090Y43937D01*
X698503Y43860D01*
X698762Y43630D01*
X698917Y43362D01*
Y42403D01*
G01Y43362D02*
X700415Y43937D01*
G01Y46270D02*
X700363Y46538D01*
X700208Y46845D01*
X699950Y47037D01*
X699588Y47113D01*
X699227Y47037D01*
X698917Y46807D01*
X698762Y46462D01*
Y46078D01*
X698658Y45848D01*
X698400Y45657D01*
X698038Y45580D01*
X697677Y45695D01*
X697418Y45963D01*
X697315Y46270D01*
X697418Y46577D01*
X697677Y46845D01*
X698038Y46960D01*
X698400Y46883D01*
X698658Y46692D01*
X698762Y46462D01*
Y46078D01*
X698917Y45733D01*
X699227Y45503D01*
X699588Y45427D01*
X699950Y45503D01*
X700208Y45695D01*
X700363Y46002D01*
X700415Y46270D01*
G01Y49370D02*
X697315D01*
X697935Y48910D01*
G01X700415D02*
Y49830D01*
G01X699795Y51627D02*
X700157Y51857D01*
X700363Y52163D01*
X700415Y52508D01*
X700363Y52815D01*
X700105Y53122D01*
X699795Y53313D01*
X699485Y53352D01*
X699123Y53275D01*
X698865Y53007D01*
X698762Y52738D01*
Y52393D01*
G01Y52738D02*
X698607Y52968D01*
X698348Y53160D01*
X698038Y53237D01*
X697728Y53160D01*
X697470Y52968D01*
X697315Y52623D01*
X697367Y52278D01*
X697573Y51933D01*
G01X694365Y32884D02*
X694525Y33134D01*
X694712Y33259D01*
X694925Y33301D01*
X695192Y33218D01*
X695379Y33009D01*
X695432Y32759D01*
X695405Y32509D01*
X695299Y32301D01*
X694765Y31884D01*
X694525Y31593D01*
X694365Y31176D01*
X694312Y30801D01*
X695432D01*
G01X720905Y36220D02*
X696417D01*
G01X687743Y41311D02*
Y44411D01*
X687283Y43791D01*
G01Y41311D02*
X688203D01*
G01X702438Y137972D02*
X700402D01*
G01X694411Y135688D02*
X692531D01*
G01X693549Y134323D02*
Y137053D01*
G01X698854Y138540D02*
Y141640D01*
G01X698954Y141240D02*
X698854Y138540D01*
G01X692161Y138368D02*
X699169D01*
G01X692161Y141912D02*
Y138368D01*
G01X699248D02*
Y141912D01*
G01X693648Y171359D02*
Y155359D01*
G01X699248Y141912D02*
X692161D01*
G01X692437Y143471D02*
Y146671D01*
G01X698637Y143471D02*
X692437D01*
G01X698637Y146671D02*
Y143471D01*
G01X692437Y146671D02*
X698637D01*
G01X695537Y143571D02*
Y146571D01*
G01X692437Y147971D02*
Y151171D01*
G01X698637Y147971D02*
X692437D01*
G01X698637Y151171D02*
Y147971D01*
G01X692437Y151171D02*
X698637D01*
G01X695537Y148071D02*
Y151071D01*
G01X695153Y159856D02*
X697375D01*
X697840Y160009D01*
X698150Y160316D01*
X698253Y160699D01*
X698150Y161082D01*
X697840Y161389D01*
X697375Y161542D01*
X695153D01*
G01X697788Y162956D02*
X698046Y163186D01*
X698201Y163454D01*
X698253Y163799D01*
X698150Y164144D01*
X697943Y164412D01*
X697581Y164604D01*
X697168Y164642D01*
X696755Y164566D01*
X696496Y164374D01*
X696290Y164106D01*
X696238Y163837D01*
X696290Y163569D01*
X696496Y163224D01*
X695153Y163339D01*
Y164374D01*
G01X697633Y166056D02*
X697995Y166286D01*
X698201Y166592D01*
X698253Y166937D01*
X698201Y167244D01*
X697943Y167551D01*
X697633Y167742D01*
X697323Y167781D01*
X696961Y167704D01*
X696703Y167436D01*
X696600Y167167D01*
Y166822D01*
G01Y167167D02*
X696445Y167397D01*
X696186Y167589D01*
X695876Y167666D01*
X695566Y167589D01*
X695308Y167397D01*
X695153Y167052D01*
X695205Y166707D01*
X695411Y166362D01*
G01X689530Y184583D02*
Y187083D01*
X689210Y186583D01*
G01Y184583D02*
X689850D01*
G01X684945Y202246D02*
Y215900D01*
G01X699364Y204351D02*
Y187812D01*
G01D02*
X691096D01*
G01D02*
Y204351D01*
G01X687638Y215195D02*
X689518D01*
G01X688500Y216560D02*
Y213830D01*
G01X690524Y206601D02*
Y209101D01*
X690204Y208601D01*
G01Y206601D02*
X690844D01*
G01X691947Y208657D02*
X693593D01*
G01X700123Y213904D02*
X693115D01*
G01X693036Y210360D02*
X700123D01*
G01X693036Y213904D02*
Y210360D01*
G01X693430Y213732D02*
Y210632D01*
G01X693330Y211032D02*
X693430Y213732D01*
G01X691096Y204351D02*
X699364D01*
G01X696475Y218368D02*
Y215368D01*
G01X699575Y218468D02*
Y215268D01*
G01X693375Y218468D02*
X699575D01*
G01X693375Y215268D02*
Y218468D01*
G01X699575Y215268D02*
X693375D01*
G01X693686Y250165D02*
Y234165D01*
G01X696475Y222868D02*
Y219868D01*
G01X699575Y222968D02*
Y219768D01*
G01X693375Y222968D02*
X699575D01*
G01X693375Y219768D02*
Y222968D01*
G01X699575Y219768D02*
X693375D01*
G01X694899Y238387D02*
X697121D01*
X697586Y238540D01*
X697896Y238847D01*
X697999Y239230D01*
X697896Y239613D01*
X697586Y239920D01*
X697121Y240073D01*
X694899D01*
G01X697534Y241487D02*
X697792Y241717D01*
X697947Y241985D01*
X697999Y242330D01*
X697896Y242675D01*
X697689Y242943D01*
X697327Y243135D01*
X696914Y243173D01*
X696501Y243097D01*
X696242Y242905D01*
X696036Y242637D01*
X695984Y242368D01*
X696036Y242100D01*
X696242Y241755D01*
X694899Y241870D01*
Y242905D01*
G01X697999Y245890D02*
X694899D01*
X697121Y244472D01*
Y246388D01*
G01X695956Y269226D02*
X695801Y268996D01*
X695698Y268728D01*
Y268421D01*
X695853Y268076D01*
X696111Y267808D01*
X696421Y267616D01*
X696938Y267463D01*
X697403Y267425D01*
X697868Y267501D01*
X698178Y267616D01*
X698488Y267846D01*
X698695Y268115D01*
X698798Y268383D01*
Y268651D01*
X698695Y268920D01*
X698540Y269150D01*
X698333Y269341D01*
G01X698798Y271943D02*
X695698D01*
X697920Y270525D01*
Y272441D01*
G01X698436Y273931D02*
X698695Y274200D01*
X698798Y274506D01*
X698695Y274813D01*
X698385Y275081D01*
X697920Y275273D01*
X697455Y275350D01*
X696886D01*
X696421Y275273D01*
X696008Y275081D01*
X695801Y274851D01*
X695698Y274583D01*
X695801Y274276D01*
X696008Y274046D01*
X696318Y273893D01*
X696731Y273816D01*
X697093Y273893D01*
X697455Y274085D01*
X697661Y274315D01*
X697713Y274583D01*
X697610Y274890D01*
X697351Y275120D01*
X696886Y275350D01*
G01X698333Y276840D02*
X698591Y277070D01*
X698746Y277338D01*
X698798Y277683D01*
X698695Y278028D01*
X698488Y278296D01*
X698126Y278488D01*
X697713Y278526D01*
X697300Y278450D01*
X697041Y278258D01*
X696835Y277990D01*
X696783Y277721D01*
X696835Y277453D01*
X697041Y277108D01*
X695698Y277223D01*
Y278258D01*
G01X691956Y269226D02*
X691801Y268996D01*
X691698Y268728D01*
Y268421D01*
X691853Y268076D01*
X692111Y267808D01*
X692421Y267616D01*
X692938Y267463D01*
X693403Y267425D01*
X693868Y267501D01*
X694178Y267616D01*
X694488Y267846D01*
X694695Y268115D01*
X694798Y268383D01*
Y268651D01*
X694695Y268920D01*
X694540Y269150D01*
X694333Y269341D01*
G01X694798Y271943D02*
X691698D01*
X693920Y270525D01*
Y272441D01*
G01X694436Y273931D02*
X694695Y274200D01*
X694798Y274506D01*
X694695Y274813D01*
X694385Y275081D01*
X693920Y275273D01*
X693455Y275350D01*
X692886D01*
X692421Y275273D01*
X692008Y275081D01*
X691801Y274851D01*
X691698Y274583D01*
X691801Y274276D01*
X692008Y274046D01*
X692318Y273893D01*
X692731Y273816D01*
X693093Y273893D01*
X693455Y274085D01*
X693661Y274315D01*
X693713Y274583D01*
X693610Y274890D01*
X693351Y275120D01*
X692886Y275350D01*
G01X693506Y276955D02*
X693145Y277223D01*
X692938Y277453D01*
X692835Y277760D01*
X692938Y278028D01*
X693145Y278220D01*
X693455Y278373D01*
X693816Y278411D01*
X694126Y278373D01*
X694436Y278220D01*
X694695Y277990D01*
X694798Y277721D01*
X694695Y277415D01*
X694385Y277146D01*
X693920Y276993D01*
X693403Y276955D01*
X692731Y277031D01*
X692370Y277146D01*
X692008Y277338D01*
X691750Y277606D01*
X691698Y277875D01*
X691801Y278143D01*
X692060Y278335D01*
G01X690899Y267616D02*
X687799D01*
Y268575D01*
X687954Y268881D01*
X688161Y269073D01*
X688574Y269150D01*
X688987Y269073D01*
X689246Y268843D01*
X689401Y268575D01*
Y267616D01*
G01Y268575D02*
X690899Y269150D01*
G01X689607Y270755D02*
X689246Y271023D01*
X689039Y271253D01*
X688936Y271560D01*
X689039Y271828D01*
X689246Y272020D01*
X689556Y272173D01*
X689917Y272211D01*
X690227Y272173D01*
X690537Y272020D01*
X690796Y271790D01*
X690899Y271521D01*
X690796Y271215D01*
X690486Y270946D01*
X690021Y270793D01*
X689504Y270755D01*
X688832Y270831D01*
X688471Y270946D01*
X688109Y271138D01*
X687851Y271406D01*
X687799Y271675D01*
X687902Y271943D01*
X688161Y272135D01*
G01X690279Y273740D02*
X690641Y273970D01*
X690847Y274276D01*
X690899Y274621D01*
X690847Y274928D01*
X690589Y275235D01*
X690279Y275426D01*
X689969Y275465D01*
X689607Y275388D01*
X689349Y275120D01*
X689246Y274851D01*
Y274506D01*
G01Y274851D02*
X689091Y275081D01*
X688832Y275273D01*
X688522Y275350D01*
X688212Y275273D01*
X687954Y275081D01*
X687799Y274736D01*
X687851Y274391D01*
X688057Y274046D01*
G01X687799Y277683D02*
X687902Y277376D01*
X688161Y277146D01*
X688471Y276993D01*
X688884Y276878D01*
X689349Y276840D01*
X689814Y276878D01*
X690227Y276993D01*
X690537Y277146D01*
X690796Y277376D01*
X690899Y277683D01*
X690796Y277990D01*
X690537Y278220D01*
X690227Y278373D01*
X689814Y278488D01*
X689349Y278526D01*
X688884Y278488D01*
X688471Y278373D01*
X688161Y278220D01*
X687902Y277990D01*
X687799Y277683D01*
G01X695802Y282871D02*
X692702D01*
Y283830D01*
X692857Y284136D01*
X693064Y284328D01*
X693477Y284405D01*
X693890Y284328D01*
X694149Y284098D01*
X694304Y283830D01*
Y282871D01*
G01Y283830D02*
X695802Y284405D01*
G01X695337Y285895D02*
X695595Y286125D01*
X695750Y286393D01*
X695802Y286738D01*
X695699Y287083D01*
X695492Y287351D01*
X695130Y287543D01*
X694717Y287581D01*
X694304Y287505D01*
X694045Y287313D01*
X693839Y287045D01*
X693787Y286776D01*
X693839Y286508D01*
X694045Y286163D01*
X692702Y286278D01*
Y287313D01*
G01X695802Y289838D02*
X692702D01*
X693322Y289378D01*
G01X695802D02*
Y290298D01*
G01Y292861D02*
X695130Y292938D01*
X694562Y293053D01*
X694045Y293206D01*
X693477Y293398D01*
X692702Y293705D01*
Y292171D01*
G01X699802Y282871D02*
X696702D01*
Y283830D01*
X696857Y284136D01*
X697064Y284328D01*
X697477Y284405D01*
X697890Y284328D01*
X698149Y284098D01*
X698304Y283830D01*
Y282871D01*
G01Y283830D02*
X699802Y284405D01*
G01X699337Y285895D02*
X699595Y286125D01*
X699750Y286393D01*
X699802Y286738D01*
X699699Y287083D01*
X699492Y287351D01*
X699130Y287543D01*
X698717Y287581D01*
X698304Y287505D01*
X698045Y287313D01*
X697839Y287045D01*
X697787Y286776D01*
X697839Y286508D01*
X698045Y286163D01*
X696702Y286278D01*
Y287313D01*
G01X699802Y289838D02*
X696702D01*
X697322Y289378D01*
G01X699802D02*
Y290298D01*
G01Y292938D02*
X699750Y293206D01*
X699595Y293513D01*
X699337Y293705D01*
X698975Y293781D01*
X698614Y293705D01*
X698304Y293475D01*
X698149Y293130D01*
Y292746D01*
X698045Y292516D01*
X697787Y292325D01*
X697425Y292248D01*
X697064Y292363D01*
X696805Y292631D01*
X696702Y292938D01*
X696805Y293245D01*
X697064Y293513D01*
X697425Y293628D01*
X697787Y293551D01*
X698045Y293360D01*
X698149Y293130D01*
Y292746D01*
X698304Y292401D01*
X698614Y292171D01*
X698975Y292095D01*
X699337Y292171D01*
X699595Y292363D01*
X699750Y292670D01*
X699802Y292938D01*
G01X691802Y282871D02*
X688702D01*
Y283830D01*
X688857Y284136D01*
X689064Y284328D01*
X689477Y284405D01*
X689890Y284328D01*
X690149Y284098D01*
X690304Y283830D01*
Y282871D01*
G01Y283830D02*
X691802Y284405D01*
G01X691337Y285895D02*
X691595Y286125D01*
X691750Y286393D01*
X691802Y286738D01*
X691699Y287083D01*
X691492Y287351D01*
X691130Y287543D01*
X690717Y287581D01*
X690304Y287505D01*
X690045Y287313D01*
X689839Y287045D01*
X689787Y286776D01*
X689839Y286508D01*
X690045Y286163D01*
X688702Y286278D01*
Y287313D01*
G01Y289838D02*
X688805Y289531D01*
X689064Y289301D01*
X689374Y289148D01*
X689787Y289033D01*
X690252Y288995D01*
X690717Y289033D01*
X691130Y289148D01*
X691440Y289301D01*
X691699Y289531D01*
X691802Y289838D01*
X691699Y290145D01*
X691440Y290375D01*
X691130Y290528D01*
X690717Y290643D01*
X690252Y290681D01*
X689787Y290643D01*
X689374Y290528D01*
X689064Y290375D01*
X688805Y290145D01*
X688702Y289838D01*
G01X689219Y292210D02*
X688909Y292440D01*
X688754Y292708D01*
X688702Y293015D01*
X688805Y293398D01*
X689064Y293666D01*
X689374Y293743D01*
X689684Y293705D01*
X689942Y293551D01*
X690459Y292785D01*
X690820Y292440D01*
X691337Y292210D01*
X691802Y292133D01*
Y293743D01*
G01X687802Y282871D02*
X684702D01*
Y283830D01*
X684857Y284136D01*
X685064Y284328D01*
X685477Y284405D01*
X685890Y284328D01*
X686149Y284098D01*
X686304Y283830D01*
Y282871D01*
G01Y283830D02*
X687802Y284405D01*
G01X687337Y285895D02*
X687595Y286125D01*
X687750Y286393D01*
X687802Y286738D01*
X687699Y287083D01*
X687492Y287351D01*
X687130Y287543D01*
X686717Y287581D01*
X686304Y287505D01*
X686045Y287313D01*
X685839Y287045D01*
X685787Y286776D01*
X685839Y286508D01*
X686045Y286163D01*
X684702Y286278D01*
Y287313D01*
G01X687802Y289838D02*
X684702D01*
X685322Y289378D01*
G01X687802D02*
Y290298D01*
G01Y293398D02*
X684702D01*
X686924Y291980D01*
Y293896D01*
G01X755810Y343180D02*
X694990D01*
G01X745650Y386060D02*
Y426220D01*
X694990D01*
Y343180D01*
G01X698937Y359143D02*
Y364143D01*
X700203D01*
X700710Y363893D01*
X701090Y363560D01*
X701407Y363060D01*
X701660Y362476D01*
X701723Y361643D01*
X701660Y360810D01*
X701407Y360226D01*
X701090Y359726D01*
X700710Y359393D01*
X700203Y359143D01*
X698937D01*
G01X695291Y365892D02*
X706255D01*
Y357490D01*
X695052D01*
G01X684977Y369380D02*
X684822Y369150D01*
X684719Y368882D01*
Y368575D01*
X684874Y368230D01*
X685132Y367962D01*
X685442Y367770D01*
X685959Y367617D01*
X686424Y367579D01*
X686889Y367655D01*
X687199Y367770D01*
X687509Y368000D01*
X687716Y368269D01*
X687819Y368537D01*
Y368805D01*
X687716Y369074D01*
X687561Y369304D01*
X687354Y369495D01*
G01X687199Y370794D02*
X687561Y371024D01*
X687767Y371330D01*
X687819Y371675D01*
X687767Y371982D01*
X687509Y372289D01*
X687199Y372480D01*
X686889Y372519D01*
X686527Y372442D01*
X686269Y372174D01*
X686166Y371905D01*
Y371560D01*
G01Y371905D02*
X686011Y372135D01*
X685752Y372327D01*
X685442Y372404D01*
X685132Y372327D01*
X684874Y372135D01*
X684719Y371790D01*
X684771Y371445D01*
X684977Y371100D01*
G01X686527Y374009D02*
X686166Y374277D01*
X685959Y374507D01*
X685856Y374814D01*
X685959Y375082D01*
X686166Y375274D01*
X686476Y375427D01*
X686837Y375465D01*
X687147Y375427D01*
X687457Y375274D01*
X687716Y375044D01*
X687819Y374775D01*
X687716Y374469D01*
X687406Y374200D01*
X686941Y374047D01*
X686424Y374009D01*
X685752Y374085D01*
X685391Y374200D01*
X685029Y374392D01*
X684771Y374660D01*
X684719Y374929D01*
X684822Y375197D01*
X685081Y375389D01*
G01X687354Y376994D02*
X687612Y377224D01*
X687767Y377492D01*
X687819Y377837D01*
X687716Y378182D01*
X687509Y378450D01*
X687147Y378642D01*
X686734Y378680D01*
X686321Y378604D01*
X686062Y378412D01*
X685856Y378144D01*
X685804Y377875D01*
X685856Y377607D01*
X686062Y377262D01*
X684719Y377377D01*
Y378412D01*
G01X698003Y374539D02*
X697773Y374694D01*
X697505Y374797D01*
X697198D01*
X696853Y374642D01*
X696585Y374384D01*
X696393Y374074D01*
X696240Y373557D01*
X696202Y373092D01*
X696278Y372627D01*
X696393Y372317D01*
X696623Y372007D01*
X696892Y371800D01*
X697160Y371697D01*
X697428D01*
X697697Y371800D01*
X697927Y371955D01*
X698118Y372162D01*
G01X699417D02*
X699647Y371904D01*
X699915Y371749D01*
X700260Y371697D01*
X700605Y371800D01*
X700873Y372007D01*
X701065Y372369D01*
X701103Y372782D01*
X701027Y373195D01*
X700835Y373454D01*
X700567Y373660D01*
X700298Y373712D01*
X700030Y373660D01*
X699685Y373454D01*
X699800Y374797D01*
X700835D01*
G01X703360Y371697D02*
X703628Y371749D01*
X703935Y371904D01*
X704127Y372162D01*
X704203Y372524D01*
X704127Y372885D01*
X703897Y373195D01*
X703552Y373350D01*
X703168D01*
X702938Y373454D01*
X702747Y373712D01*
X702670Y374074D01*
X702785Y374435D01*
X703053Y374694D01*
X703360Y374797D01*
X703667Y374694D01*
X703935Y374435D01*
X704050Y374074D01*
X703973Y373712D01*
X703782Y373454D01*
X703552Y373350D01*
X703168D01*
X702823Y373195D01*
X702593Y372885D01*
X702517Y372524D01*
X702593Y372162D01*
X702785Y371904D01*
X703092Y371749D01*
X703360Y371697D01*
G01X706460D02*
Y374797D01*
X706000Y374177D01*
G01Y371697D02*
X706920D01*
G01X692061Y367770D02*
X688961D01*
Y368729D01*
X689116Y369035D01*
X689323Y369227D01*
X689736Y369304D01*
X690149Y369227D01*
X690408Y368997D01*
X690563Y368729D01*
Y367770D01*
G01Y368729D02*
X692061Y369304D01*
G01X691596Y370794D02*
X691854Y371024D01*
X692009Y371292D01*
X692061Y371637D01*
X691958Y371982D01*
X691751Y372250D01*
X691389Y372442D01*
X690976Y372480D01*
X690563Y372404D01*
X690304Y372212D01*
X690098Y371944D01*
X690046Y371675D01*
X690098Y371407D01*
X690304Y371062D01*
X688961Y371177D01*
Y372212D01*
G01X689478Y374009D02*
X689168Y374239D01*
X689013Y374507D01*
X688961Y374814D01*
X689064Y375197D01*
X689323Y375465D01*
X689633Y375542D01*
X689943Y375504D01*
X690201Y375350D01*
X690718Y374584D01*
X691079Y374239D01*
X691596Y374009D01*
X692061Y373932D01*
Y375542D01*
G01X690769Y377109D02*
X690408Y377377D01*
X690201Y377607D01*
X690098Y377914D01*
X690201Y378182D01*
X690408Y378374D01*
X690718Y378527D01*
X691079Y378565D01*
X691389Y378527D01*
X691699Y378374D01*
X691958Y378144D01*
X692061Y377875D01*
X691958Y377569D01*
X691648Y377300D01*
X691183Y377147D01*
X690666Y377109D01*
X689994Y377185D01*
X689633Y377300D01*
X689271Y377492D01*
X689013Y377760D01*
X688961Y378029D01*
X689064Y378297D01*
X689323Y378489D01*
G01X696483Y367167D02*
Y370267D01*
X697442D01*
X697748Y370112D01*
X697940Y369905D01*
X698017Y369492D01*
X697940Y369079D01*
X697710Y368820D01*
X697442Y368665D01*
X696483D01*
G01X697442D02*
X698017Y367167D01*
G01X700350D02*
X700618Y367219D01*
X700925Y367374D01*
X701117Y367632D01*
X701193Y367994D01*
X701117Y368355D01*
X700887Y368665D01*
X700542Y368820D01*
X700158D01*
X699928Y368924D01*
X699737Y369182D01*
X699660Y369544D01*
X699775Y369905D01*
X700043Y370164D01*
X700350Y370267D01*
X700657Y370164D01*
X700925Y369905D01*
X701040Y369544D01*
X700963Y369182D01*
X700772Y368924D01*
X700542Y368820D01*
X700158D01*
X699813Y368665D01*
X699583Y368355D01*
X699507Y367994D01*
X699583Y367632D01*
X699775Y367374D01*
X700082Y367219D01*
X700350Y367167D01*
G01X703450Y370267D02*
X703143Y370164D01*
X702913Y369905D01*
X702760Y369595D01*
X702645Y369182D01*
X702607Y368717D01*
X702645Y368252D01*
X702760Y367839D01*
X702913Y367529D01*
X703143Y367270D01*
X703450Y367167D01*
X703757Y367270D01*
X703987Y367529D01*
X704140Y367839D01*
X704255Y368252D01*
X704293Y368717D01*
X704255Y369182D01*
X704140Y369595D01*
X703987Y369905D01*
X703757Y370164D01*
X703450Y370267D01*
G01X706550Y367167D02*
Y370267D01*
X706090Y369647D01*
G01Y367167D02*
X707010D01*
G01X696393Y375797D02*
Y378897D01*
X697352D01*
X697658Y378742D01*
X697850Y378535D01*
X697927Y378122D01*
X697850Y377709D01*
X697620Y377450D01*
X697352Y377295D01*
X696393D01*
G01X697352D02*
X697927Y375797D01*
G01X699608Y376159D02*
X699877Y375900D01*
X700183Y375797D01*
X700490Y375900D01*
X700758Y376210D01*
X700950Y376675D01*
X701027Y377140D01*
Y377709D01*
X700950Y378174D01*
X700758Y378587D01*
X700528Y378794D01*
X700260Y378897D01*
X699953Y378794D01*
X699723Y378587D01*
X699570Y378277D01*
X699493Y377864D01*
X699570Y377502D01*
X699762Y377140D01*
X699992Y376934D01*
X700260Y376882D01*
X700567Y376985D01*
X700797Y377244D01*
X701027Y377709D01*
G01X703360Y375797D02*
Y378897D01*
X702900Y378277D01*
G01Y375797D02*
X703820D01*
G01X706460D02*
X706728Y375849D01*
X707035Y376004D01*
X707227Y376262D01*
X707303Y376624D01*
X707227Y376985D01*
X706997Y377295D01*
X706652Y377450D01*
X706268D01*
X706038Y377554D01*
X705847Y377812D01*
X705770Y378174D01*
X705885Y378535D01*
X706153Y378794D01*
X706460Y378897D01*
X706767Y378794D01*
X707035Y378535D01*
X707150Y378174D01*
X707073Y377812D01*
X706882Y377554D01*
X706652Y377450D01*
X706268D01*
X705923Y377295D01*
X705693Y376985D01*
X705617Y376624D01*
X705693Y376262D01*
X705885Y376004D01*
X706192Y375849D01*
X706460Y375797D01*
G01X698003Y391836D02*
X697773Y391991D01*
X697505Y392094D01*
X697198D01*
X696853Y391939D01*
X696585Y391681D01*
X696393Y391371D01*
X696240Y390854D01*
X696202Y390389D01*
X696278Y389924D01*
X696393Y389614D01*
X696623Y389304D01*
X696892Y389097D01*
X697160Y388994D01*
X697428D01*
X697697Y389097D01*
X697927Y389252D01*
X698118Y389459D01*
G01X699608Y389356D02*
X699877Y389097D01*
X700183Y388994D01*
X700490Y389097D01*
X700758Y389407D01*
X700950Y389872D01*
X701027Y390337D01*
Y390906D01*
X700950Y391371D01*
X700758Y391784D01*
X700528Y391991D01*
X700260Y392094D01*
X699953Y391991D01*
X699723Y391784D01*
X699570Y391474D01*
X699493Y391061D01*
X699570Y390699D01*
X699762Y390337D01*
X699992Y390131D01*
X700260Y390079D01*
X700567Y390182D01*
X700797Y390441D01*
X701027Y390906D01*
G01X703360Y392094D02*
X703053Y391991D01*
X702823Y391732D01*
X702670Y391422D01*
X702555Y391009D01*
X702517Y390544D01*
X702555Y390079D01*
X702670Y389666D01*
X702823Y389356D01*
X703053Y389097D01*
X703360Y388994D01*
X703667Y389097D01*
X703897Y389356D01*
X704050Y389666D01*
X704165Y390079D01*
X704203Y390544D01*
X704165Y391009D01*
X704050Y391422D01*
X703897Y391732D01*
X703667Y391991D01*
X703360Y392094D01*
G01X705808Y389356D02*
X706077Y389097D01*
X706383Y388994D01*
X706690Y389097D01*
X706958Y389407D01*
X707150Y389872D01*
X707227Y390337D01*
Y390906D01*
X707150Y391371D01*
X706958Y391784D01*
X706728Y391991D01*
X706460Y392094D01*
X706153Y391991D01*
X705923Y391784D01*
X705770Y391474D01*
X705693Y391061D01*
X705770Y390699D01*
X705962Y390337D01*
X706192Y390131D01*
X706460Y390079D01*
X706767Y390182D01*
X706997Y390441D01*
X707227Y390906D01*
G01X696393Y384635D02*
Y387735D01*
X697352D01*
X697658Y387580D01*
X697850Y387373D01*
X697927Y386960D01*
X697850Y386547D01*
X697620Y386288D01*
X697352Y386133D01*
X696393D01*
G01X697352D02*
X697927Y384635D01*
G01X699608Y384997D02*
X699877Y384738D01*
X700183Y384635D01*
X700490Y384738D01*
X700758Y385048D01*
X700950Y385513D01*
X701027Y385978D01*
Y386547D01*
X700950Y387012D01*
X700758Y387425D01*
X700528Y387632D01*
X700260Y387735D01*
X699953Y387632D01*
X699723Y387425D01*
X699570Y387115D01*
X699493Y386702D01*
X699570Y386340D01*
X699762Y385978D01*
X699992Y385772D01*
X700260Y385720D01*
X700567Y385823D01*
X700797Y386082D01*
X701027Y386547D01*
G01X703820Y384635D02*
Y387735D01*
X702402Y385513D01*
X704318D01*
G01X705732Y387218D02*
X705962Y387528D01*
X706230Y387683D01*
X706537Y387735D01*
X706920Y387632D01*
X707188Y387373D01*
X707265Y387063D01*
X707227Y386753D01*
X707073Y386495D01*
X706307Y385978D01*
X705962Y385617D01*
X705732Y385100D01*
X705655Y384635D01*
X707265D01*
G01X696393Y380343D02*
Y383443D01*
X697352D01*
X697658Y383288D01*
X697850Y383081D01*
X697927Y382668D01*
X697850Y382255D01*
X697620Y381996D01*
X697352Y381841D01*
X696393D01*
G01X697352D02*
X697927Y380343D01*
G01X699608Y380705D02*
X699877Y380446D01*
X700183Y380343D01*
X700490Y380446D01*
X700758Y380756D01*
X700950Y381221D01*
X701027Y381686D01*
Y382255D01*
X700950Y382720D01*
X700758Y383133D01*
X700528Y383340D01*
X700260Y383443D01*
X699953Y383340D01*
X699723Y383133D01*
X699570Y382823D01*
X699493Y382410D01*
X699570Y382048D01*
X699762Y381686D01*
X699992Y381480D01*
X700260Y381428D01*
X700567Y381531D01*
X700797Y381790D01*
X701027Y382255D01*
G01X702517Y380963D02*
X702747Y380601D01*
X703053Y380395D01*
X703398Y380343D01*
X703705Y380395D01*
X704012Y380653D01*
X704203Y380963D01*
X704242Y381273D01*
X704165Y381635D01*
X703897Y381893D01*
X703628Y381996D01*
X703283D01*
G01X703628D02*
X703858Y382151D01*
X704050Y382410D01*
X704127Y382720D01*
X704050Y383030D01*
X703858Y383288D01*
X703513Y383443D01*
X703168Y383391D01*
X702823Y383185D01*
G01X705732Y381635D02*
X706000Y381996D01*
X706230Y382203D01*
X706537Y382306D01*
X706805Y382203D01*
X706997Y381996D01*
X707150Y381686D01*
X707188Y381325D01*
X707150Y381015D01*
X706997Y380705D01*
X706767Y380446D01*
X706498Y380343D01*
X706192Y380446D01*
X705923Y380756D01*
X705770Y381221D01*
X705732Y381738D01*
X705808Y382410D01*
X705923Y382771D01*
X706115Y383133D01*
X706383Y383391D01*
X706652Y383443D01*
X706920Y383340D01*
X707112Y383081D01*
G01X696393Y405186D02*
Y408286D01*
X697352D01*
X697658Y408131D01*
X697850Y407924D01*
X697927Y407511D01*
X697850Y407098D01*
X697620Y406839D01*
X697352Y406684D01*
X696393D01*
G01X697352D02*
X697927Y405186D01*
G01X700260D02*
Y408286D01*
X699800Y407666D01*
G01Y405186D02*
X700720D01*
G01X702632Y407769D02*
X702862Y408079D01*
X703130Y408234D01*
X703437Y408286D01*
X703820Y408183D01*
X704088Y407924D01*
X704165Y407614D01*
X704127Y407304D01*
X703973Y407046D01*
X703207Y406529D01*
X702862Y406168D01*
X702632Y405651D01*
X702555Y405186D01*
X704165D01*
G01X705617Y405651D02*
X705847Y405393D01*
X706115Y405238D01*
X706460Y405186D01*
X706805Y405289D01*
X707073Y405496D01*
X707265Y405858D01*
X707303Y406271D01*
X707227Y406684D01*
X707035Y406943D01*
X706767Y407149D01*
X706498Y407201D01*
X706230Y407149D01*
X705885Y406943D01*
X706000Y408286D01*
X707035D01*
G01X708832Y407769D02*
X709062Y408079D01*
X709330Y408234D01*
X709637Y408286D01*
X710020Y408183D01*
X710288Y407924D01*
X710365Y407614D01*
X710327Y407304D01*
X710173Y407046D01*
X709407Y406529D01*
X709062Y406168D01*
X708832Y405651D01*
X708755Y405186D01*
X710365D01*
G01X696393Y401355D02*
Y404455D01*
X697352D01*
X697658Y404300D01*
X697850Y404093D01*
X697927Y403680D01*
X697850Y403267D01*
X697620Y403008D01*
X697352Y402853D01*
X696393D01*
G01X697352D02*
X697927Y401355D01*
G01X700260D02*
X700528Y401407D01*
X700835Y401562D01*
X701027Y401820D01*
X701103Y402182D01*
X701027Y402543D01*
X700797Y402853D01*
X700452Y403008D01*
X700068D01*
X699838Y403112D01*
X699647Y403370D01*
X699570Y403732D01*
X699685Y404093D01*
X699953Y404352D01*
X700260Y404455D01*
X700567Y404352D01*
X700835Y404093D01*
X700950Y403732D01*
X700873Y403370D01*
X700682Y403112D01*
X700452Y403008D01*
X700068D01*
X699723Y402853D01*
X699493Y402543D01*
X699417Y402182D01*
X699493Y401820D01*
X699685Y401562D01*
X699992Y401407D01*
X700260Y401355D01*
G01X703360D02*
Y404455D01*
X702900Y403835D01*
G01Y401355D02*
X703820D01*
G01X706460Y404455D02*
X706153Y404352D01*
X705923Y404093D01*
X705770Y403783D01*
X705655Y403370D01*
X705617Y402905D01*
X705655Y402440D01*
X705770Y402027D01*
X705923Y401717D01*
X706153Y401458D01*
X706460Y401355D01*
X706767Y401458D01*
X706997Y401717D01*
X707150Y402027D01*
X707265Y402440D01*
X707303Y402905D01*
X707265Y403370D01*
X707150Y403783D01*
X706997Y404093D01*
X706767Y404352D01*
X706460Y404455D01*
G01X696393Y397390D02*
Y400490D01*
X697352D01*
X697658Y400335D01*
X697850Y400128D01*
X697927Y399715D01*
X697850Y399302D01*
X697620Y399043D01*
X697352Y398888D01*
X696393D01*
G01X697352D02*
X697927Y397390D01*
G01X700260D02*
X700528Y397442D01*
X700835Y397597D01*
X701027Y397855D01*
X701103Y398217D01*
X701027Y398578D01*
X700797Y398888D01*
X700452Y399043D01*
X700068D01*
X699838Y399147D01*
X699647Y399405D01*
X699570Y399767D01*
X699685Y400128D01*
X699953Y400387D01*
X700260Y400490D01*
X700567Y400387D01*
X700835Y400128D01*
X700950Y399767D01*
X700873Y399405D01*
X700682Y399147D01*
X700452Y399043D01*
X700068D01*
X699723Y398888D01*
X699493Y398578D01*
X699417Y398217D01*
X699493Y397855D01*
X699685Y397597D01*
X699992Y397442D01*
X700260Y397390D01*
G01X703360Y400490D02*
X703053Y400387D01*
X702823Y400128D01*
X702670Y399818D01*
X702555Y399405D01*
X702517Y398940D01*
X702555Y398475D01*
X702670Y398062D01*
X702823Y397752D01*
X703053Y397493D01*
X703360Y397390D01*
X703667Y397493D01*
X703897Y397752D01*
X704050Y398062D01*
X704165Y398475D01*
X704203Y398940D01*
X704165Y399405D01*
X704050Y399818D01*
X703897Y400128D01*
X703667Y400387D01*
X703360Y400490D01*
G01X705808Y397752D02*
X706077Y397493D01*
X706383Y397390D01*
X706690Y397493D01*
X706958Y397803D01*
X707150Y398268D01*
X707227Y398733D01*
Y399302D01*
X707150Y399767D01*
X706958Y400180D01*
X706728Y400387D01*
X706460Y400490D01*
X706153Y400387D01*
X705923Y400180D01*
X705770Y399870D01*
X705693Y399457D01*
X705770Y399095D01*
X705962Y398733D01*
X706192Y398527D01*
X706460Y398475D01*
X706767Y398578D01*
X706997Y398837D01*
X707227Y399302D01*
G01X696393Y393192D02*
Y396292D01*
X697352D01*
X697658Y396137D01*
X697850Y395930D01*
X697927Y395517D01*
X697850Y395104D01*
X697620Y394845D01*
X697352Y394690D01*
X696393D01*
G01X697352D02*
X697927Y393192D01*
G01X700260D02*
Y396292D01*
X699800Y395672D01*
G01Y393192D02*
X700720D01*
G01X703360D02*
Y396292D01*
X702900Y395672D01*
G01Y393192D02*
X703820D01*
G01X706383D02*
X706460Y393864D01*
X706575Y394432D01*
X706728Y394949D01*
X706920Y395517D01*
X707227Y396292D01*
X705693D01*
G01X709560Y393192D02*
X709828Y393244D01*
X710135Y393399D01*
X710327Y393657D01*
X710403Y394019D01*
X710327Y394380D01*
X710097Y394690D01*
X709752Y394845D01*
X709368D01*
X709138Y394949D01*
X708947Y395207D01*
X708870Y395569D01*
X708985Y395930D01*
X709253Y396189D01*
X709560Y396292D01*
X709867Y396189D01*
X710135Y395930D01*
X710250Y395569D01*
X710173Y395207D01*
X709982Y394949D01*
X709752Y394845D01*
X709368D01*
X709023Y394690D01*
X708793Y394380D01*
X708717Y394019D01*
X708793Y393657D01*
X708985Y393399D01*
X709292Y393244D01*
X709560Y393192D01*
G01X696403Y408947D02*
Y412047D01*
X697362D01*
X697668Y411892D01*
X697860Y411685D01*
X697937Y411272D01*
X697860Y410859D01*
X697630Y410600D01*
X697362Y410445D01*
X696403D01*
G01X697362D02*
X697937Y408947D01*
G01X700270D02*
X700538Y408999D01*
X700845Y409154D01*
X701037Y409412D01*
X701113Y409774D01*
X701037Y410135D01*
X700807Y410445D01*
X700462Y410600D01*
X700078D01*
X699848Y410704D01*
X699657Y410962D01*
X699580Y411324D01*
X699695Y411685D01*
X699963Y411944D01*
X700270Y412047D01*
X700577Y411944D01*
X700845Y411685D01*
X700960Y411324D01*
X700883Y410962D01*
X700692Y410704D01*
X700462Y410600D01*
X700078D01*
X699733Y410445D01*
X699503Y410135D01*
X699427Y409774D01*
X699503Y409412D01*
X699695Y409154D01*
X700002Y408999D01*
X700270Y408947D01*
G01X703370D02*
Y412047D01*
X702910Y411427D01*
G01Y408947D02*
X703830D01*
G01X706470D02*
Y412047D01*
X706010Y411427D01*
G01Y408947D02*
X706930D01*
G01X693001Y440399D02*
Y438177D01*
X693154Y437712D01*
X693461Y437402D01*
X693844Y437299D01*
X694227Y437402D01*
X694534Y437712D01*
X694687Y438177D01*
Y440399D01*
G01X696944Y437299D02*
Y440399D01*
X696484Y439779D01*
G01Y437299D02*
X697404D01*
G01X700044Y440399D02*
X699737Y440296D01*
X699507Y440037D01*
X699354Y439727D01*
X699239Y439314D01*
X699201Y438849D01*
X699239Y438384D01*
X699354Y437971D01*
X699507Y437661D01*
X699737Y437402D01*
X700044Y437299D01*
X700351Y437402D01*
X700581Y437661D01*
X700734Y437971D01*
X700849Y438384D01*
X700887Y438849D01*
X700849Y439314D01*
X700734Y439727D01*
X700581Y440037D01*
X700351Y440296D01*
X700044Y440399D01*
G01X702416Y439882D02*
X702646Y440192D01*
X702914Y440347D01*
X703221Y440399D01*
X703604Y440296D01*
X703872Y440037D01*
X703949Y439727D01*
X703911Y439417D01*
X703757Y439159D01*
X702991Y438642D01*
X702646Y438281D01*
X702416Y437764D01*
X702339Y437299D01*
X703949D01*
G01X692848Y443788D02*
X693078Y443530D01*
X693346Y443375D01*
X693691Y443323D01*
X694036Y443426D01*
X694304Y443633D01*
X694496Y443995D01*
X694534Y444408D01*
X694458Y444821D01*
X694266Y445080D01*
X693998Y445286D01*
X693729Y445338D01*
X693461Y445286D01*
X693116Y445080D01*
X693231Y446423D01*
X694266D01*
G01X685740Y443323D02*
X685817Y443995D01*
X685932Y444563D01*
X686085Y445080D01*
X686277Y445648D01*
X686584Y446423D01*
X685050D01*
G01X689027Y448552D02*
X689295Y448913D01*
X689525Y449120D01*
X689832Y449223D01*
X690100Y449120D01*
X690292Y448913D01*
X690445Y448603D01*
X690483Y448242D01*
X690445Y447932D01*
X690292Y447622D01*
X690062Y447363D01*
X689793Y447260D01*
X689487Y447363D01*
X689218Y447673D01*
X689065Y448138D01*
X689027Y448655D01*
X689103Y449327D01*
X689218Y449688D01*
X689410Y450050D01*
X689678Y450308D01*
X689947Y450360D01*
X690215Y450257D01*
X690407Y449998D01*
G01X698089Y447260D02*
Y450360D01*
X696671Y448138D01*
X698587D01*
G01X692761Y511230D02*
X689561D01*
G01X692761Y517430D02*
Y511230D01*
G01X689561Y517430D02*
X692761D01*
G01X689561Y511230D02*
Y517430D01*
G01X688261Y511230D02*
X685061D01*
G01X688261Y517430D02*
Y511230D01*
G01X685061Y517430D02*
X688261D01*
G01X685061Y511230D02*
Y517430D01*
G01X696480Y535560D02*
Y532520D01*
G01D02*
X724650D01*
G01X692366Y519037D02*
Y525237D01*
G01X695566Y519037D02*
X692366D01*
G01Y525237D02*
X695566D01*
G01D02*
Y519037D01*
G01X696581Y519056D02*
Y531530D01*
G01X708661Y519056D02*
X696581D01*
G01Y531530D02*
X708661D01*
G01X693259Y529666D02*
X693099Y529791D01*
X692912Y529874D01*
X692699D01*
X692459Y529749D01*
X692272Y529541D01*
X692139Y529291D01*
X692032Y528874D01*
X692005Y528499D01*
X692059Y528124D01*
X692139Y527874D01*
X692299Y527624D01*
X692485Y527457D01*
X692672Y527374D01*
X692859D01*
X693045Y527457D01*
X693205Y527582D01*
X693339Y527749D01*
G01X691123Y534316D02*
Y522236D01*
G01X685830Y535560D02*
X696480D01*
G01X699498Y548215D02*
Y551415D01*
G01X705698Y548215D02*
X699498D01*
G01X714345Y540508D02*
X699345D01*
G01Y547308D02*
X714345D01*
G01X699345Y540508D02*
Y547308D01*
G01X697398Y547554D02*
X697558Y547262D01*
X697772Y547096D01*
X698012Y547054D01*
X698225Y547096D01*
X698438Y547304D01*
X698572Y547554D01*
X698598Y547804D01*
X698545Y548096D01*
X698358Y548304D01*
X698172Y548387D01*
X697932D01*
G01X698172D02*
X698332Y548512D01*
X698465Y548721D01*
X698518Y548971D01*
X698465Y549221D01*
X698332Y549429D01*
X698092Y549554D01*
X697852Y549512D01*
X697612Y549346D01*
G01X694236Y535875D02*
X691736D01*
X692236Y535555D01*
G01X694236D02*
Y536195D01*
G01X695703Y549427D02*
Y537223D01*
G01X700589Y535129D02*
Y534063D01*
X698089D01*
Y535129D01*
G01X699297Y534703D02*
Y534063D01*
G01X699498Y551415D02*
X705698D01*
G01X706923Y558956D02*
X691923D01*
G01D02*
Y565756D01*
G01X699423Y559056D02*
Y565656D01*
G01X685981Y554111D02*
Y551889D01*
X686134Y551424D01*
X686441Y551114D01*
X686824Y551011D01*
X687207Y551114D01*
X687514Y551424D01*
X687667Y551889D01*
Y554111D01*
G01X689924Y551011D02*
Y554111D01*
X689464Y553491D01*
G01Y551011D02*
X690384D01*
G01X693024Y554111D02*
X692717Y554008D01*
X692487Y553749D01*
X692334Y553439D01*
X692219Y553026D01*
X692181Y552561D01*
X692219Y552096D01*
X692334Y551683D01*
X692487Y551373D01*
X692717Y551114D01*
X693024Y551011D01*
X693331Y551114D01*
X693561Y551373D01*
X693714Y551683D01*
X693829Y552096D01*
X693867Y552561D01*
X693829Y553026D01*
X693714Y553439D01*
X693561Y553749D01*
X693331Y554008D01*
X693024Y554111D01*
G01X695396Y552303D02*
X695664Y552664D01*
X695894Y552871D01*
X696201Y552974D01*
X696469Y552871D01*
X696661Y552664D01*
X696814Y552354D01*
X696852Y551993D01*
X696814Y551683D01*
X696661Y551373D01*
X696431Y551114D01*
X696162Y551011D01*
X695856Y551114D01*
X695587Y551424D01*
X695434Y551889D01*
X695396Y552406D01*
X695472Y553078D01*
X695587Y553439D01*
X695779Y553801D01*
X696047Y554059D01*
X696316Y554111D01*
X696584Y554008D01*
X696776Y553749D01*
G01X706908Y574980D02*
X691908D01*
G01D02*
Y581780D01*
G01X699408Y575080D02*
Y581680D01*
G01X691923Y565756D02*
X706923D01*
G01X706908Y566980D02*
X691908D01*
G01D02*
Y573780D01*
G01D02*
X706908D01*
G01X699408Y567080D02*
Y573680D01*
G01X691908Y581780D02*
X706908D01*
G01Y582980D02*
X691908D01*
G01D02*
Y589780D01*
G01D02*
X706908D01*
G01X699408Y583080D02*
Y589680D01*
G01X685443Y615853D02*
X727282D01*
Y602981D01*
X686152D01*
Y615596D01*
G01X690949Y603638D02*
X687849D01*
Y604597D01*
X688004Y604903D01*
X688211Y605095D01*
X688624Y605172D01*
X689037Y605095D01*
X689296Y604865D01*
X689451Y604597D01*
Y603638D01*
G01Y604597D02*
X690949Y605172D01*
G01X690484Y606662D02*
X690742Y606892D01*
X690897Y607160D01*
X690949Y607505D01*
X690846Y607850D01*
X690639Y608118D01*
X690277Y608310D01*
X689864Y608348D01*
X689451Y608272D01*
X689192Y608080D01*
X688986Y607812D01*
X688934Y607543D01*
X688986Y607275D01*
X689192Y606930D01*
X687849Y607045D01*
Y608080D01*
G01X690587Y609953D02*
X690846Y610222D01*
X690949Y610528D01*
X690846Y610835D01*
X690536Y611103D01*
X690071Y611295D01*
X689606Y611372D01*
X689037D01*
X688572Y611295D01*
X688159Y611103D01*
X687952Y610873D01*
X687849Y610605D01*
X687952Y610298D01*
X688159Y610068D01*
X688469Y609915D01*
X688882Y609838D01*
X689244Y609915D01*
X689606Y610107D01*
X689812Y610337D01*
X689864Y610605D01*
X689761Y610912D01*
X689502Y611142D01*
X689037Y611372D01*
G01X687849Y613705D02*
X687952Y613398D01*
X688211Y613168D01*
X688521Y613015D01*
X688934Y612900D01*
X689399Y612862D01*
X689864Y612900D01*
X690277Y613015D01*
X690587Y613168D01*
X690846Y613398D01*
X690949Y613705D01*
X690846Y614012D01*
X690587Y614242D01*
X690277Y614395D01*
X689864Y614510D01*
X689399Y614548D01*
X688934Y614510D01*
X688521Y614395D01*
X688211Y614242D01*
X687952Y614012D01*
X687849Y613705D01*
G01X696914Y603943D02*
X693814D01*
Y604902D01*
X693969Y605208D01*
X694176Y605400D01*
X694589Y605477D01*
X695002Y605400D01*
X695261Y605170D01*
X695416Y604902D01*
Y603943D01*
G01Y604902D02*
X696914Y605477D01*
G01X696449Y606967D02*
X696707Y607197D01*
X696862Y607465D01*
X696914Y607810D01*
X696811Y608155D01*
X696604Y608423D01*
X696242Y608615D01*
X695829Y608653D01*
X695416Y608577D01*
X695157Y608385D01*
X694951Y608117D01*
X694899Y607848D01*
X694951Y607580D01*
X695157Y607235D01*
X693814Y607350D01*
Y608385D01*
G01X696914Y610833D02*
X696242Y610910D01*
X695674Y611025D01*
X695157Y611178D01*
X694589Y611370D01*
X693814Y611677D01*
Y610143D01*
G01X694331Y613282D02*
X694021Y613512D01*
X693866Y613780D01*
X693814Y614087D01*
X693917Y614470D01*
X694176Y614738D01*
X694486Y614815D01*
X694796Y614777D01*
X695054Y614623D01*
X695571Y613857D01*
X695932Y613512D01*
X696449Y613282D01*
X696914Y613205D01*
Y614815D01*
G01X701026Y603943D02*
X697926D01*
Y604902D01*
X698081Y605208D01*
X698288Y605400D01*
X698701Y605477D01*
X699114Y605400D01*
X699373Y605170D01*
X699528Y604902D01*
Y603943D01*
G01Y604902D02*
X701026Y605477D01*
G01X700561Y606967D02*
X700819Y607197D01*
X700974Y607465D01*
X701026Y607810D01*
X700923Y608155D01*
X700716Y608423D01*
X700354Y608615D01*
X699941Y608653D01*
X699528Y608577D01*
X699269Y608385D01*
X699063Y608117D01*
X699011Y607848D01*
X699063Y607580D01*
X699269Y607235D01*
X697926Y607350D01*
Y608385D01*
G01X701026Y610833D02*
X700354Y610910D01*
X699786Y611025D01*
X699269Y611178D01*
X698701Y611370D01*
X697926Y611677D01*
Y610143D01*
G01X701026Y614470D02*
X697926D01*
X700148Y613052D01*
Y614968D01*
G01X693675Y785258D02*
X693782Y785383D01*
X693862Y785592D01*
X693915Y785883D01*
X693862Y786133D01*
X693755Y786300D01*
X693569Y786425D01*
X692849D01*
Y783925D01*
X693729D01*
X693915Y784092D01*
X694022Y784342D01*
X694075Y784633D01*
X694022Y784925D01*
X693862Y785175D01*
X693675Y785258D01*
X692849D01*
G01X695662Y783925D02*
Y786425D01*
X695342Y785925D01*
G01Y783925D02*
X695982D01*
G01X697862D02*
Y786425D01*
X697542Y785925D01*
G01Y783925D02*
X698182D01*
G01X687148Y792439D02*
G03X694864I3858J0D01*
G01X687148D02*
Y819152D01*
G01X694864Y792439D02*
Y819152D01*
G01X687148D02*
X684648Y821652D01*
G01X697364D02*
X736341D01*
G01X694864Y819152D02*
X697364Y821652D01*
G01X708776Y42320D02*
X705576D01*
G01X708776Y48520D02*
Y42320D01*
G01X705576D02*
Y48520D01*
G01X704453Y42379D02*
X701353D01*
Y43338D01*
X701508Y43644D01*
X701715Y43836D01*
X702128Y43913D01*
X702541Y43836D01*
X702800Y43606D01*
X702955Y43338D01*
Y42379D01*
G01Y43338D02*
X704453Y43913D01*
G01Y46246D02*
X704401Y46514D01*
X704246Y46821D01*
X703988Y47013D01*
X703626Y47089D01*
X703265Y47013D01*
X702955Y46783D01*
X702800Y46438D01*
Y46054D01*
X702696Y45824D01*
X702438Y45633D01*
X702076Y45556D01*
X701715Y45671D01*
X701456Y45939D01*
X701353Y46246D01*
X701456Y46553D01*
X701715Y46821D01*
X702076Y46936D01*
X702438Y46859D01*
X702696Y46668D01*
X702800Y46438D01*
Y46054D01*
X702955Y45709D01*
X703265Y45479D01*
X703626Y45403D01*
X703988Y45479D01*
X704246Y45671D01*
X704401Y45978D01*
X704453Y46246D01*
G01Y49346D02*
X701353D01*
X701973Y48886D01*
G01X704453D02*
Y49806D01*
G01Y52369D02*
X703781Y52446D01*
X703213Y52561D01*
X702696Y52714D01*
X702128Y52906D01*
X701353Y53213D01*
Y51679D01*
G01X710076Y42320D02*
Y48520D01*
G01X713276D02*
Y42320D01*
G01D02*
X710076D01*
G01X705576Y48520D02*
X708776D01*
G01X710076D02*
X713276D01*
G01X713040Y77760D02*
Y72760D01*
G01X711583Y77760D02*
X714497D01*
G01X716557Y72760D02*
X718140Y77760D01*
X719723Y72760D01*
G01X719153Y74510D02*
X717127D01*
G01X724633Y77343D02*
X724253Y77593D01*
X723810Y77760D01*
X723303D01*
X722733Y77510D01*
X722290Y77093D01*
X721973Y76593D01*
X721720Y75760D01*
X721657Y75010D01*
X721783Y74260D01*
X721973Y73760D01*
X722353Y73260D01*
X722797Y72927D01*
X723240Y72760D01*
X723683D01*
X724127Y72927D01*
X724507Y73177D01*
X724823Y73510D01*
G01X726947Y72760D02*
Y77760D01*
G01X729353D02*
X726947Y74677D01*
G01X729733Y72760D02*
X728023Y76093D01*
G01X733440Y72760D02*
X732933Y72843D01*
X732490Y73177D01*
X732110Y73677D01*
X731857Y74260D01*
X731730Y74927D01*
Y75593D01*
X731857Y76260D01*
X732110Y76843D01*
X732490Y77343D01*
X732933Y77677D01*
X733440Y77760D01*
X733947Y77677D01*
X734390Y77343D01*
X734770Y76843D01*
X735023Y76260D01*
X735150Y75593D01*
Y74927D01*
X735023Y74260D01*
X734770Y73677D01*
X734390Y73177D01*
X733947Y72843D01*
X733440Y72760D01*
G01X736957Y77760D02*
X738540Y72760D01*
X740123Y77760D01*
G01X744907Y72760D02*
X742373D01*
Y77760D01*
X744907D01*
G01X743893Y75343D02*
X742373D01*
G01X747473Y72760D02*
Y77760D01*
X749057D01*
X749563Y77510D01*
X749880Y77177D01*
X750007Y76510D01*
X749880Y75843D01*
X749500Y75427D01*
X749057Y75177D01*
X747473D01*
G01X749057D02*
X750007Y72760D01*
G01X751940Y71093D02*
X755740D01*
G01X760207Y72760D02*
X757673D01*
Y77760D01*
X760207D01*
G01X759193Y75343D02*
X757673D01*
G01X762583Y72760D02*
Y77760D01*
X765497Y72760D01*
Y77760D01*
G01X767557Y72760D02*
X769140Y77760D01*
X770723Y72760D01*
G01X770153Y74510D02*
X768127D01*
G01X774747Y75427D02*
X775000Y75677D01*
X775190Y76093D01*
X775317Y76677D01*
X775190Y77177D01*
X774937Y77510D01*
X774493Y77760D01*
X772783D01*
Y72760D01*
X774873D01*
X775317Y73093D01*
X775570Y73593D01*
X775697Y74177D01*
X775570Y74760D01*
X775190Y75260D01*
X774747Y75427D01*
X772783D01*
G01X778073Y77760D02*
Y72760D01*
X780607D01*
G01X785707D02*
X783173D01*
Y77760D01*
X785707D01*
G01X784693Y75343D02*
X783173D01*
G01X704181Y154945D02*
X704411Y154687D01*
X704679Y154532D01*
X705024Y154480D01*
X705369Y154583D01*
X705637Y154790D01*
X705829Y155152D01*
X705867Y155565D01*
X705791Y155978D01*
X705599Y156237D01*
X705331Y156443D01*
X705062Y156495D01*
X704794Y156443D01*
X704449Y156237D01*
X704564Y157580D01*
X705599D01*
G01X707575Y188955D02*
Y149955D01*
G01X705241Y182771D02*
X705509Y182823D01*
X705816Y182978D01*
X706008Y183236D01*
X706084Y183598D01*
X706008Y183959D01*
X705778Y184269D01*
X705433Y184424D01*
X705049D01*
X704819Y184528D01*
X704628Y184786D01*
X704551Y185148D01*
X704666Y185509D01*
X704934Y185768D01*
X705241Y185871D01*
X705548Y185768D01*
X705816Y185509D01*
X705931Y185148D01*
X705854Y184786D01*
X705663Y184528D01*
X705433Y184424D01*
X705049D01*
X704704Y184269D01*
X704474Y183959D01*
X704398Y183598D01*
X704474Y183236D01*
X704666Y182978D01*
X704973Y182823D01*
X705241Y182771D01*
G01X701088Y203739D02*
X701248Y203989D01*
X701435Y204114D01*
X701648Y204156D01*
X701915Y204073D01*
X702102Y203864D01*
X702155Y203614D01*
X702128Y203364D01*
X702022Y203156D01*
X701488Y202739D01*
X701248Y202448D01*
X701088Y202031D01*
X701035Y201656D01*
X702155D01*
G01X703517Y190597D02*
X700417D01*
Y192053D01*
G01X701915Y191517D02*
Y190597D01*
G01X703104Y193620D02*
X703362Y193927D01*
X703517Y194272D01*
Y194578D01*
X703362Y194885D01*
X703104Y195115D01*
X702742Y195230D01*
X702380Y195153D01*
X702070Y194962D01*
X701864Y194617D01*
X701760Y194157D01*
X701554Y193888D01*
X701192Y193773D01*
X700830Y193850D01*
X700572Y194042D01*
X700417Y194310D01*
Y194578D01*
X700520Y194847D01*
X700779Y195077D01*
G01X703517Y197985D02*
X700417D01*
X702639Y196567D01*
Y198483D01*
G01X712189Y209972D02*
Y206389D01*
X712442Y205639D01*
X712949Y205139D01*
X713582Y204972D01*
X714215Y205139D01*
X714722Y205639D01*
X714975Y206389D01*
Y209972D01*
G01X717352Y205639D02*
X717859Y205222D01*
X718429Y204972D01*
X718935D01*
X719442Y205222D01*
X719822Y205639D01*
X720012Y206222D01*
X719885Y206805D01*
X719569Y207305D01*
X718999Y207639D01*
X718239Y207805D01*
X717795Y208139D01*
X717605Y208722D01*
X717732Y209305D01*
X718049Y209722D01*
X718492Y209972D01*
X718935D01*
X719379Y209805D01*
X719759Y209389D01*
G01X724289Y207639D02*
X724542Y207889D01*
X724732Y208305D01*
X724859Y208889D01*
X724732Y209389D01*
X724479Y209722D01*
X724035Y209972D01*
X722325D01*
Y204972D01*
X724415D01*
X724859Y205305D01*
X725112Y205805D01*
X725239Y206389D01*
X725112Y206972D01*
X724732Y207472D01*
X724289Y207639D01*
X722325D01*
G01X728882Y209972D02*
X728375Y209805D01*
X727995Y209389D01*
X727742Y208889D01*
X727552Y208222D01*
X727489Y207472D01*
X727552Y206722D01*
X727742Y206055D01*
X727995Y205555D01*
X728375Y205139D01*
X728882Y204972D01*
X729389Y205139D01*
X729769Y205555D01*
X730022Y206055D01*
X730212Y206722D01*
X730275Y207472D01*
X730212Y208222D01*
X730022Y208889D01*
X729769Y209389D01*
X729389Y209805D01*
X728882Y209972D01*
G01X740982Y203305D02*
X737815Y208305D01*
Y209139D01*
X738449Y209972D01*
X739082D01*
X739715Y209139D01*
Y208305D01*
X739082Y207472D01*
X737815Y206639D01*
X737182Y205805D01*
Y204139D01*
X737815Y203305D01*
X739715D01*
X740982Y204972D01*
G01X747889Y209972D02*
Y206389D01*
X748142Y205639D01*
X748649Y205139D01*
X749282Y204972D01*
X749915Y205139D01*
X750422Y205639D01*
X750675Y206389D01*
Y209972D01*
G01X753052Y205639D02*
X753559Y205222D01*
X754129Y204972D01*
X754635D01*
X755142Y205222D01*
X755522Y205639D01*
X755712Y206222D01*
X755585Y206805D01*
X755269Y207305D01*
X754699Y207639D01*
X753939Y207805D01*
X753495Y208139D01*
X753305Y208722D01*
X753432Y209305D01*
X753749Y209722D01*
X754192Y209972D01*
X754635D01*
X755079Y209805D01*
X755459Y209389D01*
G01X759989Y207639D02*
X760242Y207889D01*
X760432Y208305D01*
X760559Y208889D01*
X760432Y209389D01*
X760179Y209722D01*
X759735Y209972D01*
X758025D01*
Y204972D01*
X760115D01*
X760559Y205305D01*
X760812Y205805D01*
X760939Y206389D01*
X760812Y206972D01*
X760432Y207472D01*
X759989Y207639D01*
X758025D01*
G01X764582Y204972D02*
Y209972D01*
X763822Y208972D01*
G01Y204972D02*
X765342D01*
G01X702742Y214662D02*
X701222D01*
G01X702045Y213579D02*
Y215746D01*
G01X700123Y210360D02*
Y213904D01*
G01X704854Y229768D02*
X705084Y229510D01*
X705352Y229355D01*
X705697Y229303D01*
X706042Y229406D01*
X706310Y229613D01*
X706502Y229975D01*
X706540Y230388D01*
X706464Y230801D01*
X706272Y231060D01*
X706004Y231266D01*
X705735Y231318D01*
X705467Y231266D01*
X705122Y231060D01*
X705237Y232403D01*
X706272D01*
G01X707575Y267761D02*
Y228761D01*
G01X700690Y294360D02*
Y265670D01*
G01X704197Y262803D02*
X704465Y262855D01*
X704772Y263010D01*
X704964Y263268D01*
X705040Y263630D01*
X704964Y263991D01*
X704734Y264301D01*
X704389Y264456D01*
X704005D01*
X703775Y264560D01*
X703584Y264818D01*
X703507Y265180D01*
X703622Y265541D01*
X703890Y265800D01*
X704197Y265903D01*
X704504Y265800D01*
X704772Y265541D01*
X704887Y265180D01*
X704810Y264818D01*
X704619Y264560D01*
X704389Y264456D01*
X704005D01*
X703660Y264301D01*
X703430Y263991D01*
X703354Y263630D01*
X703430Y263268D01*
X703622Y263010D01*
X703929Y262855D01*
X704197Y262803D01*
G01X714254Y295975D02*
Y292392D01*
X714507Y291642D01*
X715014Y291142D01*
X715647Y290975D01*
X716280Y291142D01*
X716787Y291642D01*
X717040Y292392D01*
Y295975D01*
G01X719417Y291642D02*
X719924Y291225D01*
X720494Y290975D01*
X721000D01*
X721507Y291225D01*
X721887Y291642D01*
X722077Y292225D01*
X721950Y292808D01*
X721634Y293308D01*
X721064Y293642D01*
X720304Y293808D01*
X719860Y294142D01*
X719670Y294725D01*
X719797Y295308D01*
X720114Y295725D01*
X720557Y295975D01*
X721000D01*
X721444Y295808D01*
X721824Y295392D01*
G01X726354Y293642D02*
X726607Y293892D01*
X726797Y294308D01*
X726924Y294892D01*
X726797Y295392D01*
X726544Y295725D01*
X726100Y295975D01*
X724390D01*
Y290975D01*
X726480D01*
X726924Y291308D01*
X727177Y291808D01*
X727304Y292392D01*
X727177Y292975D01*
X726797Y293475D01*
X726354Y293642D01*
X724390D01*
G01X729744Y295142D02*
X730124Y295642D01*
X730567Y295892D01*
X731074Y295975D01*
X731707Y295808D01*
X732150Y295392D01*
X732277Y294892D01*
X732214Y294392D01*
X731960Y293975D01*
X730694Y293142D01*
X730124Y292558D01*
X729744Y291725D01*
X729617Y290975D01*
X732277D01*
G01X743047Y289308D02*
X739880Y294308D01*
Y295142D01*
X740514Y295975D01*
X741147D01*
X741780Y295142D01*
Y294308D01*
X741147Y293475D01*
X739880Y292642D01*
X739247Y291808D01*
Y290142D01*
X739880Y289308D01*
X741780D01*
X743047Y290975D01*
G01X749954Y295975D02*
Y292392D01*
X750207Y291642D01*
X750714Y291142D01*
X751347Y290975D01*
X751980Y291142D01*
X752487Y291642D01*
X752740Y292392D01*
Y295975D01*
G01X755117Y291642D02*
X755624Y291225D01*
X756194Y290975D01*
X756700D01*
X757207Y291225D01*
X757587Y291642D01*
X757777Y292225D01*
X757650Y292808D01*
X757334Y293308D01*
X756764Y293642D01*
X756004Y293808D01*
X755560Y294142D01*
X755370Y294725D01*
X755497Y295308D01*
X755814Y295725D01*
X756257Y295975D01*
X756700D01*
X757144Y295808D01*
X757524Y295392D01*
G01X762054Y293642D02*
X762307Y293892D01*
X762497Y294308D01*
X762624Y294892D01*
X762497Y295392D01*
X762244Y295725D01*
X761800Y295975D01*
X760090D01*
Y290975D01*
X762180D01*
X762624Y291308D01*
X762877Y291808D01*
X763004Y292392D01*
X762877Y292975D01*
X762497Y293475D01*
X762054Y293642D01*
X760090D01*
G01X765254Y291975D02*
X765634Y291392D01*
X766140Y291058D01*
X766710Y290975D01*
X767217Y291058D01*
X767724Y291475D01*
X768040Y291975D01*
X768104Y292475D01*
X767977Y293058D01*
X767534Y293475D01*
X767090Y293642D01*
X766520D01*
G01X767090D02*
X767470Y293892D01*
X767787Y294308D01*
X767914Y294808D01*
X767787Y295308D01*
X767470Y295725D01*
X766900Y295975D01*
X766330Y295892D01*
X765760Y295558D01*
G01X713170Y298019D02*
X768994D01*
Y289249D01*
X711737D01*
Y298019D01*
X713170D01*
G01X708773Y354379D02*
X708543Y354534D01*
X708275Y354637D01*
X707968D01*
X707623Y354482D01*
X707355Y354224D01*
X707163Y353914D01*
X707010Y353397D01*
X706972Y352932D01*
X707048Y352467D01*
X707163Y352157D01*
X707393Y351847D01*
X707662Y351640D01*
X707930Y351537D01*
X708198D01*
X708467Y351640D01*
X708697Y351795D01*
X708888Y352002D01*
G01X711030Y351537D02*
X711298Y351589D01*
X711605Y351744D01*
X711797Y352002D01*
X711873Y352364D01*
X711797Y352725D01*
X711567Y353035D01*
X711222Y353190D01*
X710838D01*
X710608Y353294D01*
X710417Y353552D01*
X710340Y353914D01*
X710455Y354275D01*
X710723Y354534D01*
X711030Y354637D01*
X711337Y354534D01*
X711605Y354275D01*
X711720Y353914D01*
X711643Y353552D01*
X711452Y353294D01*
X711222Y353190D01*
X710838D01*
X710493Y353035D01*
X710263Y352725D01*
X710187Y352364D01*
X710263Y352002D01*
X710455Y351744D01*
X710762Y351589D01*
X711030Y351537D01*
G01X714130D02*
X714398Y351589D01*
X714705Y351744D01*
X714897Y352002D01*
X714973Y352364D01*
X714897Y352725D01*
X714667Y353035D01*
X714322Y353190D01*
X713938D01*
X713708Y353294D01*
X713517Y353552D01*
X713440Y353914D01*
X713555Y354275D01*
X713823Y354534D01*
X714130Y354637D01*
X714437Y354534D01*
X714705Y354275D01*
X714820Y353914D01*
X714743Y353552D01*
X714552Y353294D01*
X714322Y353190D01*
X713938D01*
X713593Y353035D01*
X713363Y352725D01*
X713287Y352364D01*
X713363Y352002D01*
X713555Y351744D01*
X713862Y351589D01*
X714130Y351537D01*
G01X716502Y352829D02*
X716770Y353190D01*
X717000Y353397D01*
X717307Y353500D01*
X717575Y353397D01*
X717767Y353190D01*
X717920Y352880D01*
X717958Y352519D01*
X717920Y352209D01*
X717767Y351899D01*
X717537Y351640D01*
X717268Y351537D01*
X716962Y351640D01*
X716693Y351950D01*
X716540Y352415D01*
X716502Y352932D01*
X716578Y353604D01*
X716693Y353965D01*
X716885Y354327D01*
X717153Y354585D01*
X717422Y354637D01*
X717690Y354534D01*
X717882Y354275D01*
G01X707083Y347347D02*
Y350447D01*
X708042D01*
X708348Y350292D01*
X708540Y350085D01*
X708617Y349672D01*
X708540Y349259D01*
X708310Y349000D01*
X708042Y348845D01*
X707083D01*
G01X708042D02*
X708617Y347347D01*
G01X710950D02*
X711218Y347399D01*
X711525Y347554D01*
X711717Y347812D01*
X711793Y348174D01*
X711717Y348535D01*
X711487Y348845D01*
X711142Y349000D01*
X710758D01*
X710528Y349104D01*
X710337Y349362D01*
X710260Y349724D01*
X710375Y350085D01*
X710643Y350344D01*
X710950Y350447D01*
X711257Y350344D01*
X711525Y350085D01*
X711640Y349724D01*
X711563Y349362D01*
X711372Y349104D01*
X711142Y349000D01*
X710758D01*
X710413Y348845D01*
X710183Y348535D01*
X710107Y348174D01*
X710183Y347812D01*
X710375Y347554D01*
X710682Y347399D01*
X710950Y347347D01*
G01X714050Y350447D02*
X713743Y350344D01*
X713513Y350085D01*
X713360Y349775D01*
X713245Y349362D01*
X713207Y348897D01*
X713245Y348432D01*
X713360Y348019D01*
X713513Y347709D01*
X713743Y347450D01*
X714050Y347347D01*
X714357Y347450D01*
X714587Y347709D01*
X714740Y348019D01*
X714855Y348432D01*
X714893Y348897D01*
X714855Y349362D01*
X714740Y349775D01*
X714587Y350085D01*
X714357Y350344D01*
X714050Y350447D01*
G01X717150D02*
X716843Y350344D01*
X716613Y350085D01*
X716460Y349775D01*
X716345Y349362D01*
X716307Y348897D01*
X716345Y348432D01*
X716460Y348019D01*
X716613Y347709D01*
X716843Y347450D01*
X717150Y347347D01*
X717457Y347450D01*
X717687Y347709D01*
X717840Y348019D01*
X717955Y348432D01*
X717993Y348897D01*
X717955Y349362D01*
X717840Y349775D01*
X717687Y350085D01*
X717457Y350344D01*
X717150Y350447D01*
G01X713316Y360777D02*
Y363877D01*
X714275D01*
X714581Y363722D01*
X714773Y363515D01*
X714850Y363102D01*
X714773Y362689D01*
X714543Y362430D01*
X714275Y362275D01*
X713316D01*
G01X714275D02*
X714850Y360777D01*
G01X717106D02*
X717183Y361449D01*
X717298Y362017D01*
X717451Y362534D01*
X717643Y363102D01*
X717950Y363877D01*
X716416D01*
G01X719555Y362069D02*
X719823Y362430D01*
X720053Y362637D01*
X720360Y362740D01*
X720628Y362637D01*
X720820Y362430D01*
X720973Y362120D01*
X721011Y361759D01*
X720973Y361449D01*
X720820Y361139D01*
X720590Y360880D01*
X720321Y360777D01*
X720015Y360880D01*
X719746Y361190D01*
X719593Y361655D01*
X719555Y362172D01*
X719631Y362844D01*
X719746Y363205D01*
X719938Y363567D01*
X720206Y363825D01*
X720475Y363877D01*
X720743Y363774D01*
X720935Y363515D01*
G01X723383Y360777D02*
X723651Y360829D01*
X723958Y360984D01*
X724150Y361242D01*
X724226Y361604D01*
X724150Y361965D01*
X723920Y362275D01*
X723575Y362430D01*
X723191D01*
X722961Y362534D01*
X722770Y362792D01*
X722693Y363154D01*
X722808Y363515D01*
X723076Y363774D01*
X723383Y363877D01*
X723690Y363774D01*
X723958Y363515D01*
X724073Y363154D01*
X723996Y362792D01*
X723805Y362534D01*
X723575Y362430D01*
X723191D01*
X722846Y362275D01*
X722616Y361965D01*
X722540Y361604D01*
X722616Y361242D01*
X722808Y360984D01*
X723115Y360829D01*
X723383Y360777D01*
G01X713313Y356487D02*
Y359587D01*
X714272D01*
X714578Y359432D01*
X714770Y359225D01*
X714847Y358812D01*
X714770Y358399D01*
X714540Y358140D01*
X714272Y357985D01*
X713313D01*
G01X714272D02*
X714847Y356487D01*
G01X717103D02*
X717180Y357159D01*
X717295Y357727D01*
X717448Y358244D01*
X717640Y358812D01*
X717947Y359587D01*
X716413D01*
G01X720203Y356487D02*
X720280Y357159D01*
X720395Y357727D01*
X720548Y358244D01*
X720740Y358812D01*
X721047Y359587D01*
X719513D01*
G01X723380D02*
X723073Y359484D01*
X722843Y359225D01*
X722690Y358915D01*
X722575Y358502D01*
X722537Y358037D01*
X722575Y357572D01*
X722690Y357159D01*
X722843Y356849D01*
X723073Y356590D01*
X723380Y356487D01*
X723687Y356590D01*
X723917Y356849D01*
X724070Y357159D01*
X724185Y357572D01*
X724223Y358037D01*
X724185Y358502D01*
X724070Y358915D01*
X723917Y359225D01*
X723687Y359484D01*
X723380Y359587D01*
G01X701634Y345457D02*
X703856D01*
X704321Y345610D01*
X704631Y345917D01*
X704734Y346300D01*
X704631Y346683D01*
X704321Y346990D01*
X703856Y347143D01*
X701634D01*
G01X704734Y349400D02*
X701634D01*
X702254Y348940D01*
G01X704734D02*
Y349860D01*
G01X701634Y352500D02*
X701737Y352193D01*
X701996Y351963D01*
X702306Y351810D01*
X702719Y351695D01*
X703184Y351657D01*
X703649Y351695D01*
X704062Y351810D01*
X704372Y351963D01*
X704631Y352193D01*
X704734Y352500D01*
X704631Y352807D01*
X704372Y353037D01*
X704062Y353190D01*
X703649Y353305D01*
X703184Y353343D01*
X702719Y353305D01*
X702306Y353190D01*
X701996Y353037D01*
X701737Y352807D01*
X701634Y352500D01*
G01X704734Y356060D02*
X701634D01*
X703856Y354642D01*
Y356558D01*
G01X714987Y371584D02*
X714757Y371739D01*
X714489Y371842D01*
X714182D01*
X713837Y371687D01*
X713569Y371429D01*
X713377Y371119D01*
X713224Y370602D01*
X713186Y370137D01*
X713262Y369672D01*
X713377Y369362D01*
X713607Y369052D01*
X713876Y368845D01*
X714144Y368742D01*
X714412D01*
X714681Y368845D01*
X714911Y369000D01*
X715102Y369207D01*
G01X716401D02*
X716631Y368949D01*
X716899Y368794D01*
X717244Y368742D01*
X717589Y368845D01*
X717857Y369052D01*
X718049Y369414D01*
X718087Y369827D01*
X718011Y370240D01*
X717819Y370499D01*
X717551Y370705D01*
X717282Y370757D01*
X717014Y370705D01*
X716669Y370499D01*
X716784Y371842D01*
X717819D01*
G01X720267Y368742D02*
X720344Y369414D01*
X720459Y369982D01*
X720612Y370499D01*
X720804Y371067D01*
X721111Y371842D01*
X719577D01*
G01X723367Y368742D02*
X723444Y369414D01*
X723559Y369982D01*
X723712Y370499D01*
X723904Y371067D01*
X724211Y371842D01*
X722677D01*
G01X715002Y367620D02*
X714772Y367775D01*
X714504Y367878D01*
X714197D01*
X713852Y367723D01*
X713584Y367465D01*
X713392Y367155D01*
X713239Y366638D01*
X713201Y366173D01*
X713277Y365708D01*
X713392Y365398D01*
X713622Y365088D01*
X713891Y364881D01*
X714159Y364778D01*
X714427D01*
X714696Y364881D01*
X714926Y365036D01*
X715117Y365243D01*
G01X716416D02*
X716646Y364985D01*
X716914Y364830D01*
X717259Y364778D01*
X717604Y364881D01*
X717872Y365088D01*
X718064Y365450D01*
X718102Y365863D01*
X718026Y366276D01*
X717834Y366535D01*
X717566Y366741D01*
X717297Y366793D01*
X717029Y366741D01*
X716684Y366535D01*
X716799Y367878D01*
X717834D01*
G01X720359Y364778D02*
X720627Y364830D01*
X720934Y364985D01*
X721126Y365243D01*
X721202Y365605D01*
X721126Y365966D01*
X720896Y366276D01*
X720551Y366431D01*
X720167D01*
X719937Y366535D01*
X719746Y366793D01*
X719669Y367155D01*
X719784Y367516D01*
X720052Y367775D01*
X720359Y367878D01*
X720666Y367775D01*
X720934Y367516D01*
X721049Y367155D01*
X720972Y366793D01*
X720781Y366535D01*
X720551Y366431D01*
X720167D01*
X719822Y366276D01*
X719592Y365966D01*
X719516Y365605D01*
X719592Y365243D01*
X719784Y364985D01*
X720091Y364830D01*
X720359Y364778D01*
G01X723919D02*
Y367878D01*
X722501Y365656D01*
X724417D01*
G01X713476Y372737D02*
Y375837D01*
X714435D01*
X714741Y375682D01*
X714933Y375475D01*
X715010Y375062D01*
X714933Y374649D01*
X714703Y374390D01*
X714435Y374235D01*
X713476D01*
G01X714435D02*
X715010Y372737D01*
G01X717266D02*
X717343Y373409D01*
X717458Y373977D01*
X717611Y374494D01*
X717803Y375062D01*
X718110Y375837D01*
X716576D01*
G01X719600Y373202D02*
X719830Y372944D01*
X720098Y372789D01*
X720443Y372737D01*
X720788Y372840D01*
X721056Y373047D01*
X721248Y373409D01*
X721286Y373822D01*
X721210Y374235D01*
X721018Y374494D01*
X720750Y374700D01*
X720481Y374752D01*
X720213Y374700D01*
X719868Y374494D01*
X719983Y375837D01*
X721018D01*
G01X723466Y372737D02*
X723543Y373409D01*
X723658Y373977D01*
X723811Y374494D01*
X724003Y375062D01*
X724310Y375837D01*
X722776D01*
G01X713476Y376737D02*
Y379837D01*
X714435D01*
X714741Y379682D01*
X714933Y379475D01*
X715010Y379062D01*
X714933Y378649D01*
X714703Y378390D01*
X714435Y378235D01*
X713476D01*
G01X714435D02*
X715010Y376737D01*
G01X717266D02*
X717343Y377409D01*
X717458Y377977D01*
X717611Y378494D01*
X717803Y379062D01*
X718110Y379837D01*
X716576D01*
G01X719600Y377202D02*
X719830Y376944D01*
X720098Y376789D01*
X720443Y376737D01*
X720788Y376840D01*
X721056Y377047D01*
X721248Y377409D01*
X721286Y377822D01*
X721210Y378235D01*
X721018Y378494D01*
X720750Y378700D01*
X720481Y378752D01*
X720213Y378700D01*
X719868Y378494D01*
X719983Y379837D01*
X721018D01*
G01X722815Y378029D02*
X723083Y378390D01*
X723313Y378597D01*
X723620Y378700D01*
X723888Y378597D01*
X724080Y378390D01*
X724233Y378080D01*
X724271Y377719D01*
X724233Y377409D01*
X724080Y377099D01*
X723850Y376840D01*
X723581Y376737D01*
X723275Y376840D01*
X723006Y377150D01*
X722853Y377615D01*
X722815Y378132D01*
X722891Y378804D01*
X723006Y379165D01*
X723198Y379527D01*
X723466Y379785D01*
X723735Y379837D01*
X724003Y379734D01*
X724195Y379475D01*
G01X715086Y387645D02*
X714856Y387800D01*
X714588Y387903D01*
X714281D01*
X713936Y387748D01*
X713668Y387490D01*
X713476Y387180D01*
X713323Y386663D01*
X713285Y386198D01*
X713361Y385733D01*
X713476Y385423D01*
X713706Y385113D01*
X713975Y384906D01*
X714243Y384803D01*
X714511D01*
X714780Y384906D01*
X715010Y385061D01*
X715201Y385268D01*
G01X716500D02*
X716730Y385010D01*
X716998Y384855D01*
X717343Y384803D01*
X717688Y384906D01*
X717956Y385113D01*
X718148Y385475D01*
X718186Y385888D01*
X718110Y386301D01*
X717918Y386560D01*
X717650Y386766D01*
X717381Y386818D01*
X717113Y386766D01*
X716768Y386560D01*
X716883Y387903D01*
X717918D01*
G01X720366Y384803D02*
X720443Y385475D01*
X720558Y386043D01*
X720711Y386560D01*
X720903Y387128D01*
X721210Y387903D01*
X719676D01*
G01X722700Y385268D02*
X722930Y385010D01*
X723198Y384855D01*
X723543Y384803D01*
X723888Y384906D01*
X724156Y385113D01*
X724348Y385475D01*
X724386Y385888D01*
X724310Y386301D01*
X724118Y386560D01*
X723850Y386766D01*
X723581Y386818D01*
X723313Y386766D01*
X722968Y386560D01*
X723083Y387903D01*
X724118D01*
G01X713476Y392829D02*
Y395929D01*
X714435D01*
X714741Y395774D01*
X714933Y395567D01*
X715010Y395154D01*
X714933Y394741D01*
X714703Y394482D01*
X714435Y394327D01*
X713476D01*
G01X714435D02*
X715010Y392829D01*
G01X717266D02*
X717343Y393501D01*
X717458Y394069D01*
X717611Y394586D01*
X717803Y395154D01*
X718110Y395929D01*
X716576D01*
G01X719600Y393294D02*
X719830Y393036D01*
X720098Y392881D01*
X720443Y392829D01*
X720788Y392932D01*
X721056Y393139D01*
X721248Y393501D01*
X721286Y393914D01*
X721210Y394327D01*
X721018Y394586D01*
X720750Y394792D01*
X720481Y394844D01*
X720213Y394792D01*
X719868Y394586D01*
X719983Y395929D01*
X721018D01*
G01X724003Y392829D02*
Y395929D01*
X722585Y393707D01*
X724501D01*
G01X713476Y388829D02*
Y391929D01*
X714435D01*
X714741Y391774D01*
X714933Y391567D01*
X715010Y391154D01*
X714933Y390741D01*
X714703Y390482D01*
X714435Y390327D01*
X713476D01*
G01X714435D02*
X715010Y388829D01*
G01X717266D02*
X717343Y389501D01*
X717458Y390069D01*
X717611Y390586D01*
X717803Y391154D01*
X718110Y391929D01*
X716576D01*
G01X719715Y390121D02*
X719983Y390482D01*
X720213Y390689D01*
X720520Y390792D01*
X720788Y390689D01*
X720980Y390482D01*
X721133Y390172D01*
X721171Y389811D01*
X721133Y389501D01*
X720980Y389191D01*
X720750Y388932D01*
X720481Y388829D01*
X720175Y388932D01*
X719906Y389242D01*
X719753Y389707D01*
X719715Y390224D01*
X719791Y390896D01*
X719906Y391257D01*
X720098Y391619D01*
X720366Y391877D01*
X720635Y391929D01*
X720903Y391826D01*
X721095Y391567D01*
G01X724003Y388829D02*
Y391929D01*
X722585Y389707D01*
X724501D01*
G01X713476Y380795D02*
Y383895D01*
X714435D01*
X714741Y383740D01*
X714933Y383533D01*
X715010Y383120D01*
X714933Y382707D01*
X714703Y382448D01*
X714435Y382293D01*
X713476D01*
G01X714435D02*
X715010Y380795D01*
G01X717266D02*
X717343Y381467D01*
X717458Y382035D01*
X717611Y382552D01*
X717803Y383120D01*
X718110Y383895D01*
X716576D01*
G01X719600Y381260D02*
X719830Y381002D01*
X720098Y380847D01*
X720443Y380795D01*
X720788Y380898D01*
X721056Y381105D01*
X721248Y381467D01*
X721286Y381880D01*
X721210Y382293D01*
X721018Y382552D01*
X720750Y382758D01*
X720481Y382810D01*
X720213Y382758D01*
X719868Y382552D01*
X719983Y383895D01*
X721018D01*
G01X723543Y380795D02*
X723811Y380847D01*
X724118Y381002D01*
X724310Y381260D01*
X724386Y381622D01*
X724310Y381983D01*
X724080Y382293D01*
X723735Y382448D01*
X723351D01*
X723121Y382552D01*
X722930Y382810D01*
X722853Y383172D01*
X722968Y383533D01*
X723236Y383792D01*
X723543Y383895D01*
X723850Y383792D01*
X724118Y383533D01*
X724233Y383172D01*
X724156Y382810D01*
X723965Y382552D01*
X723735Y382448D01*
X723351D01*
X723006Y382293D01*
X722776Y381983D01*
X722700Y381622D01*
X722776Y381260D01*
X722968Y381002D01*
X723275Y380847D01*
X723543Y380795D01*
G01X713476Y404829D02*
Y407929D01*
X714435D01*
X714741Y407774D01*
X714933Y407567D01*
X715010Y407154D01*
X714933Y406741D01*
X714703Y406482D01*
X714435Y406327D01*
X713476D01*
G01X714435D02*
X715010Y404829D01*
G01X717266D02*
X717343Y405501D01*
X717458Y406069D01*
X717611Y406586D01*
X717803Y407154D01*
X718110Y407929D01*
X716576D01*
G01X719600Y405294D02*
X719830Y405036D01*
X720098Y404881D01*
X720443Y404829D01*
X720788Y404932D01*
X721056Y405139D01*
X721248Y405501D01*
X721286Y405914D01*
X721210Y406327D01*
X721018Y406586D01*
X720750Y406792D01*
X720481Y406844D01*
X720213Y406792D01*
X719868Y406586D01*
X719983Y407929D01*
X721018D01*
G01X722700Y405449D02*
X722930Y405087D01*
X723236Y404881D01*
X723581Y404829D01*
X723888Y404881D01*
X724195Y405139D01*
X724386Y405449D01*
X724425Y405759D01*
X724348Y406121D01*
X724080Y406379D01*
X723811Y406482D01*
X723466D01*
G01X723811D02*
X724041Y406637D01*
X724233Y406896D01*
X724310Y407206D01*
X724233Y407516D01*
X724041Y407774D01*
X723696Y407929D01*
X723351Y407877D01*
X723006Y407671D01*
G01X713476Y400829D02*
Y403929D01*
X714435D01*
X714741Y403774D01*
X714933Y403567D01*
X715010Y403154D01*
X714933Y402741D01*
X714703Y402482D01*
X714435Y402327D01*
X713476D01*
G01X714435D02*
X715010Y400829D01*
G01X717266D02*
X717343Y401501D01*
X717458Y402069D01*
X717611Y402586D01*
X717803Y403154D01*
X718110Y403929D01*
X716576D01*
G01X719600Y401449D02*
X719830Y401087D01*
X720136Y400881D01*
X720481Y400829D01*
X720788Y400881D01*
X721095Y401139D01*
X721286Y401449D01*
X721325Y401759D01*
X721248Y402121D01*
X720980Y402379D01*
X720711Y402482D01*
X720366D01*
G01X720711D02*
X720941Y402637D01*
X721133Y402896D01*
X721210Y403206D01*
X721133Y403516D01*
X720941Y403774D01*
X720596Y403929D01*
X720251Y403877D01*
X719906Y403671D01*
G01X723543Y400829D02*
X723811Y400881D01*
X724118Y401036D01*
X724310Y401294D01*
X724386Y401656D01*
X724310Y402017D01*
X724080Y402327D01*
X723735Y402482D01*
X723351D01*
X723121Y402586D01*
X722930Y402844D01*
X722853Y403206D01*
X722968Y403567D01*
X723236Y403826D01*
X723543Y403929D01*
X723850Y403826D01*
X724118Y403567D01*
X724233Y403206D01*
X724156Y402844D01*
X723965Y402586D01*
X723735Y402482D01*
X723351D01*
X723006Y402327D01*
X722776Y402017D01*
X722700Y401656D01*
X722776Y401294D01*
X722968Y401036D01*
X723275Y400881D01*
X723543Y400829D01*
G01X713476Y396829D02*
Y399929D01*
X714435D01*
X714741Y399774D01*
X714933Y399567D01*
X715010Y399154D01*
X714933Y398741D01*
X714703Y398482D01*
X714435Y398327D01*
X713476D01*
G01X714435D02*
X715010Y396829D01*
G01X717266D02*
X717343Y397501D01*
X717458Y398069D01*
X717611Y398586D01*
X717803Y399154D01*
X718110Y399929D01*
X716576D01*
G01X719600Y397449D02*
X719830Y397087D01*
X720136Y396881D01*
X720481Y396829D01*
X720788Y396881D01*
X721095Y397139D01*
X721286Y397449D01*
X721325Y397759D01*
X721248Y398121D01*
X720980Y398379D01*
X720711Y398482D01*
X720366D01*
G01X720711D02*
X720941Y398637D01*
X721133Y398896D01*
X721210Y399206D01*
X721133Y399516D01*
X720941Y399774D01*
X720596Y399929D01*
X720251Y399877D01*
X719906Y399671D01*
G01X722891Y397191D02*
X723160Y396932D01*
X723466Y396829D01*
X723773Y396932D01*
X724041Y397242D01*
X724233Y397707D01*
X724310Y398172D01*
Y398741D01*
X724233Y399206D01*
X724041Y399619D01*
X723811Y399826D01*
X723543Y399929D01*
X723236Y399826D01*
X723006Y399619D01*
X722853Y399309D01*
X722776Y398896D01*
X722853Y398534D01*
X723045Y398172D01*
X723275Y397966D01*
X723543Y397914D01*
X723850Y398017D01*
X724080Y398276D01*
X724310Y398741D01*
G01X713476Y408829D02*
Y411929D01*
X714435D01*
X714741Y411774D01*
X714933Y411567D01*
X715010Y411154D01*
X714933Y410741D01*
X714703Y410482D01*
X714435Y410327D01*
X713476D01*
G01X714435D02*
X715010Y408829D01*
G01X717266D02*
X717343Y409501D01*
X717458Y410069D01*
X717611Y410586D01*
X717803Y411154D01*
X718110Y411929D01*
X716576D01*
G01X719600Y409294D02*
X719830Y409036D01*
X720098Y408881D01*
X720443Y408829D01*
X720788Y408932D01*
X721056Y409139D01*
X721248Y409501D01*
X721286Y409914D01*
X721210Y410327D01*
X721018Y410586D01*
X720750Y410792D01*
X720481Y410844D01*
X720213Y410792D01*
X719868Y410586D01*
X719983Y411929D01*
X721018D01*
G01X722815Y411412D02*
X723045Y411722D01*
X723313Y411877D01*
X723620Y411929D01*
X724003Y411826D01*
X724271Y411567D01*
X724348Y411257D01*
X724310Y410947D01*
X724156Y410689D01*
X723390Y410172D01*
X723045Y409811D01*
X722815Y409294D01*
X722738Y408829D01*
X724348D01*
G01X713476Y412829D02*
Y415929D01*
X714435D01*
X714741Y415774D01*
X714933Y415567D01*
X715010Y415154D01*
X714933Y414741D01*
X714703Y414482D01*
X714435Y414327D01*
X713476D01*
G01X714435D02*
X715010Y412829D01*
G01X717266D02*
X717343Y413501D01*
X717458Y414069D01*
X717611Y414586D01*
X717803Y415154D01*
X718110Y415929D01*
X716576D01*
G01X719600Y413449D02*
X719830Y413087D01*
X720136Y412881D01*
X720481Y412829D01*
X720788Y412881D01*
X721095Y413139D01*
X721286Y413449D01*
X721325Y413759D01*
X721248Y414121D01*
X720980Y414379D01*
X720711Y414482D01*
X720366D01*
G01X720711D02*
X720941Y414637D01*
X721133Y414896D01*
X721210Y415206D01*
X721133Y415516D01*
X720941Y415774D01*
X720596Y415929D01*
X720251Y415877D01*
X719906Y415671D01*
G01X723466Y412829D02*
X723543Y413501D01*
X723658Y414069D01*
X723811Y414586D01*
X724003Y415154D01*
X724310Y415929D01*
X722776D01*
G01X709440Y443323D02*
Y446423D01*
X708980Y445803D01*
G01Y443323D02*
X709900D01*
G01X700723Y443943D02*
X700953Y443581D01*
X701259Y443375D01*
X701604Y443323D01*
X701911Y443375D01*
X702218Y443633D01*
X702409Y443943D01*
X702448Y444253D01*
X702371Y444615D01*
X702103Y444873D01*
X701834Y444976D01*
X701489D01*
G01X701834D02*
X702064Y445131D01*
X702256Y445390D01*
X702333Y445700D01*
X702256Y446010D01*
X702064Y446268D01*
X701719Y446423D01*
X701374Y446371D01*
X701029Y446165D01*
G01X704775Y449843D02*
X705005Y450153D01*
X705273Y450308D01*
X705580Y450360D01*
X705963Y450257D01*
X706231Y449998D01*
X706308Y449688D01*
X706270Y449378D01*
X706116Y449120D01*
X705350Y448603D01*
X705005Y448242D01*
X704775Y447725D01*
X704698Y447260D01*
X706308D01*
G01X709261Y514830D02*
Y511630D01*
G01X703061Y514830D02*
X709261D01*
G01X703061Y511630D02*
Y514830D01*
G01X709261Y511630D02*
X703061D01*
G01X711295Y511834D02*
Y515034D01*
G01X717495Y511834D02*
X711295D01*
G01Y515034D02*
X717495D01*
G01X711960Y518099D02*
X711835Y517939D01*
X711752Y517752D01*
Y517539D01*
X711877Y517299D01*
X712085Y517112D01*
X712335Y516979D01*
X712752Y516872D01*
X713127Y516845D01*
X713502Y516899D01*
X713752Y516979D01*
X714002Y517139D01*
X714169Y517325D01*
X714252Y517512D01*
Y517699D01*
X714169Y517885D01*
X714044Y518045D01*
X713877Y518179D01*
G01X702095Y518099D02*
X701970Y517939D01*
X701887Y517752D01*
Y517539D01*
X702012Y517299D01*
X702220Y517112D01*
X702470Y516979D01*
X702887Y516872D01*
X703262Y516845D01*
X703637Y516899D01*
X703887Y516979D01*
X704137Y517139D01*
X704304Y517325D01*
X704387Y517512D01*
Y517699D01*
X704304Y517885D01*
X704179Y518045D01*
X704012Y518179D01*
G01X715061Y533430D02*
Y536630D01*
G01X721261Y533430D02*
X715061D01*
G01X713300Y533936D02*
X712234D01*
Y536436D01*
X713300D01*
G01X712874Y535228D02*
X712234D01*
G01X709981Y518956D02*
Y531430D01*
G01X722061Y518956D02*
X709981D01*
G01Y531430D02*
X722061D01*
G01X709715Y535708D02*
X709822Y535833D01*
X709902Y536042D01*
X709955Y536333D01*
X709902Y536583D01*
X709795Y536750D01*
X709609Y536875D01*
X708889D01*
Y534375D01*
X709769D01*
X709955Y534542D01*
X710062Y534792D01*
X710115Y535083D01*
X710062Y535375D01*
X709902Y535625D01*
X709715Y535708D01*
X708889D01*
G01X708661Y531530D02*
Y519056D01*
G01X711762Y551786D02*
X711532Y551941D01*
X711264Y552044D01*
X710957D01*
X710612Y551889D01*
X710344Y551631D01*
X710152Y551321D01*
X709999Y550804D01*
X709961Y550339D01*
X710037Y549874D01*
X710152Y549564D01*
X710382Y549254D01*
X710651Y549047D01*
X710919Y548944D01*
X711187D01*
X711456Y549047D01*
X711686Y549202D01*
X711877Y549409D01*
G01X713942Y548944D02*
X714019Y549616D01*
X714134Y550184D01*
X714287Y550701D01*
X714479Y551269D01*
X714786Y552044D01*
X713252D01*
G01X716467Y549306D02*
X716736Y549047D01*
X717042Y548944D01*
X717349Y549047D01*
X717617Y549357D01*
X717809Y549822D01*
X717886Y550287D01*
Y550856D01*
X717809Y551321D01*
X717617Y551734D01*
X717387Y551941D01*
X717119Y552044D01*
X716812Y551941D01*
X716582Y551734D01*
X716429Y551424D01*
X716352Y551011D01*
X716429Y550649D01*
X716621Y550287D01*
X716851Y550081D01*
X717119Y550029D01*
X717426Y550132D01*
X717656Y550391D01*
X717886Y550856D01*
G01X719567Y549306D02*
X719836Y549047D01*
X720142Y548944D01*
X720449Y549047D01*
X720717Y549357D01*
X720909Y549822D01*
X720986Y550287D01*
Y550856D01*
X720909Y551321D01*
X720717Y551734D01*
X720487Y551941D01*
X720219Y552044D01*
X719912Y551941D01*
X719682Y551734D01*
X719529Y551424D01*
X719452Y551011D01*
X719529Y550649D01*
X719721Y550287D01*
X719951Y550081D01*
X720219Y550029D01*
X720526Y550132D01*
X720756Y550391D01*
X720986Y550856D01*
G01X705698Y551415D02*
Y548215D01*
G01X702598Y548315D02*
Y551315D01*
G01X716942Y544818D02*
X716712Y544973D01*
X716444Y545076D01*
X716137D01*
X715792Y544921D01*
X715524Y544663D01*
X715332Y544353D01*
X715179Y543836D01*
X715141Y543371D01*
X715217Y542906D01*
X715332Y542596D01*
X715562Y542286D01*
X715831Y542079D01*
X716099Y541976D01*
X716367D01*
X716636Y542079D01*
X716866Y542234D01*
X717057Y542441D01*
G01X719122Y541976D02*
X719199Y542648D01*
X719314Y543216D01*
X719467Y543733D01*
X719659Y544301D01*
X719966Y545076D01*
X718432D01*
G01X721647Y542338D02*
X721916Y542079D01*
X722222Y541976D01*
X722529Y542079D01*
X722797Y542389D01*
X722989Y542854D01*
X723066Y543319D01*
Y543888D01*
X722989Y544353D01*
X722797Y544766D01*
X722567Y544973D01*
X722299Y545076D01*
X721992Y544973D01*
X721762Y544766D01*
X721609Y544456D01*
X721532Y544043D01*
X721609Y543681D01*
X721801Y543319D01*
X722031Y543113D01*
X722299Y543061D01*
X722606Y543164D01*
X722836Y543423D01*
X723066Y543888D01*
G01X725399Y541976D02*
X725667Y542028D01*
X725974Y542183D01*
X726166Y542441D01*
X726242Y542803D01*
X726166Y543164D01*
X725936Y543474D01*
X725591Y543629D01*
X725207D01*
X724977Y543733D01*
X724786Y543991D01*
X724709Y544353D01*
X724824Y544714D01*
X725092Y544973D01*
X725399Y545076D01*
X725706Y544973D01*
X725974Y544714D01*
X726089Y544353D01*
X726012Y543991D01*
X725821Y543733D01*
X725591Y543629D01*
X725207D01*
X724862Y543474D01*
X724632Y543164D01*
X724556Y542803D01*
X724632Y542441D01*
X724824Y542183D01*
X725131Y542028D01*
X725399Y541976D01*
G01X706845Y547208D02*
Y540608D01*
G01X714345Y547308D02*
Y540508D01*
G01X715061Y536630D02*
X721261D01*
G01X701626Y533799D02*
Y536999D01*
G01X707826Y533799D02*
X701626D01*
G01X707826Y536999D02*
Y533799D01*
G01X701626Y536999D02*
X707826D01*
G01X714850Y557547D02*
X714620Y557702D01*
X714352Y557805D01*
X714045D01*
X713700Y557650D01*
X713432Y557392D01*
X713240Y557082D01*
X713087Y556565D01*
X713049Y556100D01*
X713125Y555635D01*
X713240Y555325D01*
X713470Y555015D01*
X713739Y554808D01*
X714007Y554705D01*
X714275D01*
X714544Y554808D01*
X714774Y554963D01*
X714965Y555170D01*
G01X717567Y554705D02*
Y557805D01*
X716149Y555583D01*
X718065D01*
G01X720667Y554705D02*
Y557805D01*
X719249Y555583D01*
X721165D01*
G01X723307Y554705D02*
X723575Y554757D01*
X723882Y554912D01*
X724074Y555170D01*
X724150Y555532D01*
X724074Y555893D01*
X723844Y556203D01*
X723499Y556358D01*
X723115D01*
X722885Y556462D01*
X722694Y556720D01*
X722617Y557082D01*
X722732Y557443D01*
X723000Y557702D01*
X723307Y557805D01*
X723614Y557702D01*
X723882Y557443D01*
X723997Y557082D01*
X723920Y556720D01*
X723729Y556462D01*
X723499Y556358D01*
X723115D01*
X722770Y556203D01*
X722540Y555893D01*
X722464Y555532D01*
X722540Y555170D01*
X722732Y554912D01*
X723039Y554757D01*
X723307Y554705D01*
G01X712359Y560930D02*
Y565530D01*
G01X722559Y560930D02*
X712359D01*
G01X706923Y565756D02*
Y558956D01*
G01X712359Y565530D02*
X722559D01*
G01X706908Y581780D02*
Y574980D01*
G01Y573780D02*
Y566980D01*
G01X711023Y567003D02*
X707923D01*
Y567962D01*
X708078Y568268D01*
X708285Y568460D01*
X708698Y568537D01*
X709111Y568460D01*
X709370Y568230D01*
X709525Y567962D01*
Y567003D01*
G01Y567962D02*
X711023Y568537D01*
G01X710558Y570027D02*
X710816Y570257D01*
X710971Y570525D01*
X711023Y570870D01*
X710920Y571215D01*
X710713Y571483D01*
X710351Y571675D01*
X709938Y571713D01*
X709525Y571637D01*
X709266Y571445D01*
X709060Y571177D01*
X709008Y570908D01*
X709060Y570640D01*
X709266Y570295D01*
X707923Y570410D01*
Y571445D01*
G01X710661Y573318D02*
X710920Y573587D01*
X711023Y573893D01*
X710920Y574200D01*
X710610Y574468D01*
X710145Y574660D01*
X709680Y574737D01*
X709111D01*
X708646Y574660D01*
X708233Y574468D01*
X708026Y574238D01*
X707923Y573970D01*
X708026Y573663D01*
X708233Y573433D01*
X708543Y573280D01*
X708956Y573203D01*
X709318Y573280D01*
X709680Y573472D01*
X709886Y573702D01*
X709938Y573970D01*
X709835Y574277D01*
X709576Y574507D01*
X709111Y574737D01*
G01X711023Y577530D02*
X707923D01*
X710145Y576112D01*
Y578028D01*
G01X711313Y580919D02*
X708213D01*
Y581878D01*
X708368Y582184D01*
X708575Y582376D01*
X708988Y582453D01*
X709401Y582376D01*
X709660Y582146D01*
X709815Y581878D01*
Y580919D01*
G01Y581878D02*
X711313Y582453D01*
G01X710848Y583943D02*
X711106Y584173D01*
X711261Y584441D01*
X711313Y584786D01*
X711210Y585131D01*
X711003Y585399D01*
X710641Y585591D01*
X710228Y585629D01*
X709815Y585553D01*
X709556Y585361D01*
X709350Y585093D01*
X709298Y584824D01*
X709350Y584556D01*
X709556Y584211D01*
X708213Y584326D01*
Y585361D01*
G01X710951Y587234D02*
X711210Y587503D01*
X711313Y587809D01*
X711210Y588116D01*
X710900Y588384D01*
X710435Y588576D01*
X709970Y588653D01*
X709401D01*
X708936Y588576D01*
X708523Y588384D01*
X708316Y588154D01*
X708213Y587886D01*
X708316Y587579D01*
X708523Y587349D01*
X708833Y587196D01*
X709246Y587119D01*
X709608Y587196D01*
X709970Y587388D01*
X710176Y587618D01*
X710228Y587886D01*
X710125Y588193D01*
X709866Y588423D01*
X709401Y588653D01*
G01X710848Y590143D02*
X711106Y590373D01*
X711261Y590641D01*
X711313Y590986D01*
X711210Y591331D01*
X711003Y591599D01*
X710641Y591791D01*
X710228Y591829D01*
X709815Y591753D01*
X709556Y591561D01*
X709350Y591293D01*
X709298Y591024D01*
X709350Y590756D01*
X709556Y590411D01*
X708213Y590526D01*
Y591561D01*
G01X722035Y578751D02*
X714635D01*
G01D02*
Y596151D01*
G01X706908Y589780D02*
Y582980D01*
G01X714635Y596151D02*
X722035D01*
G01X713316Y603943D02*
X710216D01*
Y604902D01*
X710371Y605208D01*
X710578Y605400D01*
X710991Y605477D01*
X711404Y605400D01*
X711663Y605170D01*
X711818Y604902D01*
Y603943D01*
G01Y604902D02*
X713316Y605477D01*
G01X712851Y606967D02*
X713109Y607197D01*
X713264Y607465D01*
X713316Y607810D01*
X713213Y608155D01*
X713006Y608423D01*
X712644Y608615D01*
X712231Y608653D01*
X711818Y608577D01*
X711559Y608385D01*
X711353Y608117D01*
X711301Y607848D01*
X711353Y607580D01*
X711559Y607235D01*
X710216Y607350D01*
Y608385D01*
G01X713316Y610833D02*
X712644Y610910D01*
X712076Y611025D01*
X711559Y611178D01*
X710991Y611370D01*
X710216Y611677D01*
Y610143D01*
G01X713316Y614010D02*
X713264Y614278D01*
X713109Y614585D01*
X712851Y614777D01*
X712489Y614853D01*
X712128Y614777D01*
X711818Y614547D01*
X711663Y614202D01*
Y613818D01*
X711559Y613588D01*
X711301Y613397D01*
X710939Y613320D01*
X710578Y613435D01*
X710319Y613703D01*
X710216Y614010D01*
X710319Y614317D01*
X710578Y614585D01*
X710939Y614700D01*
X711301Y614623D01*
X711559Y614432D01*
X711663Y614202D01*
Y613818D01*
X711818Y613473D01*
X712128Y613243D01*
X712489Y613167D01*
X712851Y613243D01*
X713109Y613435D01*
X713264Y613742D01*
X713316Y614010D01*
G01X717316Y603943D02*
X714216D01*
Y604902D01*
X714371Y605208D01*
X714578Y605400D01*
X714991Y605477D01*
X715404Y605400D01*
X715663Y605170D01*
X715818Y604902D01*
Y603943D01*
G01Y604902D02*
X717316Y605477D01*
G01X716851Y606967D02*
X717109Y607197D01*
X717264Y607465D01*
X717316Y607810D01*
X717213Y608155D01*
X717006Y608423D01*
X716644Y608615D01*
X716231Y608653D01*
X715818Y608577D01*
X715559Y608385D01*
X715353Y608117D01*
X715301Y607848D01*
X715353Y607580D01*
X715559Y607235D01*
X714216Y607350D01*
Y608385D01*
G01X717316Y610910D02*
X717264Y611178D01*
X717109Y611485D01*
X716851Y611677D01*
X716489Y611753D01*
X716128Y611677D01*
X715818Y611447D01*
X715663Y611102D01*
Y610718D01*
X715559Y610488D01*
X715301Y610297D01*
X714939Y610220D01*
X714578Y610335D01*
X714319Y610603D01*
X714216Y610910D01*
X714319Y611217D01*
X714578Y611485D01*
X714939Y611600D01*
X715301Y611523D01*
X715559Y611332D01*
X715663Y611102D01*
Y610718D01*
X715818Y610373D01*
X716128Y610143D01*
X716489Y610067D01*
X716851Y610143D01*
X717109Y610335D01*
X717264Y610642D01*
X717316Y610910D01*
G01X714216Y614010D02*
X714319Y613703D01*
X714578Y613473D01*
X714888Y613320D01*
X715301Y613205D01*
X715766Y613167D01*
X716231Y613205D01*
X716644Y613320D01*
X716954Y613473D01*
X717213Y613703D01*
X717316Y614010D01*
X717213Y614317D01*
X716954Y614547D01*
X716644Y614700D01*
X716231Y614815D01*
X715766Y614853D01*
X715301Y614815D01*
X714888Y614700D01*
X714578Y614547D01*
X714319Y614317D01*
X714216Y614010D01*
G01X705156Y603943D02*
X702056D01*
Y604902D01*
X702211Y605208D01*
X702418Y605400D01*
X702831Y605477D01*
X703244Y605400D01*
X703503Y605170D01*
X703658Y604902D01*
Y603943D01*
G01Y604902D02*
X705156Y605477D01*
G01X704691Y606967D02*
X704949Y607197D01*
X705104Y607465D01*
X705156Y607810D01*
X705053Y608155D01*
X704846Y608423D01*
X704484Y608615D01*
X704071Y608653D01*
X703658Y608577D01*
X703399Y608385D01*
X703193Y608117D01*
X703141Y607848D01*
X703193Y607580D01*
X703399Y607235D01*
X702056Y607350D01*
Y608385D01*
G01X705156Y610833D02*
X704484Y610910D01*
X703916Y611025D01*
X703399Y611178D01*
X702831Y611370D01*
X702056Y611677D01*
Y610143D01*
G01X703864Y613282D02*
X703503Y613550D01*
X703296Y613780D01*
X703193Y614087D01*
X703296Y614355D01*
X703503Y614547D01*
X703813Y614700D01*
X704174Y614738D01*
X704484Y614700D01*
X704794Y614547D01*
X705053Y614317D01*
X705156Y614048D01*
X705053Y613742D01*
X704743Y613473D01*
X704278Y613320D01*
X703761Y613282D01*
X703089Y613358D01*
X702728Y613473D01*
X702366Y613665D01*
X702108Y613933D01*
X702056Y614202D01*
X702159Y614470D01*
X702418Y614662D01*
G01X709316Y603943D02*
X706216D01*
Y604902D01*
X706371Y605208D01*
X706578Y605400D01*
X706991Y605477D01*
X707404Y605400D01*
X707663Y605170D01*
X707818Y604902D01*
Y603943D01*
G01Y604902D02*
X709316Y605477D01*
G01X708851Y606967D02*
X709109Y607197D01*
X709264Y607465D01*
X709316Y607810D01*
X709213Y608155D01*
X709006Y608423D01*
X708644Y608615D01*
X708231Y608653D01*
X707818Y608577D01*
X707559Y608385D01*
X707353Y608117D01*
X707301Y607848D01*
X707353Y607580D01*
X707559Y607235D01*
X706216Y607350D01*
Y608385D01*
G01X709316Y610910D02*
X709264Y611178D01*
X709109Y611485D01*
X708851Y611677D01*
X708489Y611753D01*
X708128Y611677D01*
X707818Y611447D01*
X707663Y611102D01*
Y610718D01*
X707559Y610488D01*
X707301Y610297D01*
X706939Y610220D01*
X706578Y610335D01*
X706319Y610603D01*
X706216Y610910D01*
X706319Y611217D01*
X706578Y611485D01*
X706939Y611600D01*
X707301Y611523D01*
X707559Y611332D01*
X707663Y611102D01*
Y610718D01*
X707818Y610373D01*
X708128Y610143D01*
X708489Y610067D01*
X708851Y610143D01*
X709109Y610335D01*
X709264Y610642D01*
X709316Y610910D01*
G01X708024Y613282D02*
X707663Y613550D01*
X707456Y613780D01*
X707353Y614087D01*
X707456Y614355D01*
X707663Y614547D01*
X707973Y614700D01*
X708334Y614738D01*
X708644Y614700D01*
X708954Y614547D01*
X709213Y614317D01*
X709316Y614048D01*
X709213Y613742D01*
X708903Y613473D01*
X708438Y613320D01*
X707921Y613282D01*
X707249Y613358D01*
X706888Y613473D01*
X706526Y613665D01*
X706268Y613933D01*
X706216Y614202D01*
X706319Y614470D01*
X706578Y614662D01*
G01X714937Y669462D02*
Y667240D01*
X715090Y666775D01*
X715397Y666465D01*
X715780Y666362D01*
X716163Y666465D01*
X716470Y666775D01*
X716623Y667240D01*
Y669462D01*
G01X718880Y666362D02*
Y669462D01*
X718420Y668842D01*
G01Y666362D02*
X719340D01*
G01X721137Y666982D02*
X721367Y666620D01*
X721673Y666414D01*
X722018Y666362D01*
X722325Y666414D01*
X722632Y666672D01*
X722823Y666982D01*
X722862Y667292D01*
X722785Y667654D01*
X722517Y667912D01*
X722248Y668015D01*
X721903D01*
G01X722248D02*
X722478Y668170D01*
X722670Y668429D01*
X722747Y668739D01*
X722670Y669049D01*
X722478Y669307D01*
X722133Y669462D01*
X721788Y669410D01*
X721443Y669204D01*
G01X725080Y666362D02*
X725348Y666414D01*
X725655Y666569D01*
X725847Y666827D01*
X725923Y667189D01*
X725847Y667550D01*
X725617Y667860D01*
X725272Y668015D01*
X724888D01*
X724658Y668119D01*
X724467Y668377D01*
X724390Y668739D01*
X724505Y669100D01*
X724773Y669359D01*
X725080Y669462D01*
X725387Y669359D01*
X725655Y669100D01*
X725770Y668739D01*
X725693Y668377D01*
X725502Y668119D01*
X725272Y668015D01*
X724888D01*
X724543Y667860D01*
X724313Y667550D01*
X724237Y667189D01*
X724313Y666827D01*
X724505Y666569D01*
X724812Y666414D01*
X725080Y666362D01*
G01X710700Y746583D02*
X707600D01*
Y747542D01*
X707755Y747848D01*
X707962Y748040D01*
X708375Y748117D01*
X708788Y748040D01*
X709047Y747810D01*
X709202Y747542D01*
Y746583D01*
G01Y747542D02*
X710700Y748117D01*
G01Y750450D02*
X707600D01*
X708220Y749990D01*
G01X710700D02*
Y750910D01*
G01X708117Y752822D02*
X707807Y753052D01*
X707652Y753320D01*
X707600Y753627D01*
X707703Y754010D01*
X707962Y754278D01*
X708272Y754355D01*
X708582Y754317D01*
X708840Y754163D01*
X709357Y753397D01*
X709718Y753052D01*
X710235Y752822D01*
X710700Y752745D01*
Y754355D01*
G01X710338Y755998D02*
X710597Y756267D01*
X710700Y756573D01*
X710597Y756880D01*
X710287Y757148D01*
X709822Y757340D01*
X709357Y757417D01*
X708788D01*
X708323Y757340D01*
X707910Y757148D01*
X707703Y756918D01*
X707600Y756650D01*
X707703Y756343D01*
X707910Y756113D01*
X708220Y755960D01*
X708633Y755883D01*
X708995Y755960D01*
X709357Y756152D01*
X709563Y756382D01*
X709615Y756650D01*
X709512Y756957D01*
X709253Y757187D01*
X708788Y757417D01*
G01X710700Y760210D02*
X707600D01*
X709822Y758792D01*
Y760708D01*
G01X711000Y744900D02*
Y738700D01*
X707800D01*
Y744900D01*
X711000D01*
G01X715200Y746583D02*
X712100D01*
Y747542D01*
X712255Y747848D01*
X712462Y748040D01*
X712875Y748117D01*
X713288Y748040D01*
X713547Y747810D01*
X713702Y747542D01*
Y746583D01*
G01Y747542D02*
X715200Y748117D01*
G01Y750450D02*
X712100D01*
X712720Y749990D01*
G01X715200D02*
Y750910D01*
G01X712617Y752822D02*
X712307Y753052D01*
X712152Y753320D01*
X712100Y753627D01*
X712203Y754010D01*
X712462Y754278D01*
X712772Y754355D01*
X713082Y754317D01*
X713340Y754163D01*
X713857Y753397D01*
X714218Y753052D01*
X714735Y752822D01*
X715200Y752745D01*
Y754355D01*
G01X714838Y755998D02*
X715097Y756267D01*
X715200Y756573D01*
X715097Y756880D01*
X714787Y757148D01*
X714322Y757340D01*
X713857Y757417D01*
X713288D01*
X712823Y757340D01*
X712410Y757148D01*
X712203Y756918D01*
X712100Y756650D01*
X712203Y756343D01*
X712410Y756113D01*
X712720Y755960D01*
X713133Y755883D01*
X713495Y755960D01*
X713857Y756152D01*
X714063Y756382D01*
X714115Y756650D01*
X714012Y756957D01*
X713753Y757187D01*
X713288Y757417D01*
G01X714735Y758907D02*
X714993Y759137D01*
X715148Y759405D01*
X715200Y759750D01*
X715097Y760095D01*
X714890Y760363D01*
X714528Y760555D01*
X714115Y760593D01*
X713702Y760517D01*
X713443Y760325D01*
X713237Y760057D01*
X713185Y759788D01*
X713237Y759520D01*
X713443Y759175D01*
X712100Y759290D01*
Y760325D01*
G01X715000Y744900D02*
Y738700D01*
X711800D01*
Y744900D01*
X715000D01*
G01X718503Y-9607D02*
Y236D01*
G01X729771Y4012D02*
X730188Y4519D01*
X730438Y5089D01*
Y5595D01*
X730188Y6102D01*
X729771Y6482D01*
X729188Y6672D01*
X728605Y6545D01*
X728105Y6229D01*
X727771Y5659D01*
X727605Y4899D01*
X727271Y4455D01*
X726688Y4265D01*
X726105Y4392D01*
X725688Y4709D01*
X725438Y5152D01*
Y5595D01*
X725605Y6039D01*
X726021Y6419D01*
G01X725438Y10442D02*
X730438D01*
G01X725438Y8985D02*
Y11899D01*
G01X730438Y13959D02*
X725438Y15542D01*
X730438Y17125D01*
G01X728688Y16555D02*
Y14529D01*
G01X725438Y20642D02*
X730438D01*
G01X725438Y19185D02*
Y22099D01*
G01Y24349D02*
X729021D01*
X729771Y24602D01*
X730271Y25109D01*
X730438Y25742D01*
X730271Y26375D01*
X729771Y26882D01*
X729021Y27135D01*
X725438D01*
G01X729771Y29512D02*
X730188Y30019D01*
X730438Y30589D01*
Y31095D01*
X730188Y31602D01*
X729771Y31982D01*
X729188Y32172D01*
X728605Y32045D01*
X728105Y31729D01*
X727771Y31159D01*
X727605Y30399D01*
X727271Y29955D01*
X726688Y29765D01*
X726105Y29892D01*
X725688Y30209D01*
X725438Y30652D01*
Y31095D01*
X725605Y31539D01*
X726021Y31919D01*
G01X725438Y39775D02*
X730438D01*
Y42309D01*
G01Y47409D02*
Y44875D01*
X725438D01*
Y47409D01*
G01X727855Y46395D02*
Y44875D01*
G01X730438Y49849D02*
X725438D01*
Y51115D01*
X725688Y51622D01*
X726021Y52002D01*
X726521Y52319D01*
X727105Y52572D01*
X727938Y52635D01*
X728771Y52572D01*
X729355Y52319D01*
X729855Y52002D01*
X730188Y51622D01*
X730438Y51115D01*
Y49849D01*
G01X724960Y54126D02*
X733148D01*
Y3023D01*
X724113D01*
Y54126D01*
X724960D01*
G01X720905Y236D02*
Y28308D01*
G01X718503Y236D02*
X720905D01*
G01X722287Y19984D02*
X722447Y19692D01*
X722661Y19526D01*
X722901Y19484D01*
X723114Y19526D01*
X723327Y19734D01*
X723461Y19984D01*
X723487Y20234D01*
X723434Y20526D01*
X723247Y20734D01*
X723061Y20817D01*
X722821D01*
G01X723061D02*
X723221Y20942D01*
X723354Y21151D01*
X723407Y21401D01*
X723354Y21651D01*
X723221Y21859D01*
X722981Y21984D01*
X722741Y21942D01*
X722501Y21776D01*
G01X720905Y25008D02*
Y36220D01*
G01X720206Y38325D02*
X717106D01*
Y39091D01*
X717261Y39398D01*
X717468Y39628D01*
X717778Y39820D01*
X718139Y39973D01*
X718656Y40011D01*
X719173Y39973D01*
X719534Y39820D01*
X719844Y39628D01*
X720051Y39398D01*
X720206Y39091D01*
Y38325D01*
G01Y42268D02*
X717106D01*
X717726Y41808D01*
G01X720206D02*
Y42728D01*
G01X719844Y44716D02*
X720103Y44985D01*
X720206Y45291D01*
X720103Y45598D01*
X719793Y45866D01*
X719328Y46058D01*
X718863Y46135D01*
X718294D01*
X717829Y46058D01*
X717416Y45866D01*
X717209Y45636D01*
X717106Y45368D01*
X717209Y45061D01*
X717416Y44831D01*
X717726Y44678D01*
X718139Y44601D01*
X718501Y44678D01*
X718863Y44870D01*
X719069Y45100D01*
X719121Y45368D01*
X719018Y45675D01*
X718759Y45905D01*
X718294Y46135D01*
G01X727734Y102581D02*
X727894Y102831D01*
X728081Y102956D01*
X728294Y102998D01*
X728561Y102915D01*
X728748Y102706D01*
X728801Y102456D01*
X728774Y102206D01*
X728668Y101998D01*
X728134Y101581D01*
X727894Y101290D01*
X727734Y100873D01*
X727681Y100498D01*
X728801D01*
G01X721457Y107021D02*
X743111D01*
G01X721457Y124675D02*
Y107021D01*
G01X717217Y116568D02*
X717062Y116338D01*
X716959Y116070D01*
Y115763D01*
X717114Y115418D01*
X717372Y115150D01*
X717682Y114958D01*
X718199Y114805D01*
X718664Y114767D01*
X719129Y114843D01*
X719439Y114958D01*
X719749Y115188D01*
X719956Y115457D01*
X720059Y115725D01*
Y115993D01*
X719956Y116262D01*
X719801Y116492D01*
X719594Y116683D01*
G01X720059Y119592D02*
Y118058D01*
X716959D01*
Y119592D01*
G01X718457Y118978D02*
Y118058D01*
G01X717476Y121197D02*
X717166Y121427D01*
X717011Y121695D01*
X716959Y122002D01*
X717062Y122385D01*
X717321Y122653D01*
X717631Y122730D01*
X717941Y122692D01*
X718199Y122538D01*
X718716Y121772D01*
X719077Y121427D01*
X719594Y121197D01*
X720059Y121120D01*
Y122730D01*
G01X728168Y132082D02*
Y134582D01*
X727848Y134082D01*
G01Y132082D02*
X728488D01*
G01X739111Y128675D02*
X725457D01*
G01D02*
X721457Y124675D01*
G01X720258Y134531D02*
Y137631D01*
X719798Y137011D01*
G01Y134531D02*
X720718D01*
G01X717875Y139455D02*
X727675D01*
G01X724127Y200617D02*
Y203717D01*
X722709Y201495D01*
X724625D01*
G01X727675Y199455D02*
X717875D01*
G01X721197Y214303D02*
Y217403D01*
X720737Y216783D01*
G01Y214303D02*
X721657D01*
G01X717875Y218261D02*
X727675D01*
G01X724781Y279255D02*
Y282355D01*
X723363Y280133D01*
X725279D01*
G01X727675Y278261D02*
X717875D01*
G01X733307Y349934D02*
X730207D01*
Y350893D01*
X730362Y351199D01*
X730569Y351391D01*
X730982Y351468D01*
X731395Y351391D01*
X731654Y351161D01*
X731809Y350893D01*
Y349934D01*
G01Y350893D02*
X733307Y351468D01*
G01X732015Y353073D02*
X731654Y353341D01*
X731447Y353571D01*
X731344Y353878D01*
X731447Y354146D01*
X731654Y354338D01*
X731964Y354491D01*
X732325Y354529D01*
X732635Y354491D01*
X732945Y354338D01*
X733204Y354108D01*
X733307Y353839D01*
X733204Y353533D01*
X732894Y353264D01*
X732429Y353111D01*
X731912Y353073D01*
X731240Y353149D01*
X730879Y353264D01*
X730517Y353456D01*
X730259Y353724D01*
X730207Y353993D01*
X730310Y354261D01*
X730569Y354453D01*
G01X732842Y356058D02*
X733100Y356288D01*
X733255Y356556D01*
X733307Y356901D01*
X733204Y357246D01*
X732997Y357514D01*
X732635Y357706D01*
X732222Y357744D01*
X731809Y357668D01*
X731550Y357476D01*
X731344Y357208D01*
X731292Y356939D01*
X731344Y356671D01*
X731550Y356326D01*
X730207Y356441D01*
Y357476D01*
G01X732842Y359158D02*
X733100Y359388D01*
X733255Y359656D01*
X733307Y360001D01*
X733204Y360346D01*
X732997Y360614D01*
X732635Y360806D01*
X732222Y360844D01*
X731809Y360768D01*
X731550Y360576D01*
X731344Y360308D01*
X731292Y360039D01*
X731344Y359771D01*
X731550Y359426D01*
X730207Y359541D01*
Y360576D01*
G01X725644Y346307D02*
X727866D01*
X728331Y346460D01*
X728641Y346767D01*
X728744Y347150D01*
X728641Y347533D01*
X728331Y347840D01*
X727866Y347993D01*
X725644D01*
G01X728744Y350250D02*
X725644D01*
X726264Y349790D01*
G01X728744D02*
Y350710D01*
G01X725644Y353350D02*
X725747Y353043D01*
X726006Y352813D01*
X726316Y352660D01*
X726729Y352545D01*
X727194Y352507D01*
X727659Y352545D01*
X728072Y352660D01*
X728382Y352813D01*
X728641Y353043D01*
X728744Y353350D01*
X728641Y353657D01*
X728382Y353887D01*
X728072Y354040D01*
X727659Y354155D01*
X727194Y354193D01*
X726729Y354155D01*
X726316Y354040D01*
X726006Y353887D01*
X725747Y353657D01*
X725644Y353350D01*
G01X728279Y355607D02*
X728537Y355837D01*
X728692Y356105D01*
X728744Y356450D01*
X728641Y356795D01*
X728434Y357063D01*
X728072Y357255D01*
X727659Y357293D01*
X727246Y357217D01*
X726987Y357025D01*
X726781Y356757D01*
X726729Y356488D01*
X726781Y356220D01*
X726987Y355875D01*
X725644Y355990D01*
Y357025D01*
G01X726194Y416340D02*
Y414118D01*
X726347Y413653D01*
X726654Y413343D01*
X727037Y413240D01*
X727420Y413343D01*
X727727Y413653D01*
X727880Y414118D01*
Y416340D01*
G01X730137Y413240D02*
Y416340D01*
X729677Y415720D01*
G01Y413240D02*
X730597D01*
G01X732394Y413860D02*
X732624Y413498D01*
X732930Y413292D01*
X733275Y413240D01*
X733582Y413292D01*
X733889Y413550D01*
X734080Y413860D01*
X734119Y414170D01*
X734042Y414532D01*
X733774Y414790D01*
X733505Y414893D01*
X733160D01*
G01X733505D02*
X733735Y415048D01*
X733927Y415307D01*
X734004Y415617D01*
X733927Y415927D01*
X733735Y416185D01*
X733390Y416340D01*
X733045Y416288D01*
X732700Y416082D01*
G01X736337Y413240D02*
Y416340D01*
X735877Y415720D01*
G01Y413240D02*
X736797D01*
G01X717664Y417528D02*
Y420628D01*
X718623D01*
X718929Y420473D01*
X719121Y420266D01*
X719198Y419853D01*
X719121Y419440D01*
X718891Y419181D01*
X718623Y419026D01*
X717664D01*
G01X718623D02*
X719198Y417528D01*
G01X721531D02*
Y420628D01*
X721071Y420008D01*
G01Y417528D02*
X721991D01*
G01X725091D02*
Y420628D01*
X723673Y418406D01*
X725589D01*
G01X727003Y418820D02*
X727271Y419181D01*
X727501Y419388D01*
X727808Y419491D01*
X728076Y419388D01*
X728268Y419181D01*
X728421Y418871D01*
X728459Y418510D01*
X728421Y418200D01*
X728268Y417890D01*
X728038Y417631D01*
X727769Y417528D01*
X727463Y417631D01*
X727194Y417941D01*
X727041Y418406D01*
X727003Y418923D01*
X727079Y419595D01*
X727194Y419956D01*
X727386Y420318D01*
X727654Y420576D01*
X727923Y420628D01*
X728191Y420525D01*
X728383Y420266D01*
G01X728060Y436183D02*
Y439283D01*
X729019D01*
X729325Y439128D01*
X729517Y438921D01*
X729594Y438508D01*
X729517Y438095D01*
X729287Y437836D01*
X729019Y437681D01*
X728060D01*
G01X729019D02*
X729594Y436183D01*
G01X731927D02*
Y439283D01*
X731467Y438663D01*
G01Y436183D02*
X732387D01*
G01X735027Y439283D02*
X734720Y439180D01*
X734490Y438921D01*
X734337Y438611D01*
X734222Y438198D01*
X734184Y437733D01*
X734222Y437268D01*
X734337Y436855D01*
X734490Y436545D01*
X734720Y436286D01*
X735027Y436183D01*
X735334Y436286D01*
X735564Y436545D01*
X735717Y436855D01*
X735832Y437268D01*
X735870Y437733D01*
X735832Y438198D01*
X735717Y438611D01*
X735564Y438921D01*
X735334Y439180D01*
X735027Y439283D01*
G01X737399Y438766D02*
X737629Y439076D01*
X737897Y439231D01*
X738204Y439283D01*
X738587Y439180D01*
X738855Y438921D01*
X738932Y438611D01*
X738894Y438301D01*
X738740Y438043D01*
X737974Y437526D01*
X737629Y437165D01*
X737399Y436648D01*
X737322Y436183D01*
X738932D01*
G01X741150D02*
X741227Y436855D01*
X741342Y437423D01*
X741495Y437940D01*
X741687Y438508D01*
X741994Y439283D01*
X740460D01*
G01X728060Y432036D02*
Y435136D01*
X729019D01*
X729325Y434981D01*
X729517Y434774D01*
X729594Y434361D01*
X729517Y433948D01*
X729287Y433689D01*
X729019Y433534D01*
X728060D01*
G01X729019D02*
X729594Y432036D01*
G01X731927D02*
Y435136D01*
X731467Y434516D01*
G01Y432036D02*
X732387D01*
G01X735027Y435136D02*
X734720Y435033D01*
X734490Y434774D01*
X734337Y434464D01*
X734222Y434051D01*
X734184Y433586D01*
X734222Y433121D01*
X734337Y432708D01*
X734490Y432398D01*
X734720Y432139D01*
X735027Y432036D01*
X735334Y432139D01*
X735564Y432398D01*
X735717Y432708D01*
X735832Y433121D01*
X735870Y433586D01*
X735832Y434051D01*
X735717Y434464D01*
X735564Y434774D01*
X735334Y435033D01*
X735027Y435136D01*
G01X737399Y434619D02*
X737629Y434929D01*
X737897Y435084D01*
X738204Y435136D01*
X738587Y435033D01*
X738855Y434774D01*
X738932Y434464D01*
X738894Y434154D01*
X738740Y433896D01*
X737974Y433379D01*
X737629Y433018D01*
X737399Y432501D01*
X737322Y432036D01*
X738932D01*
G01X740575Y432398D02*
X740844Y432139D01*
X741150Y432036D01*
X741457Y432139D01*
X741725Y432449D01*
X741917Y432914D01*
X741994Y433379D01*
Y433948D01*
X741917Y434413D01*
X741725Y434826D01*
X741495Y435033D01*
X741227Y435136D01*
X740920Y435033D01*
X740690Y434826D01*
X740537Y434516D01*
X740460Y434103D01*
X740537Y433741D01*
X740729Y433379D01*
X740959Y433173D01*
X741227Y433121D01*
X741534Y433224D01*
X741764Y433483D01*
X741994Y433948D01*
G01X733166Y451103D02*
X729966D01*
G01D02*
Y457303D01*
G01Y450143D02*
X733166D01*
G01X729966Y443943D02*
Y450143D01*
G01X733166Y443943D02*
X729966D01*
G01X716970Y497896D02*
Y453802D01*
G01X728781Y509707D02*
Y441991D01*
G01X729982Y462079D02*
X736182D01*
G01X729982Y458879D02*
Y462079D01*
G01X736182Y458879D02*
X729982D01*
G01X729966Y457303D02*
X733166D01*
G01X730145Y468968D02*
X736345D01*
G01X730145Y465768D02*
Y468968D01*
G01X736345Y465768D02*
X730145D01*
G01X721824Y458666D02*
X722782Y461766D01*
X723740Y458666D01*
G01X723395Y459751D02*
X722169D01*
G01X719971Y470477D02*
Y473577D01*
X720737D01*
X721044Y473422D01*
X721274Y473215D01*
X721466Y472905D01*
X721619Y472544D01*
X721657Y472027D01*
X721619Y471510D01*
X721466Y471149D01*
X721274Y470839D01*
X721044Y470632D01*
X720737Y470477D01*
X719971D01*
G01X723625Y469382D02*
X723395Y469537D01*
X723127Y469640D01*
X722820D01*
X722475Y469485D01*
X722207Y469227D01*
X722015Y468917D01*
X721862Y468400D01*
X721824Y467935D01*
X721900Y467470D01*
X722015Y467160D01*
X722245Y466850D01*
X722514Y466643D01*
X722782Y466540D01*
X723050D01*
X723319Y466643D01*
X723549Y466798D01*
X723740Y467005D01*
G01X721121Y464256D02*
X721274Y464411D01*
X721389Y464670D01*
X721466Y465031D01*
X721389Y465341D01*
X721236Y465548D01*
X720967Y465703D01*
X719932D01*
Y462603D01*
X721197D01*
X721466Y462810D01*
X721619Y463120D01*
X721696Y463481D01*
X721619Y463843D01*
X721389Y464153D01*
X721121Y464256D01*
X719932D01*
G01X723549Y474414D02*
X722015D01*
Y477514D01*
X723549D01*
G01X722935Y476016D02*
X722015D01*
G01X720009Y486225D02*
Y489325D01*
G01X721619D02*
Y486225D01*
G01Y487775D02*
X720009D01*
G01X723012Y483838D02*
X723779D01*
Y482908D01*
X723549Y482598D01*
X723280Y482391D01*
X722897Y482288D01*
X722514Y482391D01*
X722245Y482598D01*
X722015Y482908D01*
X721862Y483270D01*
X721785Y483683D01*
Y484045D01*
X721862Y484355D01*
X722015Y484716D01*
X722245Y485026D01*
X722475Y485233D01*
X722782Y485388D01*
X723050D01*
X723357Y485285D01*
X723587Y485078D01*
G01X720086Y478351D02*
Y481451D01*
X721542D01*
G01X721006Y479953D02*
X720086D01*
G01X730000Y507500D02*
X747500D01*
Y495000D01*
X745000D01*
Y472500D01*
X734000D01*
Y493000D01*
X729500D01*
Y507500D01*
X731000D01*
G01X729702Y501700D02*
X735902D01*
Y498500D01*
X729702D01*
Y501700D01*
G01X729900Y497600D02*
X736100D01*
Y494400D01*
X729900D01*
Y497600D01*
G01X722015Y490782D02*
X722207Y490472D01*
X722437Y490265D01*
X722705Y490162D01*
X723012Y490265D01*
X723242Y490472D01*
X723472Y490782D01*
X723549Y491195D01*
Y493262D01*
G01X719971Y494099D02*
Y497199D01*
G01X721427D02*
X719971Y495287D01*
G01X721657Y494099D02*
X720622Y496166D01*
G01X725229Y517282D02*
X728429D01*
G01X725229Y511082D02*
Y517282D01*
G01X728429Y511082D02*
X725229D01*
G01X728429Y517282D02*
Y511082D01*
G01X720783Y517282D02*
X723983D01*
G01X720783Y511082D02*
Y517282D01*
G01X723983Y511082D02*
X720783D01*
G01X723983Y517282D02*
Y511082D01*
G01X717495Y515034D02*
Y511834D01*
G01X729702Y505654D02*
X735902D01*
Y502454D01*
X729702D01*
Y505654D01*
G01X724650Y528340D02*
X731330D01*
G01X724650Y532520D02*
Y528340D01*
G01X721261Y536630D02*
Y533430D01*
G01X722966Y533501D02*
Y536601D01*
X723925D01*
X724231Y536446D01*
X724423Y536239D01*
X724500Y535826D01*
X724423Y535413D01*
X724193Y535154D01*
X723925Y534999D01*
X722966D01*
G01X723925D02*
X724500Y533501D01*
G01X726833D02*
Y536601D01*
X726373Y535981D01*
G01Y533501D02*
X727293D01*
G01X729933Y536601D02*
X729626Y536498D01*
X729396Y536239D01*
X729243Y535929D01*
X729128Y535516D01*
X729090Y535051D01*
X729128Y534586D01*
X729243Y534173D01*
X729396Y533863D01*
X729626Y533604D01*
X729933Y533501D01*
X730240Y533604D01*
X730470Y533863D01*
X730623Y534173D01*
X730738Y534586D01*
X730776Y535051D01*
X730738Y535516D01*
X730623Y535929D01*
X730470Y536239D01*
X730240Y536498D01*
X729933Y536601D01*
G01X733493Y533501D02*
Y536601D01*
X732075Y534379D01*
X733991D01*
G01X735290Y534121D02*
X735520Y533759D01*
X735826Y533553D01*
X736171Y533501D01*
X736478Y533553D01*
X736785Y533811D01*
X736976Y534121D01*
X737015Y534431D01*
X736938Y534793D01*
X736670Y535051D01*
X736401Y535154D01*
X736056D01*
G01X736401D02*
X736631Y535309D01*
X736823Y535568D01*
X736900Y535878D01*
X736823Y536188D01*
X736631Y536446D01*
X736286Y536601D01*
X735941Y536549D01*
X735596Y536343D01*
G01X723993Y526564D02*
X724100Y526689D01*
X724180Y526898D01*
X724233Y527189D01*
X724180Y527439D01*
X724073Y527606D01*
X723887Y527731D01*
X723167D01*
Y525231D01*
X724047D01*
X724233Y525398D01*
X724340Y525648D01*
X724393Y525939D01*
X724340Y526231D01*
X724180Y526481D01*
X723993Y526564D01*
X723167D01*
G01X722061Y531430D02*
Y518956D01*
G01X722559Y565530D02*
Y560930D01*
G01X717459Y565530D02*
Y560930D01*
G01X720531Y576773D02*
Y566573D01*
G01D02*
X715931D01*
G01D02*
Y576773D01*
G01D02*
X720531D01*
G01X722035Y596151D02*
Y578751D01*
G01X733495Y590962D02*
X723295D01*
G01D02*
Y595562D01*
G01D02*
X733495D01*
G01X728395Y590962D02*
Y595562D01*
G01X721316Y603943D02*
X718216D01*
Y604902D01*
X718371Y605208D01*
X718578Y605400D01*
X718991Y605477D01*
X719404Y605400D01*
X719663Y605170D01*
X719818Y604902D01*
Y603943D01*
G01Y604902D02*
X721316Y605477D01*
G01X720851Y606967D02*
X721109Y607197D01*
X721264Y607465D01*
X721316Y607810D01*
X721213Y608155D01*
X721006Y608423D01*
X720644Y608615D01*
X720231Y608653D01*
X719818Y608577D01*
X719559Y608385D01*
X719353Y608117D01*
X719301Y607848D01*
X719353Y607580D01*
X719559Y607235D01*
X718216Y607350D01*
Y608385D01*
G01X721316Y610910D02*
X721264Y611178D01*
X721109Y611485D01*
X720851Y611677D01*
X720489Y611753D01*
X720128Y611677D01*
X719818Y611447D01*
X719663Y611102D01*
Y610718D01*
X719559Y610488D01*
X719301Y610297D01*
X718939Y610220D01*
X718578Y610335D01*
X718319Y610603D01*
X718216Y610910D01*
X718319Y611217D01*
X718578Y611485D01*
X718939Y611600D01*
X719301Y611523D01*
X719559Y611332D01*
X719663Y611102D01*
Y610718D01*
X719818Y610373D01*
X720128Y610143D01*
X720489Y610067D01*
X720851Y610143D01*
X721109Y610335D01*
X721264Y610642D01*
X721316Y610910D01*
G01Y613933D02*
X720644Y614010D01*
X720076Y614125D01*
X719559Y614278D01*
X718991Y614470D01*
X718216Y614777D01*
Y613243D01*
G01X725316Y603943D02*
X722216D01*
Y604902D01*
X722371Y605208D01*
X722578Y605400D01*
X722991Y605477D01*
X723404Y605400D01*
X723663Y605170D01*
X723818Y604902D01*
Y603943D01*
G01Y604902D02*
X725316Y605477D01*
G01X724851Y606967D02*
X725109Y607197D01*
X725264Y607465D01*
X725316Y607810D01*
X725213Y608155D01*
X725006Y608423D01*
X724644Y608615D01*
X724231Y608653D01*
X723818Y608577D01*
X723559Y608385D01*
X723353Y608117D01*
X723301Y607848D01*
X723353Y607580D01*
X723559Y607235D01*
X722216Y607350D01*
Y608385D01*
G01X725316Y610910D02*
X725264Y611178D01*
X725109Y611485D01*
X724851Y611677D01*
X724489Y611753D01*
X724128Y611677D01*
X723818Y611447D01*
X723663Y611102D01*
Y610718D01*
X723559Y610488D01*
X723301Y610297D01*
X722939Y610220D01*
X722578Y610335D01*
X722319Y610603D01*
X722216Y610910D01*
X722319Y611217D01*
X722578Y611485D01*
X722939Y611600D01*
X723301Y611523D01*
X723559Y611332D01*
X723663Y611102D01*
Y610718D01*
X723818Y610373D01*
X724128Y610143D01*
X724489Y610067D01*
X724851Y610143D01*
X725109Y610335D01*
X725264Y610642D01*
X725316Y610910D01*
G01Y614470D02*
X722216D01*
X724438Y613052D01*
Y614968D01*
G01X719300Y730900D02*
X735800D01*
Y669600D01*
X782400D01*
Y610800D01*
X763600D01*
Y636200D01*
X757600D01*
Y666100D01*
X729200D01*
Y679100D01*
X719300D01*
Y730900D01*
G01X724200Y684300D02*
X730400D01*
G01X724200Y681100D02*
Y684300D01*
G01X730400Y681100D02*
X724200D01*
G01X730400Y684300D02*
Y681100D01*
G01X730500Y689200D02*
X724300D01*
Y692400D01*
X730500D01*
Y689200D01*
G01X730400Y685100D02*
X724200D01*
Y688300D01*
X730400D01*
Y685100D01*
G01X730500Y697200D02*
X724300D01*
Y700400D01*
X730500D01*
Y697200D01*
G01Y693200D02*
X724300D01*
Y696400D01*
X730500D01*
Y693200D01*
G01Y701200D02*
X724300D01*
Y704400D01*
X730500D01*
Y701200D01*
G01X722800Y709400D02*
X729000D01*
Y706200D01*
X722800D01*
Y709400D01*
G01Y721400D02*
X729000D01*
Y718200D01*
X722800D01*
Y721400D01*
G01Y725400D02*
X729000D01*
Y722200D01*
X722800D01*
Y725400D01*
G01Y717400D02*
X729000D01*
Y714200D01*
X722800D01*
Y717400D01*
G01Y713400D02*
X729000D01*
Y710200D01*
X722800D01*
Y713400D01*
G01X729000Y726200D02*
X722800D01*
G01X729000Y729400D02*
Y726200D01*
G01X722800D02*
Y729400D01*
G01D02*
X729000D01*
G01X731900Y746583D02*
X728800D01*
Y747542D01*
X728955Y747848D01*
X729162Y748040D01*
X729575Y748117D01*
X729988Y748040D01*
X730247Y747810D01*
X730402Y747542D01*
Y746583D01*
G01Y747542D02*
X731900Y748117D01*
G01Y750450D02*
X728800D01*
X729420Y749990D01*
G01X731900D02*
Y750910D01*
G01X728800Y753550D02*
X728903Y753243D01*
X729162Y753013D01*
X729472Y752860D01*
X729885Y752745D01*
X730350Y752707D01*
X730815Y752745D01*
X731228Y752860D01*
X731538Y753013D01*
X731797Y753243D01*
X731900Y753550D01*
X731797Y753857D01*
X731538Y754087D01*
X731228Y754240D01*
X730815Y754355D01*
X730350Y754393D01*
X729885Y754355D01*
X729472Y754240D01*
X729162Y754087D01*
X728903Y753857D01*
X728800Y753550D01*
G01X731900Y756573D02*
X731228Y756650D01*
X730660Y756765D01*
X730143Y756918D01*
X729575Y757110D01*
X728800Y757417D01*
Y755883D01*
G01X729317Y759022D02*
X729007Y759252D01*
X728852Y759520D01*
X728800Y759827D01*
X728903Y760210D01*
X729162Y760478D01*
X729472Y760555D01*
X729782Y760517D01*
X730040Y760363D01*
X730557Y759597D01*
X730918Y759252D01*
X731435Y759022D01*
X731900Y758945D01*
Y760555D01*
G01X727800Y738700D02*
Y744900D01*
G01X731000Y738700D02*
X727800D01*
G01X731000Y744900D02*
Y738700D01*
G01X727800Y744900D02*
X731000D01*
G01X723500Y746683D02*
X720400D01*
Y747642D01*
X720555Y747948D01*
X720762Y748140D01*
X721175Y748217D01*
X721588Y748140D01*
X721847Y747910D01*
X722002Y747642D01*
Y746683D01*
G01Y747642D02*
X723500Y748217D01*
G01Y750550D02*
X720400D01*
X721020Y750090D01*
G01X723500D02*
Y751010D01*
G01X720917Y752922D02*
X720607Y753152D01*
X720452Y753420D01*
X720400Y753727D01*
X720503Y754110D01*
X720762Y754378D01*
X721072Y754455D01*
X721382Y754417D01*
X721640Y754263D01*
X722157Y753497D01*
X722518Y753152D01*
X723035Y752922D01*
X723500Y752845D01*
Y754455D01*
G01X723138Y756098D02*
X723397Y756367D01*
X723500Y756673D01*
X723397Y756980D01*
X723087Y757248D01*
X722622Y757440D01*
X722157Y757517D01*
X721588D01*
X721123Y757440D01*
X720710Y757248D01*
X720503Y757018D01*
X720400Y756750D01*
X720503Y756443D01*
X720710Y756213D01*
X721020Y756060D01*
X721433Y755983D01*
X721795Y756060D01*
X722157Y756252D01*
X722363Y756482D01*
X722415Y756750D01*
X722312Y757057D01*
X722053Y757287D01*
X721588Y757517D01*
G01X720917Y759122D02*
X720607Y759352D01*
X720452Y759620D01*
X720400Y759927D01*
X720503Y760310D01*
X720762Y760578D01*
X721072Y760655D01*
X721382Y760617D01*
X721640Y760463D01*
X722157Y759697D01*
X722518Y759352D01*
X723035Y759122D01*
X723500Y759045D01*
Y760655D01*
G01X723000Y744900D02*
Y738700D01*
X719800D01*
Y744900D01*
X723000D01*
G01X719200Y746583D02*
X716100D01*
Y747542D01*
X716255Y747848D01*
X716462Y748040D01*
X716875Y748117D01*
X717288Y748040D01*
X717547Y747810D01*
X717702Y747542D01*
Y746583D01*
G01Y747542D02*
X719200Y748117D01*
G01Y750450D02*
X716100D01*
X716720Y749990D01*
G01X719200D02*
Y750910D01*
G01X716617Y752822D02*
X716307Y753052D01*
X716152Y753320D01*
X716100Y753627D01*
X716203Y754010D01*
X716462Y754278D01*
X716772Y754355D01*
X717082Y754317D01*
X717340Y754163D01*
X717857Y753397D01*
X718218Y753052D01*
X718735Y752822D01*
X719200Y752745D01*
Y754355D01*
G01X718838Y755998D02*
X719097Y756267D01*
X719200Y756573D01*
X719097Y756880D01*
X718787Y757148D01*
X718322Y757340D01*
X717857Y757417D01*
X717288D01*
X716823Y757340D01*
X716410Y757148D01*
X716203Y756918D01*
X716100Y756650D01*
X716203Y756343D01*
X716410Y756113D01*
X716720Y755960D01*
X717133Y755883D01*
X717495Y755960D01*
X717857Y756152D01*
X718063Y756382D01*
X718115Y756650D01*
X718012Y756957D01*
X717753Y757187D01*
X717288Y757417D01*
G01X718580Y758907D02*
X718942Y759137D01*
X719148Y759443D01*
X719200Y759788D01*
X719148Y760095D01*
X718890Y760402D01*
X718580Y760593D01*
X718270Y760632D01*
X717908Y760555D01*
X717650Y760287D01*
X717547Y760018D01*
Y759673D01*
G01Y760018D02*
X717392Y760248D01*
X717133Y760440D01*
X716823Y760517D01*
X716513Y760440D01*
X716255Y760248D01*
X716100Y759903D01*
X716152Y759558D01*
X716358Y759213D01*
G01X719000Y744900D02*
Y738700D01*
X715800D01*
Y744900D01*
X719000D01*
G01X727900Y746583D02*
X724800D01*
Y747542D01*
X724955Y747848D01*
X725162Y748040D01*
X725575Y748117D01*
X725988Y748040D01*
X726247Y747810D01*
X726402Y747542D01*
Y746583D01*
G01Y747542D02*
X727900Y748117D01*
G01Y750450D02*
X724800D01*
X725420Y749990D01*
G01X727900D02*
Y750910D01*
G01X725317Y752822D02*
X725007Y753052D01*
X724852Y753320D01*
X724800Y753627D01*
X724903Y754010D01*
X725162Y754278D01*
X725472Y754355D01*
X725782Y754317D01*
X726040Y754163D01*
X726557Y753397D01*
X726918Y753052D01*
X727435Y752822D01*
X727900Y752745D01*
Y754355D01*
G01X727538Y755998D02*
X727797Y756267D01*
X727900Y756573D01*
X727797Y756880D01*
X727487Y757148D01*
X727022Y757340D01*
X726557Y757417D01*
X725988D01*
X725523Y757340D01*
X725110Y757148D01*
X724903Y756918D01*
X724800Y756650D01*
X724903Y756343D01*
X725110Y756113D01*
X725420Y755960D01*
X725833Y755883D01*
X726195Y755960D01*
X726557Y756152D01*
X726763Y756382D01*
X726815Y756650D01*
X726712Y756957D01*
X726453Y757187D01*
X725988Y757417D01*
G01X726608Y759022D02*
X726247Y759290D01*
X726040Y759520D01*
X725937Y759827D01*
X726040Y760095D01*
X726247Y760287D01*
X726557Y760440D01*
X726918Y760478D01*
X727228Y760440D01*
X727538Y760287D01*
X727797Y760057D01*
X727900Y759788D01*
X727797Y759482D01*
X727487Y759213D01*
X727022Y759060D01*
X726505Y759022D01*
X725833Y759098D01*
X725472Y759213D01*
X725110Y759405D01*
X724852Y759673D01*
X724800Y759942D01*
X724903Y760210D01*
X725162Y760402D01*
G01X727000Y744900D02*
Y738700D01*
X723800D01*
Y744900D01*
X727000D01*
G01X741125Y8907D02*
X734442D01*
Y8928D01*
X736635Y11121D01*
X736656Y11100D01*
Y6272D01*
X734421Y8507D01*
Y8844D01*
G01X738571Y20230D02*
Y23330D01*
X738111Y22710D01*
G01Y20230D02*
X739031D01*
G01X734181Y24361D02*
X755755D01*
G01X734181Y34361D02*
Y24361D01*
G01D02*
X734377D01*
G01X741722Y37119D02*
X741914Y36809D01*
X742144Y36602D01*
X742412Y36499D01*
X742719Y36602D01*
X742949Y36809D01*
X743179Y37119D01*
X743256Y37532D01*
Y39599D01*
G01X744746Y37119D02*
X744976Y36757D01*
X745282Y36551D01*
X745627Y36499D01*
X745934Y36551D01*
X746241Y36809D01*
X746432Y37119D01*
X746471Y37429D01*
X746394Y37791D01*
X746126Y38049D01*
X745857Y38152D01*
X745512D01*
G01X745857D02*
X746087Y38307D01*
X746279Y38566D01*
X746356Y38876D01*
X746279Y39186D01*
X746087Y39444D01*
X745742Y39599D01*
X745397Y39547D01*
X745052Y39341D01*
G01X747961Y39082D02*
X748191Y39392D01*
X748459Y39547D01*
X748766Y39599D01*
X749149Y39496D01*
X749417Y39237D01*
X749494Y38927D01*
X749456Y38617D01*
X749302Y38359D01*
X748536Y37842D01*
X748191Y37481D01*
X747961Y36964D01*
X747884Y36499D01*
X749494D01*
G01X755755Y34361D02*
X734181D01*
G01X743111Y107021D02*
Y124675D01*
G01X746250Y101776D02*
Y108576D01*
G01X761250Y101776D02*
X746250D01*
G01X748403Y110291D02*
X745903D01*
X746403Y109971D01*
G01X748403D02*
Y110611D01*
G01X744579Y111564D02*
Y128103D01*
G01X752847Y111564D02*
X744579D01*
G01X746250Y108576D02*
X761250D01*
G01X740021Y134862D02*
Y132982D01*
G01X741386Y134000D02*
X738656D01*
G01X743111Y124675D02*
X739111Y128675D01*
G01X744579Y128103D02*
X752847D01*
G01X740275Y139455D02*
X779875D01*
G01Y199455D02*
X740275D01*
G01X741963Y213621D02*
X742155Y213311D01*
X742385Y213104D01*
X742653Y213001D01*
X742960Y213104D01*
X743190Y213311D01*
X743420Y213621D01*
X743497Y214034D01*
Y216101D01*
G01X745830Y213001D02*
Y216101D01*
X745370Y215481D01*
G01Y213001D02*
X746290D01*
G01X748087Y213466D02*
X748317Y213208D01*
X748585Y213053D01*
X748930Y213001D01*
X749275Y213104D01*
X749543Y213311D01*
X749735Y213673D01*
X749773Y214086D01*
X749697Y214499D01*
X749505Y214758D01*
X749237Y214964D01*
X748968Y215016D01*
X748700Y214964D01*
X748355Y214758D01*
X748470Y216101D01*
X749505D01*
G01X740275Y218261D02*
X779875D01*
G01X747196Y286889D02*
Y280206D01*
X747175D01*
X744982Y282399D01*
X745003Y282420D01*
X749831D01*
X747596Y280185D01*
X747259D01*
G01X779875Y278261D02*
X740275D01*
G01X739061Y344033D02*
Y347133D01*
X739981D01*
X740288Y346978D01*
X740518Y346616D01*
X740595Y346203D01*
X740518Y345790D01*
X740326Y345480D01*
X739981Y345325D01*
X739061D01*
G01X743771Y346875D02*
X743541Y347030D01*
X743273Y347133D01*
X742966D01*
X742621Y346978D01*
X742353Y346720D01*
X742161Y346410D01*
X742008Y345893D01*
X741970Y345428D01*
X742046Y344963D01*
X742161Y344653D01*
X742391Y344343D01*
X742660Y344136D01*
X742928Y344033D01*
X743196D01*
X743465Y344136D01*
X743695Y344291D01*
X743886Y344498D01*
G01X745185Y344653D02*
X745415Y344291D01*
X745721Y344085D01*
X746066Y344033D01*
X746373Y344085D01*
X746680Y344343D01*
X746871Y344653D01*
X746910Y344963D01*
X746833Y345325D01*
X746565Y345583D01*
X746296Y345686D01*
X745951D01*
G01X746296D02*
X746526Y345841D01*
X746718Y346100D01*
X746795Y346410D01*
X746718Y346720D01*
X746526Y346978D01*
X746181Y347133D01*
X745836Y347081D01*
X745491Y346875D01*
G01X749128Y347133D02*
X748821Y347030D01*
X748591Y346771D01*
X748438Y346461D01*
X748323Y346048D01*
X748285Y345583D01*
X748323Y345118D01*
X748438Y344705D01*
X748591Y344395D01*
X748821Y344136D01*
X749128Y344033D01*
X749435Y344136D01*
X749665Y344395D01*
X749818Y344705D01*
X749933Y345118D01*
X749971Y345583D01*
X749933Y346048D01*
X749818Y346461D01*
X749665Y346771D01*
X749435Y347030D01*
X749128Y347133D01*
G01X737860Y350077D02*
X734760D01*
Y351036D01*
X734915Y351342D01*
X735122Y351534D01*
X735535Y351611D01*
X735948Y351534D01*
X736207Y351304D01*
X736362Y351036D01*
Y350077D01*
G01Y351036D02*
X737860Y351611D01*
G01Y353944D02*
X734760D01*
X735380Y353484D01*
G01X737860D02*
Y354404D01*
G01Y357044D02*
X734760D01*
X735380Y356584D01*
G01X737860D02*
Y357504D01*
G01X735277Y359416D02*
X734967Y359646D01*
X734812Y359914D01*
X734760Y360221D01*
X734863Y360604D01*
X735122Y360872D01*
X735432Y360949D01*
X735742Y360911D01*
X736000Y360757D01*
X736517Y359991D01*
X736878Y359646D01*
X737395Y359416D01*
X737860Y359339D01*
Y360949D01*
G01Y363167D02*
X737188Y363244D01*
X736620Y363359D01*
X736103Y363512D01*
X735535Y363704D01*
X734760Y364011D01*
Y362477D01*
G01X739051Y348140D02*
Y351240D01*
X740010D01*
X740316Y351085D01*
X740508Y350878D01*
X740585Y350465D01*
X740508Y350052D01*
X740278Y349793D01*
X740010Y349638D01*
X739051D01*
G01X740010D02*
X740585Y348140D01*
G01X742918D02*
Y351240D01*
X742458Y350620D01*
G01Y348140D02*
X743378D01*
G01X745290Y350723D02*
X745520Y351033D01*
X745788Y351188D01*
X746095Y351240D01*
X746478Y351137D01*
X746746Y350878D01*
X746823Y350568D01*
X746785Y350258D01*
X746631Y350000D01*
X745865Y349483D01*
X745520Y349122D01*
X745290Y348605D01*
X745213Y348140D01*
X746823D01*
G01X748275Y348760D02*
X748505Y348398D01*
X748811Y348192D01*
X749156Y348140D01*
X749463Y348192D01*
X749770Y348450D01*
X749961Y348760D01*
X750000Y349070D01*
X749923Y349432D01*
X749655Y349690D01*
X749386Y349793D01*
X749041D01*
G01X749386D02*
X749616Y349948D01*
X749808Y350207D01*
X749885Y350517D01*
X749808Y350827D01*
X749616Y351085D01*
X749271Y351240D01*
X748926Y351188D01*
X748581Y350982D01*
G01X751490Y350723D02*
X751720Y351033D01*
X751988Y351188D01*
X752295Y351240D01*
X752678Y351137D01*
X752946Y350878D01*
X753023Y350568D01*
X752985Y350258D01*
X752831Y350000D01*
X752065Y349483D01*
X751720Y349122D01*
X751490Y348605D01*
X751413Y348140D01*
X753023D01*
G01X746934Y354340D02*
X746882Y354033D01*
X746676Y353765D01*
X746366Y353535D01*
X746004Y353382D01*
X745591Y353305D01*
X745177D01*
X744764Y353382D01*
X744402Y353535D01*
X744092Y353765D01*
X743886Y354033D01*
X743834Y354340D01*
X743886Y354647D01*
X744092Y354915D01*
X744402Y355145D01*
X744764Y355298D01*
X745177Y355375D01*
X745591D01*
X746004Y355298D01*
X746366Y355145D01*
X746676Y354915D01*
X746882Y354647D01*
X746934Y354340D01*
G01X746107Y354647D02*
X746934Y355107D01*
G01Y357900D02*
X743834D01*
X746056Y356482D01*
Y358398D01*
G01X746934Y361000D02*
X743834D01*
X746056Y359582D01*
Y361498D01*
G01X745650Y386060D02*
X783840D01*
G01X735021Y386846D02*
Y384624D01*
X735174Y384159D01*
X735481Y383849D01*
X735864Y383746D01*
X736247Y383849D01*
X736554Y384159D01*
X736707Y384624D01*
Y386846D01*
G01X738887Y383746D02*
X738964Y384418D01*
X739079Y384986D01*
X739232Y385503D01*
X739424Y386071D01*
X739731Y386846D01*
X738197D01*
G01X742064D02*
X741757Y386743D01*
X741527Y386484D01*
X741374Y386174D01*
X741259Y385761D01*
X741221Y385296D01*
X741259Y384831D01*
X741374Y384418D01*
X741527Y384108D01*
X741757Y383849D01*
X742064Y383746D01*
X742371Y383849D01*
X742601Y384108D01*
X742754Y384418D01*
X742869Y384831D01*
X742907Y385296D01*
X742869Y385761D01*
X742754Y386174D01*
X742601Y386484D01*
X742371Y386743D01*
X742064Y386846D01*
G01X735131Y392197D02*
Y389975D01*
X735284Y389510D01*
X735591Y389200D01*
X735974Y389097D01*
X736357Y389200D01*
X736664Y389510D01*
X736817Y389975D01*
Y392197D01*
G01X738346Y390389D02*
X738614Y390750D01*
X738844Y390957D01*
X739151Y391060D01*
X739419Y390957D01*
X739611Y390750D01*
X739764Y390440D01*
X739802Y390079D01*
X739764Y389769D01*
X739611Y389459D01*
X739381Y389200D01*
X739112Y389097D01*
X738806Y389200D01*
X738537Y389510D01*
X738384Y389975D01*
X738346Y390492D01*
X738422Y391164D01*
X738537Y391525D01*
X738729Y391887D01*
X738997Y392145D01*
X739266Y392197D01*
X739534Y392094D01*
X739726Y391835D01*
G01X741522Y389459D02*
X741791Y389200D01*
X742097Y389097D01*
X742404Y389200D01*
X742672Y389510D01*
X742864Y389975D01*
X742941Y390440D01*
Y391009D01*
X742864Y391474D01*
X742672Y391887D01*
X742442Y392094D01*
X742174Y392197D01*
X741867Y392094D01*
X741637Y391887D01*
X741484Y391577D01*
X741407Y391164D01*
X741484Y390802D01*
X741676Y390440D01*
X741906Y390234D01*
X742174Y390182D01*
X742481Y390285D01*
X742711Y390544D01*
X742941Y391009D01*
G01X734991Y397062D02*
Y394840D01*
X735144Y394375D01*
X735451Y394065D01*
X735834Y393962D01*
X736217Y394065D01*
X736524Y394375D01*
X736677Y394840D01*
Y397062D01*
G01X738206Y395254D02*
X738474Y395615D01*
X738704Y395822D01*
X739011Y395925D01*
X739279Y395822D01*
X739471Y395615D01*
X739624Y395305D01*
X739662Y394944D01*
X739624Y394634D01*
X739471Y394324D01*
X739241Y394065D01*
X738972Y393962D01*
X738666Y394065D01*
X738397Y394375D01*
X738244Y394840D01*
X738206Y395357D01*
X738282Y396029D01*
X738397Y396390D01*
X738589Y396752D01*
X738857Y397010D01*
X739126Y397062D01*
X739394Y396959D01*
X739586Y396700D01*
G01X741957Y393962D02*
X742034Y394634D01*
X742149Y395202D01*
X742302Y395719D01*
X742494Y396287D01*
X742801Y397062D01*
X741267D01*
G01X738326Y409384D02*
X738171Y409154D01*
X738068Y408886D01*
Y408579D01*
X738223Y408234D01*
X738481Y407966D01*
X738791Y407774D01*
X739308Y407621D01*
X739773Y407583D01*
X740238Y407659D01*
X740548Y407774D01*
X740858Y408004D01*
X741065Y408273D01*
X741168Y408541D01*
Y408809D01*
X741065Y409078D01*
X740910Y409308D01*
X740703Y409499D01*
G01X741168Y411564D02*
X740496Y411641D01*
X739928Y411756D01*
X739411Y411909D01*
X738843Y412101D01*
X738068Y412408D01*
Y410874D01*
G01X741168Y414664D02*
X740496Y414741D01*
X739928Y414856D01*
X739411Y415009D01*
X738843Y415201D01*
X738068Y415508D01*
Y413974D01*
G01X739876Y417113D02*
X739515Y417381D01*
X739308Y417611D01*
X739205Y417918D01*
X739308Y418186D01*
X739515Y418378D01*
X739825Y418531D01*
X740186Y418569D01*
X740496Y418531D01*
X740806Y418378D01*
X741065Y418148D01*
X741168Y417879D01*
X741065Y417573D01*
X740755Y417304D01*
X740290Y417151D01*
X739773Y417113D01*
X739101Y417189D01*
X738740Y417304D01*
X738378Y417496D01*
X738120Y417764D01*
X738068Y418033D01*
X738171Y418301D01*
X738430Y418493D01*
G01X739149Y443220D02*
X739309Y443470D01*
X739496Y443595D01*
X739709Y443637D01*
X739976Y443554D01*
X740163Y443345D01*
X740216Y443095D01*
X740189Y442845D01*
X740083Y442637D01*
X739549Y442220D01*
X739309Y441929D01*
X739149Y441512D01*
X739096Y441137D01*
X740216D01*
G01X746411Y442166D02*
X746703Y442326D01*
X746869Y442540D01*
X746911Y442780D01*
X746869Y442993D01*
X746661Y443206D01*
X746411Y443340D01*
X746161Y443366D01*
X745869Y443313D01*
X745661Y443126D01*
X745578Y442940D01*
Y442700D01*
G01Y442940D02*
X745453Y443100D01*
X745244Y443233D01*
X744994Y443286D01*
X744744Y443233D01*
X744536Y443100D01*
X744411Y442860D01*
X744453Y442620D01*
X744619Y442380D01*
G01X749123Y444332D02*
X734123D01*
G01D02*
Y457332D01*
G01X733166Y457303D02*
Y451103D01*
G01Y450143D02*
Y443943D01*
G01X739475Y458813D02*
Y461313D01*
X739155Y460813D01*
G01Y458813D02*
X739795D01*
G01X742507Y461100D02*
Y458878D01*
X742660Y458413D01*
X742967Y458103D01*
X743350Y458000D01*
X743733Y458103D01*
X744040Y458413D01*
X744193Y458878D01*
Y461100D01*
G01X746450Y458000D02*
Y461100D01*
X745990Y460480D01*
G01Y458000D02*
X746910D01*
G01X749550Y461100D02*
X749243Y460997D01*
X749013Y460738D01*
X748860Y460428D01*
X748745Y460015D01*
X748707Y459550D01*
X748745Y459085D01*
X748860Y458672D01*
X749013Y458362D01*
X749243Y458103D01*
X749550Y458000D01*
X749857Y458103D01*
X750087Y458362D01*
X750240Y458672D01*
X750355Y459085D01*
X750393Y459550D01*
X750355Y460015D01*
X750240Y460428D01*
X750087Y460738D01*
X749857Y460997D01*
X749550Y461100D01*
G01X752650Y458000D02*
Y461100D01*
X752190Y460480D01*
G01Y458000D02*
X753110D01*
G01X734123Y457332D02*
X749123D01*
G01X738383Y463000D02*
Y466100D01*
X739342D01*
X739648Y465945D01*
X739840Y465738D01*
X739917Y465325D01*
X739840Y464912D01*
X739610Y464653D01*
X739342Y464498D01*
X738383D01*
G01X739342D02*
X739917Y463000D01*
G01X742250D02*
Y466100D01*
X741790Y465480D01*
G01Y463000D02*
X742710D01*
G01X744622Y465583D02*
X744852Y465893D01*
X745120Y466048D01*
X745427Y466100D01*
X745810Y465997D01*
X746078Y465738D01*
X746155Y465428D01*
X746117Y465118D01*
X745963Y464860D01*
X745197Y464343D01*
X744852Y463982D01*
X744622Y463465D01*
X744545Y463000D01*
X746155D01*
G01X748910D02*
Y466100D01*
X747492Y463878D01*
X749408D01*
G01X750822Y464292D02*
X751090Y464653D01*
X751320Y464860D01*
X751627Y464963D01*
X751895Y464860D01*
X752087Y464653D01*
X752240Y464343D01*
X752278Y463982D01*
X752240Y463672D01*
X752087Y463362D01*
X751857Y463103D01*
X751588Y463000D01*
X751282Y463103D01*
X751013Y463413D01*
X750860Y463878D01*
X750822Y464395D01*
X750898Y465067D01*
X751013Y465428D01*
X751205Y465790D01*
X751473Y466048D01*
X751742Y466100D01*
X752010Y465997D01*
X752202Y465738D01*
G01X736182Y462079D02*
Y458879D01*
G01X738383Y468000D02*
Y471100D01*
X739342D01*
X739648Y470945D01*
X739840Y470738D01*
X739917Y470325D01*
X739840Y469912D01*
X739610Y469653D01*
X739342Y469498D01*
X738383D01*
G01X739342D02*
X739917Y468000D01*
G01X742250D02*
Y471100D01*
X741790Y470480D01*
G01Y468000D02*
X742710D01*
G01X744622Y470583D02*
X744852Y470893D01*
X745120Y471048D01*
X745427Y471100D01*
X745810Y470997D01*
X746078Y470738D01*
X746155Y470428D01*
X746117Y470118D01*
X745963Y469860D01*
X745197Y469343D01*
X744852Y468982D01*
X744622Y468465D01*
X744545Y468000D01*
X746155D01*
G01X748910D02*
Y471100D01*
X747492Y468878D01*
X749408D01*
G01X751473Y468000D02*
X751550Y468672D01*
X751665Y469240D01*
X751818Y469757D01*
X752010Y470325D01*
X752317Y471100D01*
X750783D01*
G01X736345Y468968D02*
Y465768D01*
G01X786000Y473500D02*
Y462000D01*
X753500D01*
Y472000D01*
X746000D01*
Y495000D01*
X771500D01*
Y475000D01*
X786000D01*
Y473500D01*
G01X735310Y486039D02*
Y489239D01*
G01X741510Y486039D02*
X735310D01*
G01X741510Y489239D02*
Y486039D01*
G01X735429Y482041D02*
Y485241D01*
G01X741629Y482041D02*
X735429D01*
G01X741629Y485241D02*
Y482041D01*
G01X735429Y485241D02*
X741629D01*
G01X735451Y477375D02*
Y480575D01*
G01X741651Y477375D02*
X735451D01*
G01X741651Y480575D02*
Y477375D01*
G01X735451Y480575D02*
X741651D01*
G01X735400Y476600D02*
X741600D01*
Y473400D01*
X735400D01*
Y476600D01*
G01X735310Y489239D02*
X741510D01*
G01X746600Y495200D02*
X740400D01*
Y498400D01*
X746600D01*
Y495200D01*
G01X740400Y502600D02*
X746600D01*
Y499400D01*
X740400D01*
Y502600D01*
G01X737900Y494100D02*
X744100D01*
Y490900D01*
X737900D01*
Y494100D01*
G01X745700Y510627D02*
Y513727D01*
X746659D01*
X746965Y513572D01*
X747157Y513365D01*
X747234Y512952D01*
X747157Y512539D01*
X746927Y512280D01*
X746659Y512125D01*
X745700D01*
G01X746659D02*
X747234Y510627D01*
G01X749567D02*
Y513727D01*
X749107Y513107D01*
G01Y510627D02*
X750027D01*
G01X752667Y513727D02*
X752360Y513624D01*
X752130Y513365D01*
X751977Y513055D01*
X751862Y512642D01*
X751824Y512177D01*
X751862Y511712D01*
X751977Y511299D01*
X752130Y510989D01*
X752360Y510730D01*
X752667Y510627D01*
X752974Y510730D01*
X753204Y510989D01*
X753357Y511299D01*
X753472Y511712D01*
X753510Y512177D01*
X753472Y512642D01*
X753357Y513055D01*
X753204Y513365D01*
X752974Y513624D01*
X752667Y513727D01*
G01X756227Y510627D02*
Y513727D01*
X754809Y511505D01*
X756725D01*
G01X758867Y510627D02*
Y513727D01*
X758407Y513107D01*
G01Y510627D02*
X759327D01*
G01X739918Y509934D02*
X736818D01*
Y510893D01*
X736973Y511199D01*
X737180Y511391D01*
X737593Y511468D01*
X738006Y511391D01*
X738265Y511161D01*
X738420Y510893D01*
Y509934D01*
G01Y510893D02*
X739918Y511468D01*
G01Y513801D02*
X736818D01*
X737438Y513341D01*
G01X739918D02*
Y514261D01*
G01X736818Y516901D02*
X736921Y516594D01*
X737180Y516364D01*
X737490Y516211D01*
X737903Y516096D01*
X738368Y516058D01*
X738833Y516096D01*
X739246Y516211D01*
X739556Y516364D01*
X739815Y516594D01*
X739918Y516901D01*
X739815Y517208D01*
X739556Y517438D01*
X739246Y517591D01*
X738833Y517706D01*
X738368Y517744D01*
X737903Y517706D01*
X737490Y517591D01*
X737180Y517438D01*
X736921Y517208D01*
X736818Y516901D01*
G01X739298Y519158D02*
X739660Y519388D01*
X739866Y519694D01*
X739918Y520039D01*
X739866Y520346D01*
X739608Y520653D01*
X739298Y520844D01*
X738988Y520883D01*
X738626Y520806D01*
X738368Y520538D01*
X738265Y520269D01*
Y519924D01*
G01Y520269D02*
X738110Y520499D01*
X737851Y520691D01*
X737541Y520768D01*
X737231Y520691D01*
X736973Y520499D01*
X736818Y520154D01*
X736870Y519809D01*
X737076Y519464D01*
G01X739918Y523024D02*
X739246Y523101D01*
X738678Y523216D01*
X738161Y523369D01*
X737593Y523561D01*
X736818Y523868D01*
Y522334D01*
G01X744162Y513732D02*
X741062D01*
Y514691D01*
X741217Y514997D01*
X741424Y515189D01*
X741837Y515266D01*
X742250Y515189D01*
X742509Y514959D01*
X742664Y514691D01*
Y513732D01*
G01Y514691D02*
X744162Y515266D01*
G01Y517599D02*
X741062D01*
X741682Y517139D01*
G01X744162D02*
Y518059D01*
G01Y520699D02*
X741062D01*
X741682Y520239D01*
G01X744162D02*
Y521159D01*
G01X743542Y522956D02*
X743904Y523186D01*
X744110Y523492D01*
X744162Y523837D01*
X744110Y524144D01*
X743852Y524451D01*
X743542Y524642D01*
X743232Y524681D01*
X742870Y524604D01*
X742612Y524336D01*
X742509Y524067D01*
Y523722D01*
G01Y524067D02*
X742354Y524297D01*
X742095Y524489D01*
X741785Y524566D01*
X741475Y524489D01*
X741217Y524297D01*
X741062Y523952D01*
X741114Y523607D01*
X741320Y523262D01*
G01X744162Y526899D02*
X741062D01*
X741682Y526439D01*
G01X744162D02*
Y527359D01*
G01X735418Y509934D02*
X732318D01*
Y510893D01*
X732473Y511199D01*
X732680Y511391D01*
X733093Y511468D01*
X733506Y511391D01*
X733765Y511161D01*
X733920Y510893D01*
Y509934D01*
G01Y510893D02*
X735418Y511468D01*
G01Y513801D02*
X732318D01*
X732938Y513341D01*
G01X735418D02*
Y514261D01*
G01X732318Y516901D02*
X732421Y516594D01*
X732680Y516364D01*
X732990Y516211D01*
X733403Y516096D01*
X733868Y516058D01*
X734333Y516096D01*
X734746Y516211D01*
X735056Y516364D01*
X735315Y516594D01*
X735418Y516901D01*
X735315Y517208D01*
X735056Y517438D01*
X734746Y517591D01*
X734333Y517706D01*
X733868Y517744D01*
X733403Y517706D01*
X732990Y517591D01*
X732680Y517438D01*
X732421Y517208D01*
X732318Y516901D01*
G01X734798Y519158D02*
X735160Y519388D01*
X735366Y519694D01*
X735418Y520039D01*
X735366Y520346D01*
X735108Y520653D01*
X734798Y520844D01*
X734488Y520883D01*
X734126Y520806D01*
X733868Y520538D01*
X733765Y520269D01*
Y519924D01*
G01Y520269D02*
X733610Y520499D01*
X733351Y520691D01*
X733041Y520768D01*
X732731Y520691D01*
X732473Y520499D01*
X732318Y520154D01*
X732370Y519809D01*
X732576Y519464D01*
G01X734126Y522373D02*
X733765Y522641D01*
X733558Y522871D01*
X733455Y523178D01*
X733558Y523446D01*
X733765Y523638D01*
X734075Y523791D01*
X734436Y523829D01*
X734746Y523791D01*
X735056Y523638D01*
X735315Y523408D01*
X735418Y523139D01*
X735315Y522833D01*
X735005Y522564D01*
X734540Y522411D01*
X734023Y522373D01*
X733351Y522449D01*
X732990Y522564D01*
X732628Y522756D01*
X732370Y523024D01*
X732318Y523293D01*
X732421Y523561D01*
X732680Y523753D01*
G01X739201Y533404D02*
Y536504D01*
X740160D01*
X740466Y536349D01*
X740658Y536142D01*
X740735Y535729D01*
X740658Y535316D01*
X740428Y535057D01*
X740160Y534902D01*
X739201D01*
G01X740160D02*
X740735Y533404D01*
G01X743068D02*
Y536504D01*
X742608Y535884D01*
G01Y533404D02*
X743528D01*
G01X746168Y536504D02*
X745861Y536401D01*
X745631Y536142D01*
X745478Y535832D01*
X745363Y535419D01*
X745325Y534954D01*
X745363Y534489D01*
X745478Y534076D01*
X745631Y533766D01*
X745861Y533507D01*
X746168Y533404D01*
X746475Y533507D01*
X746705Y533766D01*
X746858Y534076D01*
X746973Y534489D01*
X747011Y534954D01*
X746973Y535419D01*
X746858Y535832D01*
X746705Y536142D01*
X746475Y536401D01*
X746168Y536504D01*
G01X749728Y533404D02*
Y536504D01*
X748310Y534282D01*
X750226D01*
G01X752291Y533404D02*
X752368Y534076D01*
X752483Y534644D01*
X752636Y535161D01*
X752828Y535729D01*
X753135Y536504D01*
X751601D01*
G01X734191Y528556D02*
X733884Y528608D01*
X733616Y528814D01*
X733386Y529124D01*
X733233Y529486D01*
X733156Y529899D01*
Y530313D01*
X733233Y530726D01*
X733386Y531088D01*
X733616Y531398D01*
X733884Y531604D01*
X734191Y531656D01*
X734498Y531604D01*
X734766Y531398D01*
X734996Y531088D01*
X735149Y530726D01*
X735226Y530313D01*
Y529899D01*
X735149Y529486D01*
X734996Y529124D01*
X734766Y528814D01*
X734498Y528608D01*
X734191Y528556D01*
G01X734498Y529383D02*
X734958Y528556D01*
G01X737751D02*
Y531656D01*
X736333Y529434D01*
X738249D01*
G01X740391Y528556D02*
Y531656D01*
X739931Y531036D01*
G01Y528556D02*
X740851D01*
G01X732257Y586379D02*
Y559979D01*
G01X745257D02*
Y586379D01*
G01X732257Y559979D02*
X745257D01*
G01X736940Y595823D02*
X736710Y595978D01*
X736442Y596081D01*
X736135D01*
X735790Y595926D01*
X735522Y595668D01*
X735330Y595358D01*
X735177Y594841D01*
X735139Y594376D01*
X735215Y593911D01*
X735330Y593601D01*
X735560Y593291D01*
X735829Y593084D01*
X736097Y592981D01*
X736365D01*
X736634Y593084D01*
X736864Y593239D01*
X737055Y593446D01*
G01X739657Y592981D02*
Y596081D01*
X738239Y593859D01*
X740155D01*
G01X741569Y594273D02*
X741837Y594634D01*
X742067Y594841D01*
X742374Y594944D01*
X742642Y594841D01*
X742834Y594634D01*
X742987Y594324D01*
X743025Y593963D01*
X742987Y593653D01*
X742834Y593343D01*
X742604Y593084D01*
X742335Y592981D01*
X742029Y593084D01*
X741760Y593394D01*
X741607Y593859D01*
X741569Y594376D01*
X741645Y595048D01*
X741760Y595409D01*
X741952Y595771D01*
X742220Y596029D01*
X742489Y596081D01*
X742757Y595978D01*
X742949Y595719D01*
G01X745397Y592981D02*
X745665Y593033D01*
X745972Y593188D01*
X746164Y593446D01*
X746240Y593808D01*
X746164Y594169D01*
X745934Y594479D01*
X745589Y594634D01*
X745205D01*
X744975Y594738D01*
X744784Y594996D01*
X744707Y595358D01*
X744822Y595719D01*
X745090Y595978D01*
X745397Y596081D01*
X745704Y595978D01*
X745972Y595719D01*
X746087Y595358D01*
X746010Y594996D01*
X745819Y594738D01*
X745589Y594634D01*
X745205D01*
X744860Y594479D01*
X744630Y594169D01*
X744554Y593808D01*
X744630Y593446D01*
X744822Y593188D01*
X745129Y593033D01*
X745397Y592981D01*
G01X733495Y595562D02*
Y590962D01*
G01X736868Y587980D02*
X736561Y588032D01*
X736293Y588238D01*
X736063Y588548D01*
X735910Y588910D01*
X735833Y589323D01*
Y589737D01*
X735910Y590150D01*
X736063Y590512D01*
X736293Y590822D01*
X736561Y591028D01*
X736868Y591080D01*
X737175Y591028D01*
X737443Y590822D01*
X737673Y590512D01*
X737826Y590150D01*
X737903Y589737D01*
Y589323D01*
X737826Y588910D01*
X737673Y588548D01*
X737443Y588238D01*
X737175Y588032D01*
X736868Y587980D01*
G01X737175Y588807D02*
X737635Y587980D01*
G01X739968D02*
Y591080D01*
X739508Y590460D01*
G01Y587980D02*
X740428D01*
G01X742340Y589272D02*
X742608Y589633D01*
X742838Y589840D01*
X743145Y589943D01*
X743413Y589840D01*
X743605Y589633D01*
X743758Y589323D01*
X743796Y588962D01*
X743758Y588652D01*
X743605Y588342D01*
X743375Y588083D01*
X743106Y587980D01*
X742800Y588083D01*
X742531Y588393D01*
X742378Y588858D01*
X742340Y589375D01*
X742416Y590047D01*
X742531Y590408D01*
X742723Y590770D01*
X742991Y591028D01*
X743260Y591080D01*
X743528Y590977D01*
X743720Y590718D01*
G01X745257Y586379D02*
X732257D01*
G01X733288Y615497D02*
Y610497D01*
X735822D01*
G01X738072D02*
X739655Y615497D01*
X741238Y610497D01*
G01X740668Y612247D02*
X738642D01*
G01X743298Y610497D02*
Y615497D01*
X746212Y610497D01*
Y615497D01*
G01X748652Y614664D02*
X749032Y615164D01*
X749475Y615414D01*
X749982Y615497D01*
X750615Y615330D01*
X751058Y614914D01*
X751185Y614414D01*
X751122Y613914D01*
X750868Y613497D01*
X749602Y612664D01*
X749032Y612080D01*
X748652Y611247D01*
X748525Y610497D01*
X751185D01*
G01X732183Y616753D02*
X752723D01*
Y609624D01*
X731618D01*
Y616753D01*
X732183D01*
G01X732997Y619298D02*
Y622398D01*
X733956D01*
X734262Y622243D01*
X734454Y622036D01*
X734531Y621623D01*
X734454Y621210D01*
X734224Y620951D01*
X733956Y620796D01*
X732997D01*
G01X733956D02*
X734531Y619298D01*
G01X736864D02*
Y622398D01*
X736404Y621778D01*
G01Y619298D02*
X737324D01*
G01X739236Y621881D02*
X739466Y622191D01*
X739734Y622346D01*
X740041Y622398D01*
X740424Y622295D01*
X740692Y622036D01*
X740769Y621726D01*
X740731Y621416D01*
X740577Y621158D01*
X739811Y620641D01*
X739466Y620280D01*
X739236Y619763D01*
X739159Y619298D01*
X740769D01*
G01X742987D02*
X743064Y619970D01*
X743179Y620538D01*
X743332Y621055D01*
X743524Y621623D01*
X743831Y622398D01*
X742297D01*
G01X746087Y619298D02*
X746164Y619970D01*
X746279Y620538D01*
X746432Y621055D01*
X746624Y621623D01*
X746931Y622398D01*
X745397D01*
G01X733047Y627650D02*
Y630750D01*
X734006D01*
X734312Y630595D01*
X734504Y630388D01*
X734581Y629975D01*
X734504Y629562D01*
X734274Y629303D01*
X734006Y629148D01*
X733047D01*
G01X734006D02*
X734581Y627650D01*
G01X736914D02*
Y630750D01*
X736454Y630130D01*
G01Y627650D02*
X737374D01*
G01X739286Y630233D02*
X739516Y630543D01*
X739784Y630698D01*
X740091Y630750D01*
X740474Y630647D01*
X740742Y630388D01*
X740819Y630078D01*
X740781Y629768D01*
X740627Y629510D01*
X739861Y628993D01*
X739516Y628632D01*
X739286Y628115D01*
X739209Y627650D01*
X740819D01*
G01X743037D02*
X743114Y628322D01*
X743229Y628890D01*
X743382Y629407D01*
X743574Y629975D01*
X743881Y630750D01*
X742347D01*
G01X745562Y628012D02*
X745831Y627753D01*
X746137Y627650D01*
X746444Y627753D01*
X746712Y628063D01*
X746904Y628528D01*
X746981Y628993D01*
Y629562D01*
X746904Y630027D01*
X746712Y630440D01*
X746482Y630647D01*
X746214Y630750D01*
X745907Y630647D01*
X745677Y630440D01*
X745524Y630130D01*
X745447Y629717D01*
X745524Y629355D01*
X745716Y628993D01*
X745946Y628787D01*
X746214Y628735D01*
X746521Y628838D01*
X746751Y629097D01*
X746981Y629562D01*
G01X733047Y623373D02*
Y626473D01*
X734006D01*
X734312Y626318D01*
X734504Y626111D01*
X734581Y625698D01*
X734504Y625285D01*
X734274Y625026D01*
X734006Y624871D01*
X733047D01*
G01X734006D02*
X734581Y623373D01*
G01X736914D02*
Y626473D01*
X736454Y625853D01*
G01Y623373D02*
X737374D01*
G01X739286Y625956D02*
X739516Y626266D01*
X739784Y626421D01*
X740091Y626473D01*
X740474Y626370D01*
X740742Y626111D01*
X740819Y625801D01*
X740781Y625491D01*
X740627Y625233D01*
X739861Y624716D01*
X739516Y624355D01*
X739286Y623838D01*
X739209Y623373D01*
X740819D01*
G01X743037D02*
X743114Y624045D01*
X743229Y624613D01*
X743382Y625130D01*
X743574Y625698D01*
X743881Y626473D01*
X742347D01*
G01X746214Y623373D02*
X746482Y623425D01*
X746789Y623580D01*
X746981Y623838D01*
X747057Y624200D01*
X746981Y624561D01*
X746751Y624871D01*
X746406Y625026D01*
X746022D01*
X745792Y625130D01*
X745601Y625388D01*
X745524Y625750D01*
X745639Y626111D01*
X745907Y626370D01*
X746214Y626473D01*
X746521Y626370D01*
X746789Y626111D01*
X746904Y625750D01*
X746827Y625388D01*
X746636Y625130D01*
X746406Y625026D01*
X746022D01*
X745677Y624871D01*
X745447Y624561D01*
X745371Y624200D01*
X745447Y623838D01*
X745639Y623580D01*
X745946Y623425D01*
X746214Y623373D01*
G01X731595Y657800D02*
Y629736D01*
G01X751139Y638772D02*
X743739D01*
G01D02*
Y656172D01*
G01X736150Y640229D02*
Y643429D01*
G01X742350Y640229D02*
X736150D01*
G01X742350Y643429D02*
Y640229D01*
G01X736150Y643429D02*
X742350D01*
G01X733197Y631927D02*
Y635027D01*
X734156D01*
X734462Y634872D01*
X734654Y634665D01*
X734731Y634252D01*
X734654Y633839D01*
X734424Y633580D01*
X734156Y633425D01*
X733197D01*
G01X734156D02*
X734731Y631927D01*
G01X737064D02*
Y635027D01*
X736604Y634407D01*
G01Y631927D02*
X737524D01*
G01X739436Y634510D02*
X739666Y634820D01*
X739934Y634975D01*
X740241Y635027D01*
X740624Y634924D01*
X740892Y634665D01*
X740969Y634355D01*
X740931Y634045D01*
X740777Y633787D01*
X740011Y633270D01*
X739666Y632909D01*
X739436Y632392D01*
X739359Y631927D01*
X740969D01*
G01X743264D02*
X743532Y631979D01*
X743839Y632134D01*
X744031Y632392D01*
X744107Y632754D01*
X744031Y633115D01*
X743801Y633425D01*
X743456Y633580D01*
X743072D01*
X742842Y633684D01*
X742651Y633942D01*
X742574Y634304D01*
X742689Y634665D01*
X742957Y634924D01*
X743264Y635027D01*
X743571Y634924D01*
X743839Y634665D01*
X743954Y634304D01*
X743877Y633942D01*
X743686Y633684D01*
X743456Y633580D01*
X743072D01*
X742727Y633425D01*
X742497Y633115D01*
X742421Y632754D01*
X742497Y632392D01*
X742689Y632134D01*
X742996Y631979D01*
X743264Y631927D01*
G01X746364Y635027D02*
X746057Y634924D01*
X745827Y634665D01*
X745674Y634355D01*
X745559Y633942D01*
X745521Y633477D01*
X745559Y633012D01*
X745674Y632599D01*
X745827Y632289D01*
X746057Y632030D01*
X746364Y631927D01*
X746671Y632030D01*
X746901Y632289D01*
X747054Y632599D01*
X747169Y633012D01*
X747207Y633477D01*
X747169Y633942D01*
X747054Y634355D01*
X746901Y634665D01*
X746671Y634924D01*
X746364Y635027D01*
G01X738995Y657074D02*
X732312D01*
Y657095D01*
X734505Y659288D01*
X734526Y659267D01*
Y654439D01*
X732291Y656674D01*
Y657011D01*
G01X743739Y656172D02*
X751139D01*
G01Y647472D02*
X743739D01*
G01X736150Y652229D02*
Y655429D01*
G01X742350Y652229D02*
X736150D01*
G01X742350Y655429D02*
Y652229D01*
G01X736150Y655429D02*
X742350D01*
G01X736150Y648229D02*
Y651429D01*
G01X742350D02*
Y648229D01*
G01X736150Y651429D02*
X742350D01*
G01Y648229D02*
X736150D01*
G01Y644229D02*
Y647429D01*
G01X742350D02*
Y644229D01*
G01X736150Y647429D02*
X742350D01*
G01Y644229D02*
X736150D01*
G01X733143Y784711D02*
X733250Y784836D01*
X733330Y785045D01*
X733383Y785336D01*
X733330Y785586D01*
X733223Y785753D01*
X733037Y785878D01*
X732317D01*
Y783378D01*
X733197D01*
X733383Y783545D01*
X733490Y783795D01*
X733543Y784086D01*
X733490Y784378D01*
X733330Y784628D01*
X733143Y784711D01*
X732317D01*
G01X735130Y783378D02*
Y785878D01*
X734810Y785378D01*
G01Y783378D02*
X735450D01*
G01X738841Y819152D02*
Y788581D01*
G01X736341Y821652D02*
X738841Y819152D01*
G01X756360Y33044D02*
X756590Y33354D01*
X756858Y33509D01*
X757165Y33561D01*
X757548Y33458D01*
X757816Y33199D01*
X757893Y32889D01*
X757855Y32579D01*
X757701Y32321D01*
X756935Y31804D01*
X756590Y31443D01*
X756360Y30926D01*
X756283Y30461D01*
X757893D01*
G01X755755Y24361D02*
Y34361D01*
G01X751165Y38082D02*
X758953Y45870D01*
Y68197D01*
X760770Y64216D01*
X757136D01*
X758867Y68283D01*
G01X750720Y98676D02*
X750490Y98831D01*
X750222Y98934D01*
X749915D01*
X749570Y98779D01*
X749302Y98521D01*
X749110Y98211D01*
X748957Y97694D01*
X748919Y97229D01*
X748995Y96764D01*
X749110Y96454D01*
X749340Y96144D01*
X749609Y95937D01*
X749877Y95834D01*
X750145D01*
X750414Y95937D01*
X750644Y96092D01*
X750835Y96299D01*
G01X752134D02*
X752364Y96041D01*
X752632Y95886D01*
X752977Y95834D01*
X753322Y95937D01*
X753590Y96144D01*
X753782Y96506D01*
X753820Y96919D01*
X753744Y97332D01*
X753552Y97591D01*
X753284Y97797D01*
X753015Y97849D01*
X752747Y97797D01*
X752402Y97591D01*
X752517Y98934D01*
X753552D01*
G01X755234Y96299D02*
X755464Y96041D01*
X755732Y95886D01*
X756077Y95834D01*
X756422Y95937D01*
X756690Y96144D01*
X756882Y96506D01*
X756920Y96919D01*
X756844Y97332D01*
X756652Y97591D01*
X756384Y97797D01*
X756115Y97849D01*
X755847Y97797D01*
X755502Y97591D01*
X755617Y98934D01*
X756652D01*
G01X758449Y97126D02*
X758717Y97487D01*
X758947Y97694D01*
X759254Y97797D01*
X759522Y97694D01*
X759714Y97487D01*
X759867Y97177D01*
X759905Y96816D01*
X759867Y96506D01*
X759714Y96196D01*
X759484Y95937D01*
X759215Y95834D01*
X758909Y95937D01*
X758640Y96247D01*
X758487Y96712D01*
X758449Y97229D01*
X758525Y97901D01*
X758640Y98262D01*
X758832Y98624D01*
X759100Y98882D01*
X759369Y98934D01*
X759637Y98831D01*
X759829Y98572D01*
G01X753750Y108476D02*
Y101876D01*
G01X761250Y108576D02*
Y101776D01*
G01X757371Y113942D02*
X754271D01*
Y115398D01*
G01X755769Y114862D02*
Y113942D01*
G01X756958Y116965D02*
X757216Y117272D01*
X757371Y117617D01*
Y117923D01*
X757216Y118230D01*
X756958Y118460D01*
X756596Y118575D01*
X756234Y118498D01*
X755924Y118307D01*
X755718Y117962D01*
X755614Y117502D01*
X755408Y117233D01*
X755046Y117118D01*
X754684Y117195D01*
X754426Y117387D01*
X754271Y117655D01*
Y117923D01*
X754374Y118192D01*
X754633Y118422D01*
G01X756751Y120027D02*
X757113Y120257D01*
X757319Y120563D01*
X757371Y120908D01*
X757319Y121215D01*
X757061Y121522D01*
X756751Y121713D01*
X756441Y121752D01*
X756079Y121675D01*
X755821Y121407D01*
X755718Y121138D01*
Y120793D01*
G01Y121138D02*
X755563Y121368D01*
X755304Y121560D01*
X754994Y121637D01*
X754684Y121560D01*
X754426Y121368D01*
X754271Y121023D01*
X754323Y120678D01*
X754529Y120333D01*
G01X752847Y128103D02*
Y111564D01*
G01X757222Y129395D02*
X757382Y129645D01*
X757569Y129770D01*
X757782Y129812D01*
X758049Y129729D01*
X758236Y129520D01*
X758289Y129270D01*
X758262Y129020D01*
X758156Y128812D01*
X757622Y128395D01*
X757382Y128104D01*
X757222Y127687D01*
X757169Y127312D01*
X758289D01*
G01X753935Y134972D02*
X754127Y134662D01*
X754357Y134455D01*
X754625Y134352D01*
X754932Y134455D01*
X755162Y134662D01*
X755392Y134972D01*
X755469Y135385D01*
Y137452D01*
G01X757802Y134352D02*
Y137452D01*
X757342Y136832D01*
G01Y134352D02*
X758262D01*
G01X761362D02*
Y137452D01*
X759944Y135230D01*
X761860D01*
G01X755810Y350690D02*
Y343180D01*
G01X783840Y350690D02*
X755810D01*
G01X753033Y357007D02*
Y360107D01*
X753992D01*
X754298Y359952D01*
X754490Y359745D01*
X754567Y359332D01*
X754490Y358919D01*
X754260Y358660D01*
X753992Y358505D01*
X753033D01*
G01X753992D02*
X754567Y357007D01*
G01X756900D02*
Y360107D01*
X756440Y359487D01*
G01Y357007D02*
X757360D01*
G01X760000Y360107D02*
X759693Y360004D01*
X759463Y359745D01*
X759310Y359435D01*
X759195Y359022D01*
X759157Y358557D01*
X759195Y358092D01*
X759310Y357679D01*
X759463Y357369D01*
X759693Y357110D01*
X760000Y357007D01*
X760307Y357110D01*
X760537Y357369D01*
X760690Y357679D01*
X760805Y358092D01*
X760843Y358557D01*
X760805Y359022D01*
X760690Y359435D01*
X760537Y359745D01*
X760307Y360004D01*
X760000Y360107D01*
G01X763100D02*
X762793Y360004D01*
X762563Y359745D01*
X762410Y359435D01*
X762295Y359022D01*
X762257Y358557D01*
X762295Y358092D01*
X762410Y357679D01*
X762563Y357369D01*
X762793Y357110D01*
X763100Y357007D01*
X763407Y357110D01*
X763637Y357369D01*
X763790Y357679D01*
X763905Y358092D01*
X763943Y358557D01*
X763905Y359022D01*
X763790Y359435D01*
X763637Y359745D01*
X763407Y360004D01*
X763100Y360107D01*
G01X765357Y357627D02*
X765587Y357265D01*
X765893Y357059D01*
X766238Y357007D01*
X766545Y357059D01*
X766852Y357317D01*
X767043Y357627D01*
X767082Y357937D01*
X767005Y358299D01*
X766737Y358557D01*
X766468Y358660D01*
X766123D01*
G01X766468D02*
X766698Y358815D01*
X766890Y359074D01*
X766967Y359384D01*
X766890Y359694D01*
X766698Y359952D01*
X766353Y360107D01*
X766008Y360055D01*
X765663Y359849D01*
G01X754221Y352630D02*
Y355730D01*
X755180D01*
X755486Y355575D01*
X755678Y355368D01*
X755755Y354955D01*
X755678Y354542D01*
X755448Y354283D01*
X755180Y354128D01*
X754221D01*
G01X755180D02*
X755755Y352630D01*
G01X758088D02*
Y355730D01*
X757628Y355110D01*
G01Y352630D02*
X758548D01*
G01X761188D02*
Y355730D01*
X760728Y355110D01*
G01Y352630D02*
X761648D01*
G01X763560Y355213D02*
X763790Y355523D01*
X764058Y355678D01*
X764365Y355730D01*
X764748Y355627D01*
X765016Y355368D01*
X765093Y355058D01*
X765055Y354748D01*
X764901Y354490D01*
X764135Y353973D01*
X763790Y353612D01*
X763560Y353095D01*
X763483Y352630D01*
X765093D01*
G01X766736Y352992D02*
X767005Y352733D01*
X767311Y352630D01*
X767618Y352733D01*
X767886Y353043D01*
X768078Y353508D01*
X768155Y353973D01*
Y354542D01*
X768078Y355007D01*
X767886Y355420D01*
X767656Y355627D01*
X767388Y355730D01*
X767081Y355627D01*
X766851Y355420D01*
X766698Y355110D01*
X766621Y354697D01*
X766698Y354335D01*
X766890Y353973D01*
X767120Y353767D01*
X767388Y353715D01*
X767695Y353818D01*
X767925Y354077D01*
X768155Y354542D01*
G01X754254Y368667D02*
Y371767D01*
X755213D01*
X755519Y371612D01*
X755711Y371405D01*
X755788Y370992D01*
X755711Y370579D01*
X755481Y370320D01*
X755213Y370165D01*
X754254D01*
G01X755213D02*
X755788Y368667D01*
G01X758044D02*
X758121Y369339D01*
X758236Y369907D01*
X758389Y370424D01*
X758581Y370992D01*
X758888Y371767D01*
X757354D01*
G01X760493Y369959D02*
X760761Y370320D01*
X760991Y370527D01*
X761298Y370630D01*
X761566Y370527D01*
X761758Y370320D01*
X761911Y370010D01*
X761949Y369649D01*
X761911Y369339D01*
X761758Y369029D01*
X761528Y368770D01*
X761259Y368667D01*
X760953Y368770D01*
X760684Y369080D01*
X760531Y369545D01*
X760493Y370062D01*
X760569Y370734D01*
X760684Y371095D01*
X760876Y371457D01*
X761144Y371715D01*
X761413Y371767D01*
X761681Y371664D01*
X761873Y371405D01*
G01X763669Y369029D02*
X763938Y368770D01*
X764244Y368667D01*
X764551Y368770D01*
X764819Y369080D01*
X765011Y369545D01*
X765088Y370010D01*
Y370579D01*
X765011Y371044D01*
X764819Y371457D01*
X764589Y371664D01*
X764321Y371767D01*
X764014Y371664D01*
X763784Y371457D01*
X763631Y371147D01*
X763554Y370734D01*
X763631Y370372D01*
X763823Y370010D01*
X764053Y369804D01*
X764321Y369752D01*
X764628Y369855D01*
X764858Y370114D01*
X765088Y370579D01*
G01X754150Y376738D02*
Y379838D01*
X755109D01*
X755415Y379683D01*
X755607Y379476D01*
X755684Y379063D01*
X755607Y378650D01*
X755377Y378391D01*
X755109Y378236D01*
X754150D01*
G01X755109D02*
X755684Y376738D01*
G01X757940D02*
X758017Y377410D01*
X758132Y377978D01*
X758285Y378495D01*
X758477Y379063D01*
X758784Y379838D01*
X757250D01*
G01X761040Y376738D02*
X761117Y377410D01*
X761232Y377978D01*
X761385Y378495D01*
X761577Y379063D01*
X761884Y379838D01*
X760350D01*
G01X764217Y376738D02*
Y379838D01*
X763757Y379218D01*
G01Y376738D02*
X764677D01*
G01X754150Y372738D02*
Y375838D01*
X755109D01*
X755415Y375683D01*
X755607Y375476D01*
X755684Y375063D01*
X755607Y374650D01*
X755377Y374391D01*
X755109Y374236D01*
X754150D01*
G01X755109D02*
X755684Y372738D01*
G01X757940D02*
X758017Y373410D01*
X758132Y373978D01*
X758285Y374495D01*
X758477Y375063D01*
X758784Y375838D01*
X757250D01*
G01X761040Y372738D02*
X761117Y373410D01*
X761232Y373978D01*
X761385Y374495D01*
X761577Y375063D01*
X761884Y375838D01*
X760350D01*
G01X763489Y375321D02*
X763719Y375631D01*
X763987Y375786D01*
X764294Y375838D01*
X764677Y375735D01*
X764945Y375476D01*
X765022Y375166D01*
X764984Y374856D01*
X764830Y374598D01*
X764064Y374081D01*
X763719Y373720D01*
X763489Y373203D01*
X763412Y372738D01*
X765022D01*
G01X753906Y380731D02*
Y383831D01*
X754865D01*
X755171Y383676D01*
X755363Y383469D01*
X755440Y383056D01*
X755363Y382643D01*
X755133Y382384D01*
X754865Y382229D01*
X753906D01*
G01X754865D02*
X755440Y380731D01*
G01X757696D02*
X757773Y381403D01*
X757888Y381971D01*
X758041Y382488D01*
X758233Y383056D01*
X758540Y383831D01*
X757006D01*
G01X760145Y382023D02*
X760413Y382384D01*
X760643Y382591D01*
X760950Y382694D01*
X761218Y382591D01*
X761410Y382384D01*
X761563Y382074D01*
X761601Y381713D01*
X761563Y381403D01*
X761410Y381093D01*
X761180Y380834D01*
X760911Y380731D01*
X760605Y380834D01*
X760336Y381144D01*
X760183Y381609D01*
X760145Y382126D01*
X760221Y382798D01*
X760336Y383159D01*
X760528Y383521D01*
X760796Y383779D01*
X761065Y383831D01*
X761333Y383728D01*
X761525Y383469D01*
G01X763896Y380731D02*
X763973Y381403D01*
X764088Y381971D01*
X764241Y382488D01*
X764433Y383056D01*
X764740Y383831D01*
X763206D01*
G01X748500Y437000D02*
X785500D01*
Y414000D01*
X777500D01*
Y395500D01*
X757500D01*
Y413500D01*
X747000D01*
Y437000D01*
X748500D01*
G01X760383Y407000D02*
Y410100D01*
X761342D01*
X761648Y409945D01*
X761840Y409738D01*
X761917Y409325D01*
X761840Y408912D01*
X761610Y408653D01*
X761342Y408498D01*
X760383D01*
G01X761342D02*
X761917Y407000D01*
G01X764250D02*
Y410100D01*
X763790Y409480D01*
G01Y407000D02*
X764710D01*
G01X767350Y410100D02*
X767043Y409997D01*
X766813Y409738D01*
X766660Y409428D01*
X766545Y409015D01*
X766507Y408550D01*
X766545Y408085D01*
X766660Y407672D01*
X766813Y407362D01*
X767043Y407103D01*
X767350Y407000D01*
X767657Y407103D01*
X767887Y407362D01*
X768040Y407672D01*
X768155Y408085D01*
X768193Y408550D01*
X768155Y409015D01*
X768040Y409428D01*
X767887Y409738D01*
X767657Y409997D01*
X767350Y410100D01*
G01X769607Y407620D02*
X769837Y407258D01*
X770143Y407052D01*
X770488Y407000D01*
X770795Y407052D01*
X771102Y407310D01*
X771293Y407620D01*
X771332Y407930D01*
X771255Y408292D01*
X770987Y408550D01*
X770718Y408653D01*
X770373D01*
G01X770718D02*
X770948Y408808D01*
X771140Y409067D01*
X771217Y409377D01*
X771140Y409687D01*
X770948Y409945D01*
X770603Y410100D01*
X770258Y410048D01*
X769913Y409842D01*
G01X774010Y407000D02*
Y410100D01*
X772592Y407878D01*
X774508D01*
G01X760383Y403000D02*
Y406100D01*
X761342D01*
X761648Y405945D01*
X761840Y405738D01*
X761917Y405325D01*
X761840Y404912D01*
X761610Y404653D01*
X761342Y404498D01*
X760383D01*
G01X761342D02*
X761917Y403000D01*
G01X764250D02*
Y406100D01*
X763790Y405480D01*
G01Y403000D02*
X764710D01*
G01X767350Y406100D02*
X767043Y405997D01*
X766813Y405738D01*
X766660Y405428D01*
X766545Y405015D01*
X766507Y404550D01*
X766545Y404085D01*
X766660Y403672D01*
X766813Y403362D01*
X767043Y403103D01*
X767350Y403000D01*
X767657Y403103D01*
X767887Y403362D01*
X768040Y403672D01*
X768155Y404085D01*
X768193Y404550D01*
X768155Y405015D01*
X768040Y405428D01*
X767887Y405738D01*
X767657Y405997D01*
X767350Y406100D01*
G01X769607Y403620D02*
X769837Y403258D01*
X770143Y403052D01*
X770488Y403000D01*
X770795Y403052D01*
X771102Y403310D01*
X771293Y403620D01*
X771332Y403930D01*
X771255Y404292D01*
X770987Y404550D01*
X770718Y404653D01*
X770373D01*
G01X770718D02*
X770948Y404808D01*
X771140Y405067D01*
X771217Y405377D01*
X771140Y405687D01*
X770948Y405945D01*
X770603Y406100D01*
X770258Y406048D01*
X769913Y405842D01*
G01X772707Y403465D02*
X772937Y403207D01*
X773205Y403052D01*
X773550Y403000D01*
X773895Y403103D01*
X774163Y403310D01*
X774355Y403672D01*
X774393Y404085D01*
X774317Y404498D01*
X774125Y404757D01*
X773857Y404963D01*
X773588Y405015D01*
X773320Y404963D01*
X772975Y404757D01*
X773090Y406100D01*
X774125D01*
G01X760883Y398500D02*
Y401600D01*
X761842D01*
X762148Y401445D01*
X762340Y401238D01*
X762417Y400825D01*
X762340Y400412D01*
X762110Y400153D01*
X761842Y399998D01*
X760883D01*
G01X761842D02*
X762417Y398500D01*
G01X764750D02*
Y401600D01*
X764290Y400980D01*
G01Y398500D02*
X765210D01*
G01X767122Y401083D02*
X767352Y401393D01*
X767620Y401548D01*
X767927Y401600D01*
X768310Y401497D01*
X768578Y401238D01*
X768655Y400928D01*
X768617Y400618D01*
X768463Y400360D01*
X767697Y399843D01*
X767352Y399482D01*
X767122Y398965D01*
X767045Y398500D01*
X768655D01*
G01X770950D02*
X771218Y398552D01*
X771525Y398707D01*
X771717Y398965D01*
X771793Y399327D01*
X771717Y399688D01*
X771487Y399998D01*
X771142Y400153D01*
X770758D01*
X770528Y400257D01*
X770337Y400515D01*
X770260Y400877D01*
X770375Y401238D01*
X770643Y401497D01*
X770950Y401600D01*
X771257Y401497D01*
X771525Y401238D01*
X771640Y400877D01*
X771563Y400515D01*
X771372Y400257D01*
X771142Y400153D01*
X770758D01*
X770413Y399998D01*
X770183Y399688D01*
X770107Y399327D01*
X770183Y398965D01*
X770375Y398707D01*
X770682Y398552D01*
X770950Y398500D01*
G01X773207Y398965D02*
X773437Y398707D01*
X773705Y398552D01*
X774050Y398500D01*
X774395Y398603D01*
X774663Y398810D01*
X774855Y399172D01*
X774893Y399585D01*
X774817Y399998D01*
X774625Y400257D01*
X774357Y400463D01*
X774088Y400515D01*
X773820Y400463D01*
X773475Y400257D01*
X773590Y401600D01*
X774625D01*
G01X760383Y411500D02*
Y414600D01*
X761342D01*
X761648Y414445D01*
X761840Y414238D01*
X761917Y413825D01*
X761840Y413412D01*
X761610Y413153D01*
X761342Y412998D01*
X760383D01*
G01X761342D02*
X761917Y411500D01*
G01X764250D02*
Y414600D01*
X763790Y413980D01*
G01Y411500D02*
X764710D01*
G01X767350Y414600D02*
X767043Y414497D01*
X766813Y414238D01*
X766660Y413928D01*
X766545Y413515D01*
X766507Y413050D01*
X766545Y412585D01*
X766660Y412172D01*
X766813Y411862D01*
X767043Y411603D01*
X767350Y411500D01*
X767657Y411603D01*
X767887Y411862D01*
X768040Y412172D01*
X768155Y412585D01*
X768193Y413050D01*
X768155Y413515D01*
X768040Y413928D01*
X767887Y414238D01*
X767657Y414497D01*
X767350Y414600D01*
G01X769607Y412120D02*
X769837Y411758D01*
X770143Y411552D01*
X770488Y411500D01*
X770795Y411552D01*
X771102Y411810D01*
X771293Y412120D01*
X771332Y412430D01*
X771255Y412792D01*
X770987Y413050D01*
X770718Y413153D01*
X770373D01*
G01X770718D02*
X770948Y413308D01*
X771140Y413567D01*
X771217Y413877D01*
X771140Y414187D01*
X770948Y414445D01*
X770603Y414600D01*
X770258Y414548D01*
X769913Y414342D01*
G01X772707Y412120D02*
X772937Y411758D01*
X773243Y411552D01*
X773588Y411500D01*
X773895Y411552D01*
X774202Y411810D01*
X774393Y412120D01*
X774432Y412430D01*
X774355Y412792D01*
X774087Y413050D01*
X773818Y413153D01*
X773473D01*
G01X773818D02*
X774048Y413308D01*
X774240Y413567D01*
X774317Y413877D01*
X774240Y414187D01*
X774048Y414445D01*
X773703Y414600D01*
X773358Y414548D01*
X773013Y414342D01*
G01X749283Y420800D02*
Y423900D01*
X750242D01*
X750548Y423745D01*
X750740Y423538D01*
X750817Y423125D01*
X750740Y422712D01*
X750510Y422453D01*
X750242Y422298D01*
X749283D01*
G01X750242D02*
X750817Y420800D01*
G01X753150D02*
Y423900D01*
X752690Y423280D01*
G01Y420800D02*
X753610D01*
G01X755522Y423383D02*
X755752Y423693D01*
X756020Y423848D01*
X756327Y423900D01*
X756710Y423797D01*
X756978Y423538D01*
X757055Y423228D01*
X757017Y422918D01*
X756863Y422660D01*
X756097Y422143D01*
X755752Y421782D01*
X755522Y421265D01*
X755445Y420800D01*
X757055D01*
G01X758698Y421162D02*
X758967Y420903D01*
X759273Y420800D01*
X759580Y420903D01*
X759848Y421213D01*
X760040Y421678D01*
X760117Y422143D01*
Y422712D01*
X760040Y423177D01*
X759848Y423590D01*
X759618Y423797D01*
X759350Y423900D01*
X759043Y423797D01*
X758813Y423590D01*
X758660Y423280D01*
X758583Y422867D01*
X758660Y422505D01*
X758852Y422143D01*
X759082Y421937D01*
X759350Y421885D01*
X759657Y421988D01*
X759887Y422247D01*
X760117Y422712D01*
G01X762450Y423900D02*
X762143Y423797D01*
X761913Y423538D01*
X761760Y423228D01*
X761645Y422815D01*
X761607Y422350D01*
X761645Y421885D01*
X761760Y421472D01*
X761913Y421162D01*
X762143Y420903D01*
X762450Y420800D01*
X762757Y420903D01*
X762987Y421162D01*
X763140Y421472D01*
X763255Y421885D01*
X763293Y422350D01*
X763255Y422815D01*
X763140Y423228D01*
X762987Y423538D01*
X762757Y423797D01*
X762450Y423900D01*
G01X749383Y416500D02*
Y419600D01*
X750342D01*
X750648Y419445D01*
X750840Y419238D01*
X750917Y418825D01*
X750840Y418412D01*
X750610Y418153D01*
X750342Y417998D01*
X749383D01*
G01X750342D02*
X750917Y416500D01*
G01X753250D02*
Y419600D01*
X752790Y418980D01*
G01Y416500D02*
X753710D01*
G01X755622Y419083D02*
X755852Y419393D01*
X756120Y419548D01*
X756427Y419600D01*
X756810Y419497D01*
X757078Y419238D01*
X757155Y418928D01*
X757117Y418618D01*
X756963Y418360D01*
X756197Y417843D01*
X755852Y417482D01*
X755622Y416965D01*
X755545Y416500D01*
X757155D01*
G01X759373D02*
X759450Y417172D01*
X759565Y417740D01*
X759718Y418257D01*
X759910Y418825D01*
X760217Y419600D01*
X758683D01*
G01X761822Y419083D02*
X762052Y419393D01*
X762320Y419548D01*
X762627Y419600D01*
X763010Y419497D01*
X763278Y419238D01*
X763355Y418928D01*
X763317Y418618D01*
X763163Y418360D01*
X762397Y417843D01*
X762052Y417482D01*
X761822Y416965D01*
X761745Y416500D01*
X763355D01*
G01X749383Y425000D02*
Y428100D01*
X750342D01*
X750648Y427945D01*
X750840Y427738D01*
X750917Y427325D01*
X750840Y426912D01*
X750610Y426653D01*
X750342Y426498D01*
X749383D01*
G01X750342D02*
X750917Y425000D01*
G01X753250D02*
Y428100D01*
X752790Y427480D01*
G01Y425000D02*
X753710D01*
G01X755622Y427583D02*
X755852Y427893D01*
X756120Y428048D01*
X756427Y428100D01*
X756810Y427997D01*
X757078Y427738D01*
X757155Y427428D01*
X757117Y427118D01*
X756963Y426860D01*
X756197Y426343D01*
X755852Y425982D01*
X755622Y425465D01*
X755545Y425000D01*
X757155D01*
G01X759450D02*
X759718Y425052D01*
X760025Y425207D01*
X760217Y425465D01*
X760293Y425827D01*
X760217Y426188D01*
X759987Y426498D01*
X759642Y426653D01*
X759258D01*
X759028Y426757D01*
X758837Y427015D01*
X758760Y427377D01*
X758875Y427738D01*
X759143Y427997D01*
X759450Y428100D01*
X759757Y427997D01*
X760025Y427738D01*
X760140Y427377D01*
X760063Y427015D01*
X759872Y426757D01*
X759642Y426653D01*
X759258D01*
X758913Y426498D01*
X758683Y426188D01*
X758607Y425827D01*
X758683Y425465D01*
X758875Y425207D01*
X759182Y425052D01*
X759450Y425000D01*
G01X761822Y426292D02*
X762090Y426653D01*
X762320Y426860D01*
X762627Y426963D01*
X762895Y426860D01*
X763087Y426653D01*
X763240Y426343D01*
X763278Y425982D01*
X763240Y425672D01*
X763087Y425362D01*
X762857Y425103D01*
X762588Y425000D01*
X762282Y425103D01*
X762013Y425413D01*
X761860Y425878D01*
X761822Y426395D01*
X761898Y427067D01*
X762013Y427428D01*
X762205Y427790D01*
X762473Y428048D01*
X762742Y428100D01*
X763010Y427997D01*
X763202Y427738D01*
G01X749123Y457332D02*
Y444332D01*
G01X761257Y447506D02*
X761027Y447661D01*
X760759Y447764D01*
X760452D01*
X760107Y447609D01*
X759839Y447351D01*
X759647Y447041D01*
X759494Y446524D01*
X759456Y446059D01*
X759532Y445594D01*
X759647Y445284D01*
X759877Y444974D01*
X760146Y444767D01*
X760414Y444664D01*
X760682D01*
X760951Y444767D01*
X761181Y444922D01*
X761372Y445129D01*
G01X763437Y444664D02*
X763514Y445336D01*
X763629Y445904D01*
X763782Y446421D01*
X763974Y446989D01*
X764281Y447764D01*
X762747D01*
G01X766614Y444664D02*
X766882Y444716D01*
X767189Y444871D01*
X767381Y445129D01*
X767457Y445491D01*
X767381Y445852D01*
X767151Y446162D01*
X766806Y446317D01*
X766422D01*
X766192Y446421D01*
X766001Y446679D01*
X765924Y447041D01*
X766039Y447402D01*
X766307Y447661D01*
X766614Y447764D01*
X766921Y447661D01*
X767189Y447402D01*
X767304Y447041D01*
X767227Y446679D01*
X767036Y446421D01*
X766806Y446317D01*
X766422D01*
X766077Y446162D01*
X765847Y445852D01*
X765771Y445491D01*
X765847Y445129D01*
X766039Y444871D01*
X766346Y444716D01*
X766614Y444664D01*
G01X769714D02*
Y447764D01*
X769254Y447144D01*
G01Y444664D02*
X770174D01*
G01X756523Y448132D02*
Y444932D01*
G01D02*
X750323D01*
G01X753423Y448032D02*
Y445032D01*
G01X750323Y444932D02*
Y448132D01*
G01D02*
X756523D01*
G01X759807Y453516D02*
Y456616D01*
X760766D01*
X761072Y456461D01*
X761264Y456254D01*
X761341Y455841D01*
X761264Y455428D01*
X761034Y455169D01*
X760766Y455014D01*
X759807D01*
G01X760766D02*
X761341Y453516D01*
G01X763674D02*
Y456616D01*
X763214Y455996D01*
G01Y453516D02*
X764134D01*
G01X766774Y456616D02*
X766467Y456513D01*
X766237Y456254D01*
X766084Y455944D01*
X765969Y455531D01*
X765931Y455066D01*
X765969Y454601D01*
X766084Y454188D01*
X766237Y453878D01*
X766467Y453619D01*
X766774Y453516D01*
X767081Y453619D01*
X767311Y453878D01*
X767464Y454188D01*
X767579Y454601D01*
X767617Y455066D01*
X767579Y455531D01*
X767464Y455944D01*
X767311Y456254D01*
X767081Y456513D01*
X766774Y456616D01*
G01X769146Y456099D02*
X769376Y456409D01*
X769644Y456564D01*
X769951Y456616D01*
X770334Y456513D01*
X770602Y456254D01*
X770679Y455944D01*
X770641Y455634D01*
X770487Y455376D01*
X769721Y454859D01*
X769376Y454498D01*
X769146Y453981D01*
X769069Y453516D01*
X770679D01*
G01X772246Y454808D02*
X772514Y455169D01*
X772744Y455376D01*
X773051Y455479D01*
X773319Y455376D01*
X773511Y455169D01*
X773664Y454859D01*
X773702Y454498D01*
X773664Y454188D01*
X773511Y453878D01*
X773281Y453619D01*
X773012Y453516D01*
X772706Y453619D01*
X772437Y453929D01*
X772284Y454394D01*
X772246Y454911D01*
X772322Y455583D01*
X772437Y455944D01*
X772629Y456306D01*
X772897Y456564D01*
X773166Y456616D01*
X773434Y456513D01*
X773626Y456254D01*
G01X756523Y457132D02*
Y453932D01*
G01D02*
X750323D01*
G01D02*
Y457132D01*
G01X759647Y449171D02*
Y452271D01*
X760606D01*
X760912Y452116D01*
X761104Y451909D01*
X761181Y451496D01*
X761104Y451083D01*
X760874Y450824D01*
X760606Y450669D01*
X759647D01*
G01X760606D02*
X761181Y449171D01*
G01X763514D02*
Y452271D01*
X763054Y451651D01*
G01Y449171D02*
X763974D01*
G01X766614Y452271D02*
X766307Y452168D01*
X766077Y451909D01*
X765924Y451599D01*
X765809Y451186D01*
X765771Y450721D01*
X765809Y450256D01*
X765924Y449843D01*
X766077Y449533D01*
X766307Y449274D01*
X766614Y449171D01*
X766921Y449274D01*
X767151Y449533D01*
X767304Y449843D01*
X767419Y450256D01*
X767457Y450721D01*
X767419Y451186D01*
X767304Y451599D01*
X767151Y451909D01*
X766921Y452168D01*
X766614Y452271D01*
G01X768986Y451754D02*
X769216Y452064D01*
X769484Y452219D01*
X769791Y452271D01*
X770174Y452168D01*
X770442Y451909D01*
X770519Y451599D01*
X770481Y451289D01*
X770327Y451031D01*
X769561Y450514D01*
X769216Y450153D01*
X768986Y449636D01*
X768909Y449171D01*
X770519D01*
G01X772814D02*
X773082Y449223D01*
X773389Y449378D01*
X773581Y449636D01*
X773657Y449998D01*
X773581Y450359D01*
X773351Y450669D01*
X773006Y450824D01*
X772622D01*
X772392Y450928D01*
X772201Y451186D01*
X772124Y451548D01*
X772239Y451909D01*
X772507Y452168D01*
X772814Y452271D01*
X773121Y452168D01*
X773389Y451909D01*
X773504Y451548D01*
X773427Y451186D01*
X773236Y450928D01*
X773006Y450824D01*
X772622D01*
X772277Y450669D01*
X772047Y450359D01*
X771971Y449998D01*
X772047Y449636D01*
X772239Y449378D01*
X772546Y449223D01*
X772814Y449171D01*
G01X756523Y452632D02*
Y449432D01*
G01X750323Y452632D02*
X756523D01*
G01Y449432D02*
X750323D01*
G01D02*
Y452632D01*
G01Y457132D02*
X756523D01*
G01X754683Y463200D02*
Y466300D01*
X755642D01*
X755948Y466145D01*
X756140Y465938D01*
X756217Y465525D01*
X756140Y465112D01*
X755910Y464853D01*
X755642Y464698D01*
X754683D01*
G01X755642D02*
X756217Y463200D01*
G01X758550D02*
Y466300D01*
X758090Y465680D01*
G01Y463200D02*
X759010D01*
G01X760922Y465783D02*
X761152Y466093D01*
X761420Y466248D01*
X761727Y466300D01*
X762110Y466197D01*
X762378Y465938D01*
X762455Y465628D01*
X762417Y465318D01*
X762263Y465060D01*
X761497Y464543D01*
X761152Y464182D01*
X760922Y463665D01*
X760845Y463200D01*
X762455D01*
G01X764022Y464492D02*
X764290Y464853D01*
X764520Y465060D01*
X764827Y465163D01*
X765095Y465060D01*
X765287Y464853D01*
X765440Y464543D01*
X765478Y464182D01*
X765440Y463872D01*
X765287Y463562D01*
X765057Y463303D01*
X764788Y463200D01*
X764482Y463303D01*
X764213Y463613D01*
X764060Y464078D01*
X764022Y464595D01*
X764098Y465267D01*
X764213Y465628D01*
X764405Y465990D01*
X764673Y466248D01*
X764942Y466300D01*
X765210Y466197D01*
X765402Y465938D01*
G01X767122Y464492D02*
X767390Y464853D01*
X767620Y465060D01*
X767927Y465163D01*
X768195Y465060D01*
X768387Y464853D01*
X768540Y464543D01*
X768578Y464182D01*
X768540Y463872D01*
X768387Y463562D01*
X768157Y463303D01*
X767888Y463200D01*
X767582Y463303D01*
X767313Y463613D01*
X767160Y464078D01*
X767122Y464595D01*
X767198Y465267D01*
X767313Y465628D01*
X767505Y465990D01*
X767773Y466248D01*
X768042Y466300D01*
X768310Y466197D01*
X768502Y465938D01*
G01X754683Y468000D02*
Y471100D01*
X755642D01*
X755948Y470945D01*
X756140Y470738D01*
X756217Y470325D01*
X756140Y469912D01*
X755910Y469653D01*
X755642Y469498D01*
X754683D01*
G01X755642D02*
X756217Y468000D01*
G01X758550D02*
Y471100D01*
X758090Y470480D01*
G01Y468000D02*
X759010D01*
G01X760922Y470583D02*
X761152Y470893D01*
X761420Y471048D01*
X761727Y471100D01*
X762110Y470997D01*
X762378Y470738D01*
X762455Y470428D01*
X762417Y470118D01*
X762263Y469860D01*
X761497Y469343D01*
X761152Y468982D01*
X760922Y468465D01*
X760845Y468000D01*
X762455D01*
G01X764022Y469292D02*
X764290Y469653D01*
X764520Y469860D01*
X764827Y469963D01*
X765095Y469860D01*
X765287Y469653D01*
X765440Y469343D01*
X765478Y468982D01*
X765440Y468672D01*
X765287Y468362D01*
X765057Y468103D01*
X764788Y468000D01*
X764482Y468103D01*
X764213Y468413D01*
X764060Y468878D01*
X764022Y469395D01*
X764098Y470067D01*
X764213Y470428D01*
X764405Y470790D01*
X764673Y471048D01*
X764942Y471100D01*
X765210Y470997D01*
X765402Y470738D01*
G01X767007Y468465D02*
X767237Y468207D01*
X767505Y468052D01*
X767850Y468000D01*
X768195Y468103D01*
X768463Y468310D01*
X768655Y468672D01*
X768693Y469085D01*
X768617Y469498D01*
X768425Y469757D01*
X768157Y469963D01*
X767888Y470015D01*
X767620Y469963D01*
X767275Y469757D01*
X767390Y471100D01*
X768425D01*
G01X756600Y473400D02*
X750400D01*
Y476600D01*
X756600D01*
Y473400D01*
G01X750400Y480600D02*
X756600D01*
Y477400D01*
X750400D01*
Y480600D01*
G01X755883Y487000D02*
Y490100D01*
X756842D01*
X757148Y489945D01*
X757340Y489738D01*
X757417Y489325D01*
X757340Y488912D01*
X757110Y488653D01*
X756842Y488498D01*
X755883D01*
G01X756842D02*
X757417Y487000D01*
G01X759750D02*
Y490100D01*
X759290Y489480D01*
G01Y487000D02*
X760210D01*
G01X762122Y489583D02*
X762352Y489893D01*
X762620Y490048D01*
X762927Y490100D01*
X763310Y489997D01*
X763578Y489738D01*
X763655Y489428D01*
X763617Y489118D01*
X763463Y488860D01*
X762697Y488343D01*
X762352Y487982D01*
X762122Y487465D01*
X762045Y487000D01*
X763655D01*
G01X765222Y488292D02*
X765490Y488653D01*
X765720Y488860D01*
X766027Y488963D01*
X766295Y488860D01*
X766487Y488653D01*
X766640Y488343D01*
X766678Y487982D01*
X766640Y487672D01*
X766487Y487362D01*
X766257Y487103D01*
X765988Y487000D01*
X765682Y487103D01*
X765413Y487413D01*
X765260Y487878D01*
X765222Y488395D01*
X765298Y489067D01*
X765413Y489428D01*
X765605Y489790D01*
X765873Y490048D01*
X766142Y490100D01*
X766410Y489997D01*
X766602Y489738D01*
G01X768973Y487000D02*
X769050Y487672D01*
X769165Y488240D01*
X769318Y488757D01*
X769510Y489325D01*
X769817Y490100D01*
X768283D01*
G01X762584Y503259D02*
X762204Y503509D01*
X761761Y503676D01*
X761254D01*
X760684Y503426D01*
X760241Y503009D01*
X759924Y502509D01*
X759671Y501676D01*
X759608Y500926D01*
X759734Y500176D01*
X759924Y499676D01*
X760304Y499176D01*
X760748Y498843D01*
X761191Y498676D01*
X761634D01*
X762078Y498843D01*
X762458Y499093D01*
X762774Y499426D01*
G01X765024Y498676D02*
Y503676D01*
X766544D01*
X767051Y503426D01*
X767431Y502843D01*
X767558Y502176D01*
X767431Y501509D01*
X767114Y501009D01*
X766544Y500759D01*
X765024D01*
G01X770124Y503676D02*
Y498676D01*
X772658D01*
G01X775098D02*
Y503676D01*
X776364D01*
X776871Y503426D01*
X777251Y503093D01*
X777568Y502593D01*
X777821Y502009D01*
X777884Y501176D01*
X777821Y500343D01*
X777568Y499759D01*
X777251Y499259D01*
X776871Y498926D01*
X776364Y498676D01*
X775098D01*
G01X781591D02*
Y503676D01*
X780831Y502676D01*
G01Y498676D02*
X782351D01*
G01X749197Y501500D02*
Y506500D01*
X751603D01*
G01X750717Y504083D02*
X749197D01*
G01X760694Y505474D02*
X783895D01*
Y496512D01*
X757947D01*
Y505474D01*
X760694D01*
G01X756763Y498630D02*
X750080D01*
Y498651D01*
X752273Y500844D01*
X752294Y500823D01*
Y495995D01*
X750059Y498230D01*
Y498567D01*
G01X747500Y507500D02*
X752500D01*
Y501500D01*
X747500D01*
G01X755883Y491500D02*
Y494600D01*
X756842D01*
X757148Y494445D01*
X757340Y494238D01*
X757417Y493825D01*
X757340Y493412D01*
X757110Y493153D01*
X756842Y492998D01*
X755883D01*
G01X756842D02*
X757417Y491500D01*
G01X759750D02*
Y494600D01*
X759290Y493980D01*
G01Y491500D02*
X760210D01*
G01X762122Y494083D02*
X762352Y494393D01*
X762620Y494548D01*
X762927Y494600D01*
X763310Y494497D01*
X763578Y494238D01*
X763655Y493928D01*
X763617Y493618D01*
X763463Y493360D01*
X762697Y492843D01*
X762352Y492482D01*
X762122Y491965D01*
X762045Y491500D01*
X763655D01*
G01X765873D02*
X765950Y492172D01*
X766065Y492740D01*
X766218Y493257D01*
X766410Y493825D01*
X766717Y494600D01*
X765183D01*
G01X769050D02*
X768743Y494497D01*
X768513Y494238D01*
X768360Y493928D01*
X768245Y493515D01*
X768207Y493050D01*
X768245Y492585D01*
X768360Y492172D01*
X768513Y491862D01*
X768743Y491603D01*
X769050Y491500D01*
X769357Y491603D01*
X769587Y491862D01*
X769740Y492172D01*
X769855Y492585D01*
X769893Y493050D01*
X769855Y493515D01*
X769740Y493928D01*
X769587Y494238D01*
X769357Y494497D01*
X769050Y494600D01*
G01X753600Y490900D02*
X747400D01*
Y494100D01*
X753600D01*
Y490900D01*
G01X747400Y490100D02*
X753600D01*
Y486900D01*
X747400D01*
Y490100D01*
G01X761197Y510398D02*
Y513498D01*
X762156D01*
X762462Y513343D01*
X762654Y513136D01*
X762731Y512723D01*
X762654Y512310D01*
X762424Y512051D01*
X762156Y511896D01*
X761197D01*
G01X762156D02*
X762731Y510398D01*
G01X765064D02*
Y513498D01*
X764604Y512878D01*
G01Y510398D02*
X765524D01*
G01X768164Y513498D02*
X767857Y513395D01*
X767627Y513136D01*
X767474Y512826D01*
X767359Y512413D01*
X767321Y511948D01*
X767359Y511483D01*
X767474Y511070D01*
X767627Y510760D01*
X767857Y510501D01*
X768164Y510398D01*
X768471Y510501D01*
X768701Y510760D01*
X768854Y511070D01*
X768969Y511483D01*
X769007Y511948D01*
X768969Y512413D01*
X768854Y512826D01*
X768701Y513136D01*
X768471Y513395D01*
X768164Y513498D01*
G01X771724Y510398D02*
Y513498D01*
X770306Y511276D01*
X772222D01*
G01X773636Y511690D02*
X773904Y512051D01*
X774134Y512258D01*
X774441Y512361D01*
X774709Y512258D01*
X774901Y512051D01*
X775054Y511741D01*
X775092Y511380D01*
X775054Y511070D01*
X774901Y510760D01*
X774671Y510501D01*
X774402Y510398D01*
X774096Y510501D01*
X773827Y510811D01*
X773674Y511276D01*
X773636Y511793D01*
X773712Y512465D01*
X773827Y512826D01*
X774019Y513188D01*
X774287Y513446D01*
X774556Y513498D01*
X774824Y513395D01*
X775016Y513136D01*
G01X764169Y521627D02*
X764117Y521320D01*
X763911Y521052D01*
X763601Y520822D01*
X763239Y520669D01*
X762826Y520592D01*
X762412D01*
X761999Y520669D01*
X761637Y520822D01*
X761327Y521052D01*
X761121Y521320D01*
X761069Y521627D01*
X761121Y521934D01*
X761327Y522202D01*
X761637Y522432D01*
X761999Y522585D01*
X762412Y522662D01*
X762826D01*
X763239Y522585D01*
X763601Y522432D01*
X763911Y522202D01*
X764117Y521934D01*
X764169Y521627D01*
G01X763342Y521934D02*
X764169Y522394D01*
G01X761586Y523999D02*
X761276Y524229D01*
X761121Y524497D01*
X761069Y524804D01*
X761172Y525187D01*
X761431Y525455D01*
X761741Y525532D01*
X762051Y525494D01*
X762309Y525340D01*
X762826Y524574D01*
X763187Y524229D01*
X763704Y523999D01*
X764169Y523922D01*
Y525532D01*
G01X763704Y526984D02*
X763962Y527214D01*
X764117Y527482D01*
X764169Y527827D01*
X764066Y528172D01*
X763859Y528440D01*
X763497Y528632D01*
X763084Y528670D01*
X762671Y528594D01*
X762412Y528402D01*
X762206Y528134D01*
X762154Y527865D01*
X762206Y527597D01*
X762412Y527252D01*
X761069Y527367D01*
Y528402D01*
G01X760409Y561013D02*
Y558013D01*
G01X763509Y557913D02*
X757309D01*
G01D02*
Y561113D01*
G01D02*
X763509D01*
G01X755307Y562265D02*
Y566865D01*
G01X760407Y562265D02*
Y566865D01*
G01X765507Y562265D02*
X755307D01*
G01X755414Y568168D02*
Y572768D01*
G01X760514Y568168D02*
Y572768D01*
G01X765614Y568168D02*
X755414D01*
G01Y572768D02*
X765614D01*
G01X755307Y566865D02*
X765507D01*
G01X755177Y574264D02*
Y581064D01*
G01X770177Y574264D02*
X755177D01*
G01X755168Y582387D02*
Y589187D01*
G01X770168Y582387D02*
X755168D01*
G01Y589187D02*
X770168D01*
G01X755177Y581064D02*
X770177D01*
G01X752108Y642375D02*
X751953Y642145D01*
X751850Y641877D01*
Y641570D01*
X752005Y641225D01*
X752263Y640957D01*
X752573Y640765D01*
X753090Y640612D01*
X753555Y640574D01*
X754020Y640650D01*
X754330Y640765D01*
X754640Y640995D01*
X754847Y641264D01*
X754950Y641532D01*
Y641800D01*
X754847Y642069D01*
X754692Y642299D01*
X754485Y642490D01*
G01Y643789D02*
X754743Y644019D01*
X754898Y644287D01*
X754950Y644632D01*
X754847Y644977D01*
X754640Y645245D01*
X754278Y645437D01*
X753865Y645475D01*
X753452Y645399D01*
X753193Y645207D01*
X752987Y644939D01*
X752935Y644670D01*
X752987Y644402D01*
X753193Y644057D01*
X751850Y644172D01*
Y645207D01*
G01X754950Y648192D02*
X751850D01*
X754072Y646774D01*
Y648690D01*
G01X754950Y650832D02*
X751850D01*
X752470Y650372D01*
G01X754950D02*
Y651292D01*
G01X751139Y656172D02*
Y638772D01*
G01X762983Y638700D02*
Y641800D01*
X763942D01*
X764248Y641645D01*
X764440Y641438D01*
X764517Y641025D01*
X764440Y640612D01*
X764210Y640353D01*
X763942Y640198D01*
X762983D01*
G01X763942D02*
X764517Y638700D01*
G01X766850D02*
Y641800D01*
X766390Y641180D01*
G01Y638700D02*
X767310D01*
G01X769107Y639320D02*
X769337Y638958D01*
X769643Y638752D01*
X769988Y638700D01*
X770295Y638752D01*
X770602Y639010D01*
X770793Y639320D01*
X770832Y639630D01*
X770755Y639992D01*
X770487Y640250D01*
X770218Y640353D01*
X769873D01*
G01X770218D02*
X770448Y640508D01*
X770640Y640767D01*
X770717Y641077D01*
X770640Y641387D01*
X770448Y641645D01*
X770103Y641800D01*
X769758Y641748D01*
X769413Y641542D01*
G01X773050Y638700D02*
Y641800D01*
X772590Y641180D01*
G01Y638700D02*
X773510D01*
G01X776150D02*
X776418Y638752D01*
X776725Y638907D01*
X776917Y639165D01*
X776993Y639527D01*
X776917Y639888D01*
X776687Y640198D01*
X776342Y640353D01*
X775958D01*
X775728Y640457D01*
X775537Y640715D01*
X775460Y641077D01*
X775575Y641438D01*
X775843Y641697D01*
X776150Y641800D01*
X776457Y641697D01*
X776725Y641438D01*
X776840Y641077D01*
X776763Y640715D01*
X776572Y640457D01*
X776342Y640353D01*
X775958D01*
X775613Y640198D01*
X775383Y639888D01*
X775307Y639527D01*
X775383Y639165D01*
X775575Y638907D01*
X775882Y638752D01*
X776150Y638700D01*
G01X762983Y643000D02*
Y646100D01*
X763942D01*
X764248Y645945D01*
X764440Y645738D01*
X764517Y645325D01*
X764440Y644912D01*
X764210Y644653D01*
X763942Y644498D01*
X762983D01*
G01X763942D02*
X764517Y643000D01*
G01X766850D02*
Y646100D01*
X766390Y645480D01*
G01Y643000D02*
X767310D01*
G01X769107Y643620D02*
X769337Y643258D01*
X769643Y643052D01*
X769988Y643000D01*
X770295Y643052D01*
X770602Y643310D01*
X770793Y643620D01*
X770832Y643930D01*
X770755Y644292D01*
X770487Y644550D01*
X770218Y644653D01*
X769873D01*
G01X770218D02*
X770448Y644808D01*
X770640Y645067D01*
X770717Y645377D01*
X770640Y645687D01*
X770448Y645945D01*
X770103Y646100D01*
X769758Y646048D01*
X769413Y645842D01*
G01X772322Y645583D02*
X772552Y645893D01*
X772820Y646048D01*
X773127Y646100D01*
X773510Y645997D01*
X773778Y645738D01*
X773855Y645428D01*
X773817Y645118D01*
X773663Y644860D01*
X772897Y644343D01*
X772552Y643982D01*
X772322Y643465D01*
X772245Y643000D01*
X773855D01*
G01X776150D02*
Y646100D01*
X775690Y645480D01*
G01Y643000D02*
X776610D01*
G01X762883Y647100D02*
Y650200D01*
X763842D01*
X764148Y650045D01*
X764340Y649838D01*
X764417Y649425D01*
X764340Y649012D01*
X764110Y648753D01*
X763842Y648598D01*
X762883D01*
G01X763842D02*
X764417Y647100D01*
G01X766750D02*
Y650200D01*
X766290Y649580D01*
G01Y647100D02*
X767210D01*
G01X769007Y647720D02*
X769237Y647358D01*
X769543Y647152D01*
X769888Y647100D01*
X770195Y647152D01*
X770502Y647410D01*
X770693Y647720D01*
X770732Y648030D01*
X770655Y648392D01*
X770387Y648650D01*
X770118Y648753D01*
X769773D01*
G01X770118D02*
X770348Y648908D01*
X770540Y649167D01*
X770617Y649477D01*
X770540Y649787D01*
X770348Y650045D01*
X770003Y650200D01*
X769658Y650148D01*
X769313Y649942D01*
G01X772222Y649683D02*
X772452Y649993D01*
X772720Y650148D01*
X773027Y650200D01*
X773410Y650097D01*
X773678Y649838D01*
X773755Y649528D01*
X773717Y649218D01*
X773563Y648960D01*
X772797Y648443D01*
X772452Y648082D01*
X772222Y647565D01*
X772145Y647100D01*
X773755D01*
G01X776050Y650200D02*
X775743Y650097D01*
X775513Y649838D01*
X775360Y649528D01*
X775245Y649115D01*
X775207Y648650D01*
X775245Y648185D01*
X775360Y647772D01*
X775513Y647462D01*
X775743Y647203D01*
X776050Y647100D01*
X776357Y647203D01*
X776587Y647462D01*
X776740Y647772D01*
X776855Y648185D01*
X776893Y648650D01*
X776855Y649115D01*
X776740Y649528D01*
X776587Y649838D01*
X776357Y650097D01*
X776050Y650200D01*
G01X769879Y207285D02*
Y200602D01*
X769858D01*
X767665Y202795D01*
X767686Y202816D01*
X772514D01*
X770279Y200581D01*
X769942D01*
G01X772187Y357887D02*
Y355665D01*
X772340Y355200D01*
X772647Y354890D01*
X773030Y354787D01*
X773413Y354890D01*
X773720Y355200D01*
X773873Y355665D01*
Y357887D01*
G01X776130Y354787D02*
Y357887D01*
X775670Y357267D01*
G01Y354787D02*
X776590D01*
G01X778502Y357370D02*
X778732Y357680D01*
X779000Y357835D01*
X779307Y357887D01*
X779690Y357784D01*
X779958Y357525D01*
X780035Y357215D01*
X779997Y356905D01*
X779843Y356647D01*
X779077Y356130D01*
X778732Y355769D01*
X778502Y355252D01*
X778425Y354787D01*
X780035D01*
G01X781602Y356079D02*
X781870Y356440D01*
X782100Y356647D01*
X782407Y356750D01*
X782675Y356647D01*
X782867Y356440D01*
X783020Y356130D01*
X783058Y355769D01*
X783020Y355459D01*
X782867Y355149D01*
X782637Y354890D01*
X782368Y354787D01*
X782062Y354890D01*
X781793Y355200D01*
X781640Y355665D01*
X781602Y356182D01*
X781678Y356854D01*
X781793Y357215D01*
X781985Y357577D01*
X782253Y357835D01*
X782522Y357887D01*
X782790Y357784D01*
X782982Y357525D01*
G01X768617Y378726D02*
Y376504D01*
X768770Y376039D01*
X769077Y375729D01*
X769460Y375626D01*
X769843Y375729D01*
X770150Y376039D01*
X770303Y376504D01*
Y378726D01*
G01X771832Y376918D02*
X772100Y377279D01*
X772330Y377486D01*
X772637Y377589D01*
X772905Y377486D01*
X773097Y377279D01*
X773250Y376969D01*
X773288Y376608D01*
X773250Y376298D01*
X773097Y375988D01*
X772867Y375729D01*
X772598Y375626D01*
X772292Y375729D01*
X772023Y376039D01*
X771870Y376504D01*
X771832Y377021D01*
X771908Y377693D01*
X772023Y378054D01*
X772215Y378416D01*
X772483Y378674D01*
X772752Y378726D01*
X773020Y378623D01*
X773212Y378364D01*
G01X775660Y375626D02*
X775928Y375678D01*
X776235Y375833D01*
X776427Y376091D01*
X776503Y376453D01*
X776427Y376814D01*
X776197Y377124D01*
X775852Y377279D01*
X775468D01*
X775238Y377383D01*
X775047Y377641D01*
X774970Y378003D01*
X775085Y378364D01*
X775353Y378623D01*
X775660Y378726D01*
X775967Y378623D01*
X776235Y378364D01*
X776350Y378003D01*
X776273Y377641D01*
X776082Y377383D01*
X775852Y377279D01*
X775468D01*
X775123Y377124D01*
X774893Y376814D01*
X774817Y376453D01*
X774893Y376091D01*
X775085Y375833D01*
X775392Y375678D01*
X775660Y375626D01*
G01X767993Y362727D02*
Y365827D01*
X768952D01*
X769258Y365672D01*
X769450Y365465D01*
X769527Y365052D01*
X769450Y364639D01*
X769220Y364380D01*
X768952Y364225D01*
X767993D01*
G01X768952D02*
X769527Y362727D01*
G01X771132Y364019D02*
X771400Y364380D01*
X771630Y364587D01*
X771937Y364690D01*
X772205Y364587D01*
X772397Y364380D01*
X772550Y364070D01*
X772588Y363709D01*
X772550Y363399D01*
X772397Y363089D01*
X772167Y362830D01*
X771898Y362727D01*
X771592Y362830D01*
X771323Y363140D01*
X771170Y363605D01*
X771132Y364122D01*
X771208Y364794D01*
X771323Y365155D01*
X771515Y365517D01*
X771783Y365775D01*
X772052Y365827D01*
X772320Y365724D01*
X772512Y365465D01*
G01X775420Y362727D02*
Y365827D01*
X774002Y363605D01*
X775918D01*
G01X777332Y364019D02*
X777600Y364380D01*
X777830Y364587D01*
X778137Y364690D01*
X778405Y364587D01*
X778597Y364380D01*
X778750Y364070D01*
X778788Y363709D01*
X778750Y363399D01*
X778597Y363089D01*
X778367Y362830D01*
X778098Y362727D01*
X777792Y362830D01*
X777523Y363140D01*
X777370Y363605D01*
X777332Y364122D01*
X777408Y364794D01*
X777523Y365155D01*
X777715Y365517D01*
X777983Y365775D01*
X778252Y365827D01*
X778520Y365724D01*
X778712Y365465D01*
G01X768853Y371697D02*
Y374797D01*
X769812D01*
X770118Y374642D01*
X770310Y374435D01*
X770387Y374022D01*
X770310Y373609D01*
X770080Y373350D01*
X769812Y373195D01*
X768853D01*
G01X769812D02*
X770387Y371697D01*
G01X772643D02*
X772720Y372369D01*
X772835Y372937D01*
X772988Y373454D01*
X773180Y374022D01*
X773487Y374797D01*
X771953D01*
G01X774977Y372162D02*
X775207Y371904D01*
X775475Y371749D01*
X775820Y371697D01*
X776165Y371800D01*
X776433Y372007D01*
X776625Y372369D01*
X776663Y372782D01*
X776587Y373195D01*
X776395Y373454D01*
X776127Y373660D01*
X775858Y373712D01*
X775590Y373660D01*
X775245Y373454D01*
X775360Y374797D01*
X776395D01*
G01X778268Y372059D02*
X778537Y371800D01*
X778843Y371697D01*
X779150Y371800D01*
X779418Y372110D01*
X779610Y372575D01*
X779687Y373040D01*
Y373609D01*
X779610Y374074D01*
X779418Y374487D01*
X779188Y374694D01*
X778920Y374797D01*
X778613Y374694D01*
X778383Y374487D01*
X778230Y374177D01*
X778153Y373764D01*
X778230Y373402D01*
X778422Y373040D01*
X778652Y372834D01*
X778920Y372782D01*
X779227Y372885D01*
X779457Y373144D01*
X779687Y373609D01*
G01X769383Y421000D02*
Y424100D01*
X770342D01*
X770648Y423945D01*
X770840Y423738D01*
X770917Y423325D01*
X770840Y422912D01*
X770610Y422653D01*
X770342Y422498D01*
X769383D01*
G01X770342D02*
X770917Y421000D01*
G01X773250D02*
Y424100D01*
X772790Y423480D01*
G01Y421000D02*
X773710D01*
G01X775622Y423583D02*
X775852Y423893D01*
X776120Y424048D01*
X776427Y424100D01*
X776810Y423997D01*
X777078Y423738D01*
X777155Y423428D01*
X777117Y423118D01*
X776963Y422860D01*
X776197Y422343D01*
X775852Y421982D01*
X775622Y421465D01*
X775545Y421000D01*
X777155D01*
G01X778722Y422292D02*
X778990Y422653D01*
X779220Y422860D01*
X779527Y422963D01*
X779795Y422860D01*
X779987Y422653D01*
X780140Y422343D01*
X780178Y421982D01*
X780140Y421672D01*
X779987Y421362D01*
X779757Y421103D01*
X779488Y421000D01*
X779182Y421103D01*
X778913Y421413D01*
X778760Y421878D01*
X778722Y422395D01*
X778798Y423067D01*
X778913Y423428D01*
X779105Y423790D01*
X779373Y424048D01*
X779642Y424100D01*
X779910Y423997D01*
X780102Y423738D01*
G01X781898Y421362D02*
X782167Y421103D01*
X782473Y421000D01*
X782780Y421103D01*
X783048Y421413D01*
X783240Y421878D01*
X783317Y422343D01*
Y422912D01*
X783240Y423377D01*
X783048Y423790D01*
X782818Y423997D01*
X782550Y424100D01*
X782243Y423997D01*
X782013Y423790D01*
X781860Y423480D01*
X781783Y423067D01*
X781860Y422705D01*
X782052Y422343D01*
X782282Y422137D01*
X782550Y422085D01*
X782857Y422188D01*
X783087Y422447D01*
X783317Y422912D01*
G01X766383Y416500D02*
Y419600D01*
X767342D01*
X767648Y419445D01*
X767840Y419238D01*
X767917Y418825D01*
X767840Y418412D01*
X767610Y418153D01*
X767342Y417998D01*
X766383D01*
G01X767342D02*
X767917Y416500D01*
G01X770250D02*
Y419600D01*
X769790Y418980D01*
G01Y416500D02*
X770710D01*
G01X772622Y419083D02*
X772852Y419393D01*
X773120Y419548D01*
X773427Y419600D01*
X773810Y419497D01*
X774078Y419238D01*
X774155Y418928D01*
X774117Y418618D01*
X773963Y418360D01*
X773197Y417843D01*
X772852Y417482D01*
X772622Y416965D01*
X772545Y416500D01*
X774155D01*
G01X776450D02*
X776718Y416552D01*
X777025Y416707D01*
X777217Y416965D01*
X777293Y417327D01*
X777217Y417688D01*
X776987Y417998D01*
X776642Y418153D01*
X776258D01*
X776028Y418257D01*
X775837Y418515D01*
X775760Y418877D01*
X775875Y419238D01*
X776143Y419497D01*
X776450Y419600D01*
X776757Y419497D01*
X777025Y419238D01*
X777140Y418877D01*
X777063Y418515D01*
X776872Y418257D01*
X776642Y418153D01*
X776258D01*
X775913Y417998D01*
X775683Y417688D01*
X775607Y417327D01*
X775683Y416965D01*
X775875Y416707D01*
X776182Y416552D01*
X776450Y416500D01*
G01X779473D02*
X779550Y417172D01*
X779665Y417740D01*
X779818Y418257D01*
X780010Y418825D01*
X780317Y419600D01*
X778783D01*
G01X769383Y425500D02*
Y428600D01*
X770342D01*
X770648Y428445D01*
X770840Y428238D01*
X770917Y427825D01*
X770840Y427412D01*
X770610Y427153D01*
X770342Y426998D01*
X769383D01*
G01X770342D02*
X770917Y425500D01*
G01X773250D02*
Y428600D01*
X772790Y427980D01*
G01Y425500D02*
X773710D01*
G01X775622Y428083D02*
X775852Y428393D01*
X776120Y428548D01*
X776427Y428600D01*
X776810Y428497D01*
X777078Y428238D01*
X777155Y427928D01*
X777117Y427618D01*
X776963Y427360D01*
X776197Y426843D01*
X775852Y426482D01*
X775622Y425965D01*
X775545Y425500D01*
X777155D01*
G01X778722Y426792D02*
X778990Y427153D01*
X779220Y427360D01*
X779527Y427463D01*
X779795Y427360D01*
X779987Y427153D01*
X780140Y426843D01*
X780178Y426482D01*
X780140Y426172D01*
X779987Y425862D01*
X779757Y425603D01*
X779488Y425500D01*
X779182Y425603D01*
X778913Y425913D01*
X778760Y426378D01*
X778722Y426895D01*
X778798Y427567D01*
X778913Y427928D01*
X779105Y428290D01*
X779373Y428548D01*
X779642Y428600D01*
X779910Y428497D01*
X780102Y428238D01*
G01X782550Y425500D02*
X782818Y425552D01*
X783125Y425707D01*
X783317Y425965D01*
X783393Y426327D01*
X783317Y426688D01*
X783087Y426998D01*
X782742Y427153D01*
X782358D01*
X782128Y427257D01*
X781937Y427515D01*
X781860Y427877D01*
X781975Y428238D01*
X782243Y428497D01*
X782550Y428600D01*
X782857Y428497D01*
X783125Y428238D01*
X783240Y427877D01*
X783163Y427515D01*
X782972Y427257D01*
X782742Y427153D01*
X782358D01*
X782013Y426998D01*
X781783Y426688D01*
X781707Y426327D01*
X781783Y425965D01*
X781975Y425707D01*
X782282Y425552D01*
X782550Y425500D01*
G01X779012Y510418D02*
X775912D01*
Y511377D01*
X776067Y511683D01*
X776274Y511875D01*
X776687Y511952D01*
X777100Y511875D01*
X777359Y511645D01*
X777514Y511377D01*
Y510418D01*
G01Y511377D02*
X779012Y511952D01*
G01Y514285D02*
X775912D01*
X776532Y513825D01*
G01X779012D02*
Y514745D01*
G01Y517385D02*
X775912D01*
X776532Y516925D01*
G01X779012D02*
Y517845D01*
G01X776429Y519757D02*
X776119Y519987D01*
X775964Y520255D01*
X775912Y520562D01*
X776015Y520945D01*
X776274Y521213D01*
X776584Y521290D01*
X776894Y521252D01*
X777152Y521098D01*
X777669Y520332D01*
X778030Y519987D01*
X778547Y519757D01*
X779012Y519680D01*
Y521290D01*
G01Y523585D02*
X775912D01*
X776532Y523125D01*
G01X779012D02*
Y524045D01*
G01X770771Y521664D02*
X770719Y521357D01*
X770513Y521089D01*
X770203Y520859D01*
X769841Y520706D01*
X769428Y520629D01*
X769014D01*
X768601Y520706D01*
X768239Y520859D01*
X767929Y521089D01*
X767723Y521357D01*
X767671Y521664D01*
X767723Y521971D01*
X767929Y522239D01*
X768239Y522469D01*
X768601Y522622D01*
X769014Y522699D01*
X769428D01*
X769841Y522622D01*
X770203Y522469D01*
X770513Y522239D01*
X770719Y521971D01*
X770771Y521664D01*
G01X769944Y521971D02*
X770771Y522431D01*
G01X768188Y524036D02*
X767878Y524266D01*
X767723Y524534D01*
X767671Y524841D01*
X767774Y525224D01*
X768033Y525492D01*
X768343Y525569D01*
X768653Y525531D01*
X768911Y525377D01*
X769428Y524611D01*
X769789Y524266D01*
X770306Y524036D01*
X770771Y523959D01*
Y525569D01*
G01Y527787D02*
X770099Y527864D01*
X769531Y527979D01*
X769014Y528132D01*
X768446Y528324D01*
X767671Y528631D01*
Y527097D01*
G01X770482Y559141D02*
X770252Y559296D01*
X769984Y559399D01*
X769677D01*
X769332Y559244D01*
X769064Y558986D01*
X768872Y558676D01*
X768719Y558159D01*
X768681Y557694D01*
X768757Y557229D01*
X768872Y556919D01*
X769102Y556609D01*
X769371Y556402D01*
X769639Y556299D01*
X769907D01*
X770176Y556402D01*
X770406Y556557D01*
X770597Y556764D01*
G01X773199Y556299D02*
Y559399D01*
X771781Y557177D01*
X773697D01*
G01X775111Y557591D02*
X775379Y557952D01*
X775609Y558159D01*
X775916Y558262D01*
X776184Y558159D01*
X776376Y557952D01*
X776529Y557642D01*
X776567Y557281D01*
X776529Y556971D01*
X776376Y556661D01*
X776146Y556402D01*
X775877Y556299D01*
X775571Y556402D01*
X775302Y556712D01*
X775149Y557177D01*
X775111Y557694D01*
X775187Y558366D01*
X775302Y558727D01*
X775494Y559089D01*
X775762Y559347D01*
X776031Y559399D01*
X776299Y559296D01*
X776491Y559037D01*
G01X778939Y559399D02*
X778632Y559296D01*
X778402Y559037D01*
X778249Y558727D01*
X778134Y558314D01*
X778096Y557849D01*
X778134Y557384D01*
X778249Y556971D01*
X778402Y556661D01*
X778632Y556402D01*
X778939Y556299D01*
X779246Y556402D01*
X779476Y556661D01*
X779629Y556971D01*
X779744Y557384D01*
X779782Y557849D01*
X779744Y558314D01*
X779629Y558727D01*
X779476Y559037D01*
X779246Y559296D01*
X778939Y559399D01*
G01X763509Y561113D02*
Y557913D01*
G01X771796Y565466D02*
X771566Y565621D01*
X771298Y565724D01*
X770991D01*
X770646Y565569D01*
X770378Y565311D01*
X770186Y565001D01*
X770033Y564484D01*
X769995Y564019D01*
X770071Y563554D01*
X770186Y563244D01*
X770416Y562934D01*
X770685Y562727D01*
X770953Y562624D01*
X771221D01*
X771490Y562727D01*
X771720Y562882D01*
X771911Y563089D01*
G01X774513Y562624D02*
Y565724D01*
X773095Y563502D01*
X775011D01*
G01X777076Y562624D02*
X777153Y563296D01*
X777268Y563864D01*
X777421Y564381D01*
X777613Y564949D01*
X777920Y565724D01*
X776386D01*
G01X779525Y563916D02*
X779793Y564277D01*
X780023Y564484D01*
X780330Y564587D01*
X780598Y564484D01*
X780790Y564277D01*
X780943Y563967D01*
X780981Y563606D01*
X780943Y563296D01*
X780790Y562986D01*
X780560Y562727D01*
X780291Y562624D01*
X779985Y562727D01*
X779716Y563037D01*
X779563Y563502D01*
X779525Y564019D01*
X779601Y564691D01*
X779716Y565052D01*
X779908Y565414D01*
X780176Y565672D01*
X780445Y565724D01*
X780713Y565621D01*
X780905Y565362D01*
G01X765507Y566865D02*
Y562265D01*
G01X771772Y572833D02*
X771542Y572988D01*
X771274Y573091D01*
X770967D01*
X770622Y572936D01*
X770354Y572678D01*
X770162Y572368D01*
X770009Y571851D01*
X769971Y571386D01*
X770047Y570921D01*
X770162Y570611D01*
X770392Y570301D01*
X770661Y570094D01*
X770929Y569991D01*
X771197D01*
X771466Y570094D01*
X771696Y570249D01*
X771887Y570456D01*
G01X774489Y569991D02*
Y573091D01*
X773071Y570869D01*
X774987D01*
G01X777052Y569991D02*
X777129Y570663D01*
X777244Y571231D01*
X777397Y571748D01*
X777589Y572316D01*
X777896Y573091D01*
X776362D01*
G01X779386Y570456D02*
X779616Y570198D01*
X779884Y570043D01*
X780229Y569991D01*
X780574Y570094D01*
X780842Y570301D01*
X781034Y570663D01*
X781072Y571076D01*
X780996Y571489D01*
X780804Y571748D01*
X780536Y571954D01*
X780267Y572006D01*
X779999Y571954D01*
X779654Y571748D01*
X779769Y573091D01*
X780804D01*
G01X765614Y572768D02*
Y568168D01*
G01X774012Y581802D02*
X773782Y581957D01*
X773514Y582060D01*
X773207D01*
X772862Y581905D01*
X772594Y581647D01*
X772402Y581337D01*
X772249Y580820D01*
X772211Y580355D01*
X772287Y579890D01*
X772402Y579580D01*
X772632Y579270D01*
X772901Y579063D01*
X773169Y578960D01*
X773437D01*
X773706Y579063D01*
X773936Y579218D01*
X774127Y579425D01*
G01X776729Y578960D02*
Y582060D01*
X775311Y579838D01*
X777227D01*
G01X779292Y578960D02*
X779369Y579632D01*
X779484Y580200D01*
X779637Y580717D01*
X779829Y581285D01*
X780136Y582060D01*
X778602D01*
G01X782929Y578960D02*
Y582060D01*
X781511Y579838D01*
X783427D01*
G01X762677Y580964D02*
Y574364D01*
G01X770177Y581064D02*
Y574264D01*
G01X773942Y587597D02*
X773712Y587752D01*
X773444Y587855D01*
X773137D01*
X772792Y587700D01*
X772524Y587442D01*
X772332Y587132D01*
X772179Y586615D01*
X772141Y586150D01*
X772217Y585685D01*
X772332Y585375D01*
X772562Y585065D01*
X772831Y584858D01*
X773099Y584755D01*
X773367D01*
X773636Y584858D01*
X773866Y585013D01*
X774057Y585220D01*
G01X776659Y584755D02*
Y587855D01*
X775241Y585633D01*
X777157D01*
G01X779222Y584755D02*
X779299Y585427D01*
X779414Y585995D01*
X779567Y586512D01*
X779759Y587080D01*
X780066Y587855D01*
X778532D01*
G01X781556Y585375D02*
X781786Y585013D01*
X782092Y584807D01*
X782437Y584755D01*
X782744Y584807D01*
X783051Y585065D01*
X783242Y585375D01*
X783281Y585685D01*
X783204Y586047D01*
X782936Y586305D01*
X782667Y586408D01*
X782322D01*
G01X782667D02*
X782897Y586563D01*
X783089Y586822D01*
X783166Y587132D01*
X783089Y587442D01*
X782897Y587700D01*
X782552Y587855D01*
X782207Y587803D01*
X781862Y587597D01*
G01X762668Y589087D02*
Y582487D01*
G01X770168Y589187D02*
Y582387D01*
G01X766883Y612700D02*
Y615800D01*
X767842D01*
X768148Y615645D01*
X768340Y615438D01*
X768417Y615025D01*
X768340Y614612D01*
X768110Y614353D01*
X767842Y614198D01*
X766883D01*
G01X767842D02*
X768417Y612700D01*
G01X770750D02*
Y615800D01*
X770290Y615180D01*
G01Y612700D02*
X771210D01*
G01X773850Y615800D02*
X773543Y615697D01*
X773313Y615438D01*
X773160Y615128D01*
X773045Y614715D01*
X773007Y614250D01*
X773045Y613785D01*
X773160Y613372D01*
X773313Y613062D01*
X773543Y612803D01*
X773850Y612700D01*
X774157Y612803D01*
X774387Y613062D01*
X774540Y613372D01*
X774655Y613785D01*
X774693Y614250D01*
X774655Y614715D01*
X774540Y615128D01*
X774387Y615438D01*
X774157Y615697D01*
X773850Y615800D01*
G01X776873Y612700D02*
X776950Y613372D01*
X777065Y613940D01*
X777218Y614457D01*
X777410Y615025D01*
X777717Y615800D01*
X776183D01*
G01X779207Y613320D02*
X779437Y612958D01*
X779743Y612752D01*
X780088Y612700D01*
X780395Y612752D01*
X780702Y613010D01*
X780893Y613320D01*
X780932Y613630D01*
X780855Y613992D01*
X780587Y614250D01*
X780318Y614353D01*
X779973D01*
G01X780318D02*
X780548Y614508D01*
X780740Y614767D01*
X780817Y615077D01*
X780740Y615387D01*
X780548Y615645D01*
X780203Y615800D01*
X779858Y615748D01*
X779513Y615542D01*
G01X766983Y628700D02*
Y631800D01*
X767942D01*
X768248Y631645D01*
X768440Y631438D01*
X768517Y631025D01*
X768440Y630612D01*
X768210Y630353D01*
X767942Y630198D01*
X766983D01*
G01X767942D02*
X768517Y628700D01*
G01X770850D02*
Y631800D01*
X770390Y631180D01*
G01Y628700D02*
X771310D01*
G01X773107Y629320D02*
X773337Y628958D01*
X773643Y628752D01*
X773988Y628700D01*
X774295Y628752D01*
X774602Y629010D01*
X774793Y629320D01*
X774832Y629630D01*
X774755Y629992D01*
X774487Y630250D01*
X774218Y630353D01*
X773873D01*
G01X774218D02*
X774448Y630508D01*
X774640Y630767D01*
X774717Y631077D01*
X774640Y631387D01*
X774448Y631645D01*
X774103Y631800D01*
X773758Y631748D01*
X773413Y631542D01*
G01X777050Y628700D02*
Y631800D01*
X776590Y631180D01*
G01Y628700D02*
X777510D01*
G01X779422Y631283D02*
X779652Y631593D01*
X779920Y631748D01*
X780227Y631800D01*
X780610Y631697D01*
X780878Y631438D01*
X780955Y631128D01*
X780917Y630818D01*
X780763Y630560D01*
X779997Y630043D01*
X779652Y629682D01*
X779422Y629165D01*
X779345Y628700D01*
X780955D01*
G01X766983Y620900D02*
Y624000D01*
X767942D01*
X768248Y623845D01*
X768440Y623638D01*
X768517Y623225D01*
X768440Y622812D01*
X768210Y622553D01*
X767942Y622398D01*
X766983D01*
G01X767942D02*
X768517Y620900D01*
G01X770850D02*
Y624000D01*
X770390Y623380D01*
G01Y620900D02*
X771310D01*
G01X773107Y621520D02*
X773337Y621158D01*
X773643Y620952D01*
X773988Y620900D01*
X774295Y620952D01*
X774602Y621210D01*
X774793Y621520D01*
X774832Y621830D01*
X774755Y622192D01*
X774487Y622450D01*
X774218Y622553D01*
X773873D01*
G01X774218D02*
X774448Y622708D01*
X774640Y622967D01*
X774717Y623277D01*
X774640Y623587D01*
X774448Y623845D01*
X774103Y624000D01*
X773758Y623948D01*
X773413Y623742D01*
G01X777050Y620900D02*
Y624000D01*
X776590Y623380D01*
G01Y620900D02*
X777510D01*
G01X779307Y621520D02*
X779537Y621158D01*
X779843Y620952D01*
X780188Y620900D01*
X780495Y620952D01*
X780802Y621210D01*
X780993Y621520D01*
X781032Y621830D01*
X780955Y622192D01*
X780687Y622450D01*
X780418Y622553D01*
X780073D01*
G01X780418D02*
X780648Y622708D01*
X780840Y622967D01*
X780917Y623277D01*
X780840Y623587D01*
X780648Y623845D01*
X780303Y624000D01*
X779958Y623948D01*
X779613Y623742D01*
G01X766983Y624700D02*
Y627800D01*
X767942D01*
X768248Y627645D01*
X768440Y627438D01*
X768517Y627025D01*
X768440Y626612D01*
X768210Y626353D01*
X767942Y626198D01*
X766983D01*
G01X767942D02*
X768517Y624700D01*
G01X770850D02*
Y627800D01*
X770390Y627180D01*
G01Y624700D02*
X771310D01*
G01X773107Y625320D02*
X773337Y624958D01*
X773643Y624752D01*
X773988Y624700D01*
X774295Y624752D01*
X774602Y625010D01*
X774793Y625320D01*
X774832Y625630D01*
X774755Y625992D01*
X774487Y626250D01*
X774218Y626353D01*
X773873D01*
G01X774218D02*
X774448Y626508D01*
X774640Y626767D01*
X774717Y627077D01*
X774640Y627387D01*
X774448Y627645D01*
X774103Y627800D01*
X773758Y627748D01*
X773413Y627542D01*
G01X777050Y624700D02*
Y627800D01*
X776590Y627180D01*
G01Y624700D02*
X777510D01*
G01X780610D02*
Y627800D01*
X779192Y625578D01*
X781108D01*
G01X767083Y616600D02*
Y619700D01*
X768042D01*
X768348Y619545D01*
X768540Y619338D01*
X768617Y618925D01*
X768540Y618512D01*
X768310Y618253D01*
X768042Y618098D01*
X767083D01*
G01X768042D02*
X768617Y616600D01*
G01X770950D02*
Y619700D01*
X770490Y619080D01*
G01Y616600D02*
X771410D01*
G01X773207Y617220D02*
X773437Y616858D01*
X773743Y616652D01*
X774088Y616600D01*
X774395Y616652D01*
X774702Y616910D01*
X774893Y617220D01*
X774932Y617530D01*
X774855Y617892D01*
X774587Y618150D01*
X774318Y618253D01*
X773973D01*
G01X774318D02*
X774548Y618408D01*
X774740Y618667D01*
X774817Y618977D01*
X774740Y619287D01*
X774548Y619545D01*
X774203Y619700D01*
X773858Y619648D01*
X773513Y619442D01*
G01X777150Y616600D02*
Y619700D01*
X776690Y619080D01*
G01Y616600D02*
X777610D01*
G01X779407Y617065D02*
X779637Y616807D01*
X779905Y616652D01*
X780250Y616600D01*
X780595Y616703D01*
X780863Y616910D01*
X781055Y617272D01*
X781093Y617685D01*
X781017Y618098D01*
X780825Y618357D01*
X780557Y618563D01*
X780288Y618615D01*
X780020Y618563D01*
X779675Y618357D01*
X779790Y619700D01*
X780825D01*
G01X767083Y633200D02*
Y636300D01*
X768042D01*
X768348Y636145D01*
X768540Y635938D01*
X768617Y635525D01*
X768540Y635112D01*
X768310Y634853D01*
X768042Y634698D01*
X767083D01*
G01X768042D02*
X768617Y633200D01*
G01X770950D02*
Y636300D01*
X770490Y635680D01*
G01Y633200D02*
X771410D01*
G01X773207Y633820D02*
X773437Y633458D01*
X773743Y633252D01*
X774088Y633200D01*
X774395Y633252D01*
X774702Y633510D01*
X774893Y633820D01*
X774932Y634130D01*
X774855Y634492D01*
X774587Y634750D01*
X774318Y634853D01*
X773973D01*
G01X774318D02*
X774548Y635008D01*
X774740Y635267D01*
X774817Y635577D01*
X774740Y635887D01*
X774548Y636145D01*
X774203Y636300D01*
X773858Y636248D01*
X773513Y636042D01*
G01X777150Y633200D02*
Y636300D01*
X776690Y635680D01*
G01Y633200D02*
X777610D01*
G01X779522Y634492D02*
X779790Y634853D01*
X780020Y635060D01*
X780327Y635163D01*
X780595Y635060D01*
X780787Y634853D01*
X780940Y634543D01*
X780978Y634182D01*
X780940Y633872D01*
X780787Y633562D01*
X780557Y633303D01*
X780288Y633200D01*
X779982Y633303D01*
X779713Y633613D01*
X779560Y634078D01*
X779522Y634595D01*
X779598Y635267D01*
X779713Y635628D01*
X779905Y635990D01*
X780173Y636248D01*
X780442Y636300D01*
X780710Y636197D01*
X780902Y635938D01*
G01X763383Y659600D02*
Y662700D01*
X764342D01*
X764648Y662545D01*
X764840Y662338D01*
X764917Y661925D01*
X764840Y661512D01*
X764610Y661253D01*
X764342Y661098D01*
X763383D01*
G01X764342D02*
X764917Y659600D01*
G01X767250D02*
Y662700D01*
X766790Y662080D01*
G01Y659600D02*
X767710D01*
G01X769622Y662183D02*
X769852Y662493D01*
X770120Y662648D01*
X770427Y662700D01*
X770810Y662597D01*
X771078Y662338D01*
X771155Y662028D01*
X771117Y661718D01*
X770963Y661460D01*
X770197Y660943D01*
X769852Y660582D01*
X769622Y660065D01*
X769545Y659600D01*
X771155D01*
G01X773373D02*
X773450Y660272D01*
X773565Y660840D01*
X773718Y661357D01*
X773910Y661925D01*
X774217Y662700D01*
X772683D01*
G01X776550Y659600D02*
Y662700D01*
X776090Y662080D01*
G01Y659600D02*
X777010D01*
G01X763383Y651300D02*
Y654400D01*
X764342D01*
X764648Y654245D01*
X764840Y654038D01*
X764917Y653625D01*
X764840Y653212D01*
X764610Y652953D01*
X764342Y652798D01*
X763383D01*
G01X764342D02*
X764917Y651300D01*
G01X767250D02*
Y654400D01*
X766790Y653780D01*
G01Y651300D02*
X767710D01*
G01X769507Y651920D02*
X769737Y651558D01*
X770043Y651352D01*
X770388Y651300D01*
X770695Y651352D01*
X771002Y651610D01*
X771193Y651920D01*
X771232Y652230D01*
X771155Y652592D01*
X770887Y652850D01*
X770618Y652953D01*
X770273D01*
G01X770618D02*
X770848Y653108D01*
X771040Y653367D01*
X771117Y653677D01*
X771040Y653987D01*
X770848Y654245D01*
X770503Y654400D01*
X770158Y654348D01*
X769813Y654142D01*
G01X773450Y651300D02*
Y654400D01*
X772990Y653780D01*
G01Y651300D02*
X773910D01*
G01X776473D02*
X776550Y651972D01*
X776665Y652540D01*
X776818Y653057D01*
X777010Y653625D01*
X777317Y654400D01*
X775783D01*
G01X763283Y655400D02*
Y658500D01*
X764242D01*
X764548Y658345D01*
X764740Y658138D01*
X764817Y657725D01*
X764740Y657312D01*
X764510Y657053D01*
X764242Y656898D01*
X763283D01*
G01X764242D02*
X764817Y655400D01*
G01X767150D02*
Y658500D01*
X766690Y657880D01*
G01Y655400D02*
X767610D01*
G01X769407Y656020D02*
X769637Y655658D01*
X769943Y655452D01*
X770288Y655400D01*
X770595Y655452D01*
X770902Y655710D01*
X771093Y656020D01*
X771132Y656330D01*
X771055Y656692D01*
X770787Y656950D01*
X770518Y657053D01*
X770173D01*
G01X770518D02*
X770748Y657208D01*
X770940Y657467D01*
X771017Y657777D01*
X770940Y658087D01*
X770748Y658345D01*
X770403Y658500D01*
X770058Y658448D01*
X769713Y658242D01*
G01X773350Y655400D02*
Y658500D01*
X772890Y657880D01*
G01Y655400D02*
X773810D01*
G01X775798Y655762D02*
X776067Y655503D01*
X776373Y655400D01*
X776680Y655503D01*
X776948Y655813D01*
X777140Y656278D01*
X777217Y656743D01*
Y657312D01*
X777140Y657777D01*
X776948Y658190D01*
X776718Y658397D01*
X776450Y658500D01*
X776143Y658397D01*
X775913Y658190D01*
X775760Y657880D01*
X775683Y657467D01*
X775760Y657105D01*
X775952Y656743D01*
X776182Y656537D01*
X776450Y656485D01*
X776757Y656588D01*
X776987Y656847D01*
X777217Y657312D01*
G01X779875Y139455D02*
Y199455D01*
G01Y218261D02*
Y278261D01*
G01X783840Y386060D02*
Y350690D01*
G01X781297Y438333D02*
Y443333D01*
X783703D01*
G01X782817Y440916D02*
X781297D01*
G01X785500Y437000D02*
Y445000D01*
X778500D01*
Y437000D01*
G01X782778Y510614D02*
X779678D01*
Y511573D01*
X779833Y511879D01*
X780040Y512071D01*
X780453Y512148D01*
X780866Y512071D01*
X781125Y511841D01*
X781280Y511573D01*
Y510614D01*
G01Y511573D02*
X782778Y512148D01*
G01Y514481D02*
X779678D01*
X780298Y514021D01*
G01X782778D02*
Y514941D01*
G01Y517581D02*
X779678D01*
X780298Y517121D01*
G01X782778D02*
Y518041D01*
G01X780195Y519953D02*
X779885Y520183D01*
X779730Y520451D01*
X779678Y520758D01*
X779781Y521141D01*
X780040Y521409D01*
X780350Y521486D01*
X780660Y521448D01*
X780918Y521294D01*
X781435Y520528D01*
X781796Y520183D01*
X782313Y519953D01*
X782778Y519876D01*
Y521486D01*
G01X779678Y523781D02*
X779781Y523474D01*
X780040Y523244D01*
X780350Y523091D01*
X780763Y522976D01*
X781228Y522938D01*
X781693Y522976D01*
X782106Y523091D01*
X782416Y523244D01*
X782675Y523474D01*
X782778Y523781D01*
X782675Y524088D01*
X782416Y524318D01*
X782106Y524471D01*
X781693Y524586D01*
X781228Y524624D01*
X780763Y524586D01*
X780350Y524471D01*
X780040Y524318D01*
X779781Y524088D01*
X779678Y523781D01*
G54D13*
G01X394900Y324860D02*
X396660D01*
G01X394900Y325020D02*
X396660D01*
G01X394900Y325180D02*
X396660D01*
G01X394900Y325340D02*
X396660D01*
G01X394900Y325500D02*
X396660D01*
G01X394900Y325660D02*
X396660D01*
G01X394900Y325820D02*
X396660D01*
G01X394900Y325980D02*
X396660D01*
G01X394900Y326140D02*
X396660D01*
G01X394900Y326300D02*
X396660D01*
G01X394900Y326460D02*
X396660D01*
G01X394900Y326620D02*
X396660D01*
G01X394900Y326780D02*
X396660D01*
G01X394900Y326940D02*
X396660D01*
G01X394900Y327100D02*
X396660D01*
G01X394900Y327260D02*
X396660D01*
G01X394900Y327420D02*
X396660D01*
G01X394900Y327580D02*
X396660D01*
G01X394900Y327740D02*
X396660D01*
G01X394900Y327900D02*
X396660D01*
G01X394900Y328060D02*
X396660D01*
G01X394900Y328220D02*
X396660D01*
G01X394900Y328380D02*
X396660D01*
G01X394900Y328540D02*
X396660D01*
G01X394900Y328700D02*
X396660D01*
G01X394900Y328860D02*
X396660D01*
G01X394900Y329020D02*
X396660D01*
G01X400020Y324860D02*
X401300D01*
G01X400020Y325020D02*
X401460D01*
G01X400020Y325180D02*
X401460D01*
G01X399860Y325340D02*
X401460D01*
G01X399860Y325500D02*
X401620D01*
G01X399700Y325660D02*
X401620D01*
G01X399700Y325820D02*
X401780D01*
G01X399540Y325980D02*
X401780D01*
G01X399540Y326140D02*
X401780D01*
G01X399540Y326300D02*
X401940D01*
G01X399380Y326460D02*
X401940D01*
G01X399380Y326620D02*
X402100D01*
G01X399220Y326780D02*
X402100D01*
G01X399220Y326940D02*
X402100D01*
G01X399220Y327100D02*
X402260D01*
G01X399060Y327260D02*
X400660D01*
G01X399060Y327420D02*
X400660D01*
G01X398900Y327580D02*
X400660D01*
G01X398900Y327740D02*
X400500D01*
G01X398900Y327900D02*
X400500D01*
G01X398740Y328060D02*
X400340D01*
G01X398740Y328220D02*
X400340D01*
G01X398580Y328380D02*
X400340D01*
G01X398580Y328540D02*
X400180D01*
G01X398580Y328700D02*
X400180D01*
G01X398420Y328860D02*
X400020D01*
G01X398420Y329020D02*
X400020D01*
G01X394900Y329180D02*
X396660D01*
G01X394900Y329340D02*
X396660D01*
G01X394900Y329500D02*
X396660D01*
G01X394900Y329660D02*
X396660D01*
G01X394900Y329820D02*
X396660D01*
G01X394900Y329980D02*
X396660D01*
G01X394900Y330140D02*
X396660D01*
G01X394900Y330300D02*
X396660D01*
G01X394900Y330460D02*
X396660D01*
G01X394900Y330620D02*
X396660D01*
G01X394900Y330780D02*
X396660D01*
G01X394900Y330940D02*
X396660D01*
G01X394900Y331100D02*
X396660D01*
G01X394900Y331260D02*
X396660D01*
G01X394900Y331420D02*
X396660D01*
G01X394900Y331580D02*
X396660D01*
G01X394900Y331740D02*
X396660D01*
G01X394900Y331900D02*
X396660D01*
G01X394900Y332060D02*
X396660D01*
G01X394900Y332220D02*
X396660D01*
G01X394900Y332380D02*
X396660D01*
G01X394900Y332540D02*
X396660D01*
G01X394900Y332700D02*
X396660D01*
G01X394900Y332860D02*
X396660D01*
G01X394900Y333020D02*
X396500D01*
G01X394900Y333180D02*
X396500D01*
G01X394900Y333340D02*
X396500D01*
G01X394900Y333500D02*
X398260D01*
G01X394900Y333660D02*
X398260D01*
G01X394900Y333820D02*
X398100D01*
G01X394900Y333980D02*
X398100D01*
G01X394900Y334140D02*
X397940D01*
G01X394900Y334300D02*
X397940D01*
G01X394900Y334460D02*
X397940D01*
G01X394900Y334620D02*
X397780D01*
G01X394900Y334780D02*
X397780D01*
G01X394900Y334940D02*
X397620D01*
G01X394900Y335100D02*
X397620D01*
G01X394900Y335260D02*
X397620D01*
G01X394900Y335420D02*
X397460D01*
G01X398260Y329180D02*
X400020D01*
G01X398260Y329340D02*
X399860D01*
G01X398260Y329500D02*
X399860D01*
G01X398100Y329660D02*
X399700D01*
G01X398100Y329820D02*
X399700D01*
G01X397940Y329980D02*
X399700D01*
G01X397940Y330140D02*
X399540D01*
G01X397940Y330300D02*
X399540D01*
G01X397780Y330460D02*
X399380D01*
G01X397780Y330620D02*
X399380D01*
G01X397620Y330780D02*
X399380D01*
G01X397620Y330940D02*
X399220D01*
G01X397460Y331100D02*
X399220D01*
G01X397460Y331260D02*
X399220D01*
G01X397460Y331420D02*
X399060D01*
G01X397300Y331580D02*
X399060D01*
G01X397300Y331740D02*
X398900D01*
G01X397140Y331900D02*
X398900D01*
G01X397140Y332060D02*
X398900D01*
G01X397140Y332220D02*
X398740D01*
G01X396980Y332380D02*
X398740D01*
G01X396980Y332540D02*
X398580D01*
G01X396820Y332700D02*
X398580D01*
G01X396820Y332860D02*
X398580D01*
G01X396820Y333020D02*
X398420D01*
G01X396660Y333180D02*
X398420D01*
G01X396660Y333340D02*
X398260D01*
G01X415380Y324700D02*
X417140D01*
G01X414900Y324860D02*
X417780D01*
G01X408980D02*
X410740D01*
G01X404820D02*
X406580D01*
G01X414420Y325020D02*
X418260D01*
G01X408980D02*
X410740D01*
G01X404820D02*
X406580D01*
G01X414260Y325180D02*
X418420D01*
G01X408980D02*
X410740D01*
G01X404820D02*
X406580D01*
G01X413940Y325340D02*
X418420D01*
G01X408980D02*
X410740D01*
G01X404820D02*
X406580D01*
G01X413780Y325500D02*
X418420D01*
G01X408980D02*
X410740D01*
G01X404820D02*
X406580D01*
G01X413620Y325660D02*
X418420D01*
G01X408980D02*
X410740D01*
G01X404820D02*
X406580D01*
G01X413460Y325820D02*
X418420D01*
G01X408980D02*
X410740D01*
G01X404820D02*
X406580D01*
G01X413300Y325980D02*
X418420D01*
G01X408980D02*
X410740D01*
G01X404820D02*
X406580D01*
G01X413140Y326140D02*
X416020D01*
G01X408980D02*
X410740D01*
G01X404820D02*
X406580D01*
G01X413140Y326300D02*
X415540D01*
G01X408980D02*
X410740D01*
G01X404820D02*
X406580D01*
G01X412980Y326460D02*
X415220D01*
G01X408980D02*
X410740D01*
G01X404820D02*
X406580D01*
G01X412820Y326620D02*
X415060D01*
G01X408980D02*
X410740D01*
G01X404820D02*
X406580D01*
G01X412820Y326780D02*
X414900D01*
G01X408980D02*
X410740D01*
G01X404820D02*
X406580D01*
G01X412820Y326940D02*
X414740D01*
G01X408980D02*
X410740D01*
G01X404820D02*
X406580D01*
G01X412660Y327100D02*
X414580D01*
G01X408980D02*
X410740D01*
G01X404820D02*
X406580D01*
G01X412660Y327260D02*
X414580D01*
G01X408980D02*
X410740D01*
G01X404820D02*
X406580D01*
G01X400820D02*
X402260D01*
G01X412660Y327420D02*
X414420D01*
G01X408980D02*
X410740D01*
G01X404820D02*
X406580D01*
G01X400820D02*
X402420D01*
G01X412660Y327580D02*
X414420D01*
G01X408980D02*
X410740D01*
G01X404820D02*
X406580D01*
G01X400980D02*
X402420D01*
G01X412500Y327740D02*
X414420D01*
G01X408980D02*
X410740D01*
G01X404820D02*
X406580D01*
G01X400980D02*
X402580D01*
G01X412500Y327900D02*
X414260D01*
G01X408980D02*
X410740D01*
G01X404820D02*
X406580D01*
G01X400980D02*
X402580D01*
G01X412500Y328060D02*
X414260D01*
G01X408980D02*
X410740D01*
G01X404820D02*
X406580D01*
G01X401140D02*
X402580D01*
G01X412500Y328220D02*
X414260D01*
G01X408980D02*
X410740D01*
G01X404820D02*
X406580D01*
G01X401140D02*
X402740D01*
G01X412500Y328380D02*
X414260D01*
G01X408980D02*
X410740D01*
G01X404820D02*
X406580D01*
G01X401300D02*
X402740D01*
G01X412500Y328540D02*
X414260D01*
G01X408980D02*
X410740D01*
G01X404820D02*
X406580D01*
G01X401300D02*
X402900D01*
G01X412500Y328700D02*
X414260D01*
G01X408980D02*
X410740D01*
G01X404820D02*
X406580D01*
G01X401300D02*
X402900D01*
G01X412500Y328860D02*
X414260D01*
G01X408980D02*
X410740D01*
G01X404820D02*
X406580D01*
G01X401460D02*
X402900D01*
G01X412500Y329020D02*
X414260D01*
G01X408980D02*
X410740D01*
G01X404820D02*
X406580D01*
G01X401460D02*
X403060D01*
G01X412500Y329180D02*
X414260D01*
G01X408980D02*
X410740D01*
G01X404820D02*
X406580D01*
G01X401620D02*
X403060D01*
G01X412500Y329340D02*
X414420D01*
G01X408980D02*
X410740D01*
G01X404820D02*
X406580D01*
G01X401620D02*
X403220D01*
G01X412660Y329500D02*
X414420D01*
G01X408980D02*
X410740D01*
G01X404820D02*
X406580D01*
G01X401620D02*
X403220D01*
G01X412660Y329660D02*
X414420D01*
G01X408980D02*
X410740D01*
G01X404820D02*
X406580D01*
G01X401780D02*
X403220D01*
G01X412660Y329820D02*
X414580D01*
G01X408980D02*
X410740D01*
G01X404820D02*
X406580D01*
G01X401780D02*
X403380D01*
G01X412660Y329980D02*
X414580D01*
G01X408980D02*
X410740D01*
G01X404820D02*
X406580D01*
G01X401940D02*
X403380D01*
G01X412820Y330140D02*
X414740D01*
G01X408980D02*
X410740D01*
G01X404820D02*
X406580D01*
G01X401940D02*
X403540D01*
G01X412820Y330300D02*
X414900D01*
G01X408980D02*
X410740D01*
G01X404820D02*
X406580D01*
G01X401940D02*
X403540D01*
G01X412980Y330460D02*
X415060D01*
G01X408980D02*
X410740D01*
G01X404820D02*
X406580D01*
G01X402100D02*
X403540D01*
G01X412980Y330620D02*
X415220D01*
G01X408980D02*
X410740D01*
G01X404820D02*
X406580D01*
G01X402100D02*
X403700D01*
G01X413140Y330780D02*
X415380D01*
G01X408980D02*
X410740D01*
G01X404820D02*
X406580D01*
G01X402260D02*
X403700D01*
G01X413140Y330940D02*
X415700D01*
G01X408980D02*
X410740D01*
G01X404820D02*
X406580D01*
G01X402260D02*
X403860D01*
G01X413300Y331100D02*
X416020D01*
G01X408980D02*
X410740D01*
G01X404820D02*
X406580D01*
G01X402260D02*
X403860D01*
G01X413460Y331260D02*
X418420D01*
G01X408980D02*
X410740D01*
G01X404820D02*
X406580D01*
G01X402420D02*
X403860D01*
G01X413620Y331420D02*
X418420D01*
G01X408980D02*
X410740D01*
G01X404820D02*
X406580D01*
G01X402420D02*
X404020D01*
G01X413780Y331580D02*
X418420D01*
G01X408980D02*
X410740D01*
G01X404820D02*
X406580D01*
G01X402580D02*
X404020D01*
G01X413940Y331740D02*
X418420D01*
G01X408980D02*
X410740D01*
G01X404820D02*
X406580D01*
G01X402580D02*
X404180D01*
G01X414100Y331900D02*
X418420D01*
G01X408980D02*
X410740D01*
G01X404820D02*
X406580D01*
G01X402740D02*
X404180D01*
G01X414420Y332060D02*
X418420D01*
G01X408980D02*
X410740D01*
G01X404820D02*
X406580D01*
G01X402740D02*
X404180D01*
G01X414740Y332220D02*
X418420D01*
G01X408980D02*
X410740D01*
G01X404820D02*
X406580D01*
G01X402740D02*
X404340D01*
G01X415060Y332380D02*
X418100D01*
G01X408980D02*
X410740D01*
G01X404820D02*
X406580D01*
G01X402900D02*
X404340D01*
G01X415700Y332540D02*
X417460D01*
G01X404820D02*
X406580D01*
G01X402900D02*
X404500D01*
G01X404820Y332700D02*
X406580D01*
G01X403060D02*
X404500D01*
G01X404820Y332860D02*
X406580D01*
G01X403060D02*
X404500D01*
G01X404820Y333020D02*
X406580D01*
G01X403060D02*
X404660D01*
G01X404820Y333180D02*
X406580D01*
G01X403220D02*
X404660D01*
G01X404820Y333340D02*
X406580D01*
G01X403220D02*
X404660D01*
G01X403380Y333500D02*
X406580D01*
G01X403380Y333660D02*
X406580D01*
G01X403380Y333820D02*
X406580D01*
G01X403540Y333980D02*
X406580D01*
G01X409460Y334140D02*
X410260D01*
G01X403540D02*
X406580D01*
G01X409140Y334300D02*
X410580D01*
G01X403700D02*
X406580D01*
G01X408980Y334460D02*
X410740D01*
G01X403700D02*
X406580D01*
G01X408980Y334620D02*
X410740D01*
G01X403700D02*
X406580D01*
G01X408820Y334780D02*
X410900D01*
G01X403860D02*
X406580D01*
G01X408820Y334940D02*
X410900D01*
G01X403860D02*
X406580D01*
G01X408820Y335100D02*
X410900D01*
G01X404020D02*
X406580D01*
G01X408820Y335260D02*
X410900D01*
G01X404020D02*
X406580D01*
G01X408980Y335420D02*
X410740D01*
G01X404020D02*
X406580D01*
G01X408980Y335580D02*
X410740D01*
G01X409140Y335740D02*
X410580D01*
G01X409460Y335900D02*
X410260D01*
G01X420180Y324860D02*
X421940D01*
G01X420180Y325020D02*
X421940D01*
G01X420180Y325180D02*
X421940D01*
G01X420180Y325340D02*
X421940D01*
G01X420180Y325500D02*
X421940D01*
G01X420180Y325660D02*
X421940D01*
G01X420180Y325820D02*
X421940D01*
G01X420180Y325980D02*
X421940D01*
G01X420180Y326140D02*
X421940D01*
G01X417460D02*
X418420D01*
G01X420180Y326300D02*
X421940D01*
G01X417780D02*
X418420D01*
G01X420180Y326460D02*
X421940D01*
G01X418100D02*
X418420D01*
G01X420180Y326620D02*
X421940D01*
G01X420180Y326780D02*
X421940D01*
G01X420180Y326940D02*
X421940D01*
G01X420180Y327100D02*
X421940D01*
G01X420180Y327260D02*
X421940D01*
G01X420180Y327420D02*
X421940D01*
G01X420180Y327580D02*
X421940D01*
G01X420180Y327740D02*
X421940D01*
G01X420180Y327900D02*
X421940D01*
G01X420180Y328060D02*
X421940D01*
G01X420180Y328220D02*
X421940D01*
G01X420180Y328380D02*
X421940D01*
G01X420180Y328540D02*
X421940D01*
G01X420180Y328700D02*
X421940D01*
G01X420180Y328860D02*
X421940D01*
G01X420180Y329020D02*
X421940D01*
G01X428500Y324700D02*
X430260D01*
G01X427860Y324860D02*
X430900D01*
G01X427380Y325020D02*
X431220D01*
G01X427220Y325180D02*
X431540D01*
G01X426900Y325340D02*
X431860D01*
G01X426740Y325500D02*
X432020D01*
G01X426580Y325660D02*
X432180D01*
G01X426420Y325820D02*
X432340D01*
G01X426260Y325980D02*
X432500D01*
G01X430100Y326140D02*
X432660D01*
G01X426100D02*
X428820D01*
G01X430420Y326300D02*
X432660D01*
G01X426100D02*
X428340D01*
G01X430740Y326460D02*
X432820D01*
G01X425940D02*
X428180D01*
G01X430900Y326620D02*
X432820D01*
G01X425940D02*
X427860D01*
G01X431060Y326780D02*
X432980D01*
G01X425780D02*
X427860D01*
G01X431220Y326940D02*
X432980D01*
G01X425780D02*
X427700D01*
G01X431220Y327100D02*
X433140D01*
G01X425620D02*
X427540D01*
G01X431380Y327260D02*
X433140D01*
G01X425620D02*
X427540D01*
G01X431380Y327420D02*
X433140D01*
G01X425620D02*
X427380D01*
G01X431380Y327580D02*
X433140D01*
G01X425620D02*
X427380D01*
G01X431540Y327740D02*
X433300D01*
G01X425460D02*
X427380D01*
G01X431540Y327900D02*
X433300D01*
G01X425460D02*
X427220D01*
G01X431540Y328060D02*
X433300D01*
G01X425460D02*
X427220D01*
G01X431540Y328220D02*
X433300D01*
G01X425460D02*
X427220D01*
G01X431540Y328380D02*
X433300D01*
G01X425460D02*
X427220D01*
G01X431540Y328540D02*
X433300D01*
G01X425460D02*
X427220D01*
G01X431540Y328700D02*
X433300D01*
G01X425460D02*
X427220D01*
G01X431540Y328860D02*
X433300D01*
G01X425460D02*
X427220D01*
G01X431540Y329020D02*
X433300D01*
G01X425460D02*
X427220D01*
G01X420180Y329180D02*
X421940D01*
G01X420180Y329340D02*
X422100D01*
G01X420180Y329500D02*
X422100D01*
G01X420180Y329660D02*
X422100D01*
G01X420180Y329820D02*
X422260D01*
G01X420180Y329980D02*
X422260D01*
G01X420180Y330140D02*
X422420D01*
G01X420180Y330300D02*
X422420D01*
G01X420180Y330460D02*
X422580D01*
G01X420180Y330620D02*
X422740D01*
G01X420180Y330780D02*
X422900D01*
G01X418100D02*
X418420D01*
G01X424340Y330940D02*
X424660D01*
G01X420180D02*
X423220D01*
G01X417940D02*
X418420D01*
G01X422100Y331100D02*
X424660D01*
G01X420180D02*
X421940D01*
G01X417460D02*
X418420D01*
G01X422100Y331260D02*
X424660D01*
G01X420180D02*
X421940D01*
G01X422260Y331420D02*
X424660D01*
G01X420180D02*
X421940D01*
G01X422260Y331580D02*
X424660D01*
G01X420180D02*
X421940D01*
G01X422420Y331740D02*
X424660D01*
G01X420180D02*
X421940D01*
G01X422580Y331900D02*
X424660D01*
G01X420180D02*
X421940D01*
G01X422740Y332060D02*
X424660D01*
G01X420180D02*
X421940D01*
G01X422900Y332220D02*
X424660D01*
G01X420180D02*
X421940D01*
G01X423060Y332380D02*
X424660D01*
G01X420180D02*
X421940D01*
G01X423540Y332540D02*
X424500D01*
G01X431540Y329180D02*
X433300D01*
G01X425460D02*
X427220D01*
G01X431540Y329340D02*
X433300D01*
G01X425460D02*
X427220D01*
G01X431380Y329500D02*
X433300D01*
G01X425620D02*
X427380D01*
G01X431380Y329660D02*
X433300D01*
G01X425620D02*
X427380D01*
G01X431380Y329820D02*
X433140D01*
G01X425620D02*
X427380D01*
G01X431380Y329980D02*
X433140D01*
G01X425620D02*
X427540D01*
G01X431220Y330140D02*
X433140D01*
G01X425780D02*
X427540D01*
G01X431220Y330300D02*
X433140D01*
G01X425780D02*
X427700D01*
G01X431060Y330460D02*
X432980D01*
G01X425780D02*
X427860D01*
G01X430900Y330620D02*
X432980D01*
G01X425940D02*
X427860D01*
G01X430740Y330780D02*
X432820D01*
G01X425940D02*
X428180D01*
G01X430420Y330940D02*
X432820D01*
G01X426100D02*
X428340D01*
G01X430100Y331100D02*
X432660D01*
G01X426260D02*
X428820D01*
G01X426260Y331260D02*
X432500D01*
G01X426420Y331420D02*
X432500D01*
G01X426580Y331580D02*
X432340D01*
G01X426740Y331740D02*
X432180D01*
G01X427060Y331900D02*
X431860D01*
G01X427220Y332060D02*
X431700D01*
G01X427540Y332220D02*
X431380D01*
G01X428020Y332380D02*
X431060D01*
G01X428660Y332540D02*
X430420D01*
G01X444180Y324700D02*
X445940D01*
G01X435860D02*
X437620D01*
G01X443540Y324860D02*
X446580D01*
G01X435220D02*
X438420D01*
G01X443060Y325020D02*
X446900D01*
G01X434740D02*
X438740D01*
G01X442900Y325180D02*
X447220D01*
G01X434580D02*
X439060D01*
G01X442580Y325340D02*
X447540D01*
G01X434580D02*
X439220D01*
G01X442420Y325500D02*
X447700D01*
G01X434580D02*
X439380D01*
G01X442260Y325660D02*
X447860D01*
G01X434580D02*
X439540D01*
G01X442100Y325820D02*
X448020D01*
G01X434580D02*
X439700D01*
G01X441940Y325980D02*
X448180D01*
G01X434580D02*
X439700D01*
G01X445780Y326140D02*
X448340D01*
G01X441780D02*
X444500D01*
G01X437620D02*
X439860D01*
G01X434580D02*
X436020D01*
G01X446100Y326300D02*
X448340D01*
G01X441780D02*
X444020D01*
G01X437940D02*
X439860D01*
G01X434580D02*
X435540D01*
G01X446420Y326460D02*
X448500D01*
G01X441620D02*
X443860D01*
G01X438100D02*
X440020D01*
G01X434580D02*
X435220D01*
G01X446580Y326620D02*
X448500D01*
G01X441620D02*
X443540D01*
G01X438260D02*
X440020D01*
G01X434580D02*
X434900D01*
G01X446740Y326780D02*
X448660D01*
G01X441460D02*
X443540D01*
G01X438260D02*
X440020D01*
G01X446900Y326940D02*
X448660D01*
G01X441460D02*
X443380D01*
G01X438260D02*
X440020D01*
G01X446900Y327100D02*
X448820D01*
G01X441300D02*
X443220D01*
G01X438260D02*
X440020D01*
G01X447060Y327260D02*
X448820D01*
G01X441300D02*
X443220D01*
G01X438100D02*
X440020D01*
G01X447060Y327420D02*
X448820D01*
G01X441300D02*
X443060D01*
G01X438100D02*
X440020D01*
G01X447060Y327580D02*
X448820D01*
G01X441300D02*
X443060D01*
G01X437780D02*
X439860D01*
G01X447220Y327740D02*
X448980D01*
G01X441140D02*
X443060D01*
G01X437620D02*
X439860D01*
G01X447220Y327900D02*
X448980D01*
G01X441140D02*
X442900D01*
G01X437140D02*
X439700D01*
G01X447220Y328060D02*
X448980D01*
G01X441140D02*
X442900D01*
G01X436660D02*
X439700D01*
G01X447220Y328220D02*
X448980D01*
G01X441140D02*
X442900D01*
G01X436340D02*
X439540D01*
G01X447220Y328380D02*
X448980D01*
G01X441140D02*
X442900D01*
G01X436020D02*
X439380D01*
G01X447220Y328540D02*
X448980D01*
G01X441140D02*
X442900D01*
G01X435700D02*
X439220D01*
G01X447220Y328700D02*
X448980D01*
G01X441140D02*
X442900D01*
G01X435380D02*
X438900D01*
G01X447220Y328860D02*
X448980D01*
G01X441140D02*
X442900D01*
G01X435220D02*
X438740D01*
G01X447220Y329020D02*
X448980D01*
G01X441140D02*
X442900D01*
G01X435060D02*
X438420D01*
G01X447220Y329180D02*
X448980D01*
G01X441140D02*
X442900D01*
G01X434900D02*
X437940D01*
G01X447220Y329340D02*
X448980D01*
G01X441140D02*
X442900D01*
G01X434900D02*
X437620D01*
G01X447060Y329500D02*
X448980D01*
G01X441300D02*
X443060D01*
G01X434740D02*
X437140D01*
G01X447060Y329660D02*
X448980D01*
G01X441300D02*
X443060D01*
G01X434740D02*
X436820D01*
G01X447060Y329820D02*
X448820D01*
G01X441300D02*
X443060D01*
G01X434740D02*
X436500D01*
G01X447060Y329980D02*
X448820D01*
G01X441300D02*
X443220D01*
G01X434580D02*
X436500D01*
G01X446900Y330140D02*
X448820D01*
G01X441460D02*
X443220D01*
G01X434580D02*
X436340D01*
G01X446900Y330300D02*
X448820D01*
G01X441460D02*
X443380D01*
G01X434580D02*
X436340D01*
G01X446740Y330460D02*
X448660D01*
G01X441460D02*
X443540D01*
G01X434580D02*
X436340D01*
G01X446580Y330620D02*
X448660D01*
G01X441620D02*
X443540D01*
G01X434580D02*
X436340D01*
G01X446420Y330780D02*
X448500D01*
G01X441620D02*
X443860D01*
G01X434580D02*
X436500D01*
G01X446100Y330940D02*
X448500D01*
G01X441780D02*
X444020D01*
G01X439060D02*
X439540D01*
G01X434740D02*
X436660D01*
G01X445780Y331100D02*
X448340D01*
G01X441940D02*
X444500D01*
G01X438580D02*
X439540D01*
G01X434740D02*
X436980D01*
G01X441940Y331260D02*
X448180D01*
G01X434900D02*
X439540D01*
G01X442100Y331420D02*
X448180D01*
G01X434900D02*
X439540D01*
G01X442260Y331580D02*
X448020D01*
G01X435060D02*
X439540D01*
G01X442420Y331740D02*
X447860D01*
G01X435220D02*
X439540D01*
G01X442740Y331900D02*
X447540D01*
G01X435380D02*
X439540D01*
G01X442900Y332060D02*
X447380D01*
G01X435540D02*
X439540D01*
G01X443220Y332220D02*
X447060D01*
G01X435860D02*
X439540D01*
G01X443700Y332380D02*
X446740D01*
G01X436340D02*
X439380D01*
G01X444340Y332540D02*
X446100D01*
G01X436820D02*
X438740D01*
G01X451380Y324860D02*
X452980D01*
G01X451380Y325020D02*
X452980D01*
G01X451380Y325180D02*
X452980D01*
G01X451380Y325340D02*
X452980D01*
G01X451380Y325500D02*
X452980D01*
G01X451380Y325660D02*
X452980D01*
G01X451380Y325820D02*
X452980D01*
G01X451380Y325980D02*
X452980D01*
G01X451380Y326140D02*
X452980D01*
G01X451380Y326300D02*
X452980D01*
G01X451380Y326460D02*
X452980D01*
G01X451380Y326620D02*
X452980D01*
G01X451380Y326780D02*
X452980D01*
G01X451380Y326940D02*
X452980D01*
G01X451380Y327100D02*
X452980D01*
G01X451380Y327260D02*
X452980D01*
G01X451380Y327420D02*
X452980D01*
G01X451380Y327580D02*
X452980D01*
G01X451380Y327740D02*
X452980D01*
G01X451380Y327900D02*
X452980D01*
G01X451380Y328060D02*
X452980D01*
G01X451380Y328220D02*
X452980D01*
G01X451380Y328380D02*
X452980D01*
G01X451380Y328540D02*
X452980D01*
G01X451380Y328700D02*
X452980D01*
G01X451380Y328860D02*
X452980D01*
G01X451380Y329020D02*
X452980D01*
G01X457940Y324700D02*
X459540D01*
G01X457460Y324860D02*
X460020D01*
G01X457300Y325020D02*
X460020D01*
G01X457140Y325180D02*
X460020D01*
G01X456980Y325340D02*
X460020D01*
G01X456820Y325500D02*
X460020D01*
G01X456820Y325660D02*
X460020D01*
G01X456660Y325820D02*
X460020D01*
G01X456660Y325980D02*
X460020D01*
G01X459700Y326140D02*
X460020D01*
G01X456660D02*
X458740D01*
G01X456500Y326300D02*
X458580D01*
G01X456500Y326460D02*
X458420D01*
G01X456500Y326620D02*
X458420D01*
G01X456500Y326780D02*
X458260D01*
G01X456500Y326940D02*
X458260D01*
G01X456500Y327100D02*
X458260D01*
G01X456500Y327260D02*
X458260D01*
G01X456500Y327420D02*
X458260D01*
G01X456500Y327580D02*
X458260D01*
G01X456500Y327740D02*
X458260D01*
G01X456500Y327900D02*
X458260D01*
G01X456500Y328060D02*
X458260D01*
G01X456500Y328220D02*
X458260D01*
G01X456500Y328380D02*
X458260D01*
G01X456500Y328540D02*
X458260D01*
G01X456500Y328700D02*
X458260D01*
G01X456500Y328860D02*
X458260D01*
G01X456500Y329020D02*
X458260D01*
G01X451380Y329180D02*
X452980D01*
G01X451380Y329340D02*
X452980D01*
G01X451380Y329500D02*
X452980D01*
G01X451380Y329660D02*
X452980D01*
G01X451380Y329820D02*
X452980D01*
G01X451380Y329980D02*
X452980D01*
G01X451380Y330140D02*
X452980D01*
G01X451380Y330300D02*
X452980D01*
G01X451380Y330460D02*
X452980D01*
G01X451380Y330620D02*
X452980D01*
G01X451380Y330780D02*
X452980D01*
G01X451380Y330940D02*
X452980D01*
G01X455220Y331100D02*
X460020D01*
G01X449940D02*
X455240D01*
G01X455220Y331260D02*
X460020D01*
G01X449940D02*
X455240D01*
G01X455220Y331420D02*
X460020D01*
G01X449940D02*
X455240D01*
G01X455220Y331580D02*
X460020D01*
G01X449940D02*
X455240D01*
G01X455220Y331740D02*
X460020D01*
G01X449940D02*
X454740D01*
G01X455220Y331900D02*
X460020D01*
G01X449940D02*
X455240D01*
G01X455220Y332060D02*
X460020D01*
G01X449940D02*
X454740D01*
G01X455220Y332220D02*
X460020D01*
G01X449940D02*
X455240D01*
G01X455220Y332380D02*
X460020D01*
G01X449940D02*
X455240D01*
G01X451380Y332540D02*
X452980D01*
G01X451380Y332700D02*
X452980D01*
G01X451380Y332860D02*
X452980D01*
G01X451380Y333020D02*
X452980D01*
G01X451380Y333180D02*
X452980D01*
G01X451380Y333340D02*
X452980D01*
G01X451380Y333500D02*
X452980D01*
G01X451380Y333660D02*
X452980D01*
G01X451380Y333820D02*
X452980D01*
G01X451380Y333980D02*
X453140D01*
G01X451380Y334140D02*
X453140D01*
G01X451380Y334300D02*
X453140D01*
G01X451380Y334460D02*
X453300D01*
G01X451380Y334620D02*
X453460D01*
G01X454900Y334780D02*
X455060D01*
G01X451540D02*
X453780D01*
G01X451540Y334940D02*
X455060D01*
G01X451700Y335100D02*
X455060D01*
G01X451860Y335260D02*
X455060D01*
G01X451860Y335420D02*
X455060D01*
G01X452020Y335580D02*
X455060D01*
G01X452340Y335740D02*
X455060D01*
G01X452500Y335900D02*
X455060D01*
G01X452820Y336060D02*
X455060D01*
G01X453300Y336220D02*
X454900D01*
G01X456500Y329180D02*
X458260D01*
G01X456500Y329340D02*
X458260D01*
G01X456500Y329500D02*
X458260D01*
G01X456500Y329660D02*
X458260D01*
G01X456500Y329820D02*
X458260D01*
G01X456500Y329980D02*
X458260D01*
G01X456500Y330140D02*
X458260D01*
G01X456500Y330300D02*
X458260D01*
G01X456500Y330460D02*
X458260D01*
G01X456500Y330620D02*
X458260D01*
G01X456500Y330780D02*
X458260D01*
G01X456500Y330940D02*
X458260D01*
G01X456500Y332540D02*
X458260D01*
G01X456500Y332700D02*
X458260D01*
G01X456500Y332860D02*
X458260D01*
G01X456500Y333020D02*
X458260D01*
G01X456500Y333180D02*
X458260D01*
G01X456500Y333340D02*
X458260D01*
G01X456500Y333500D02*
X458260D01*
G01X456500Y333660D02*
X458260D01*
G01X456500Y333820D02*
X458260D01*
G01X456500Y333980D02*
X458260D01*
G01X456500Y334140D02*
X458260D01*
G01X456820Y334300D02*
X458260D01*
G01X457460Y334460D02*
X458260D01*
G01X457940Y334620D02*
X458260D01*
G54D14*
G01X561673Y73769D02*
X540689D01*
G01X561673Y74261D02*
X540689D01*
G01X561673Y75245D02*
X540689D01*
G01X561673Y72785D02*
X540689D01*
G01X561673Y75737D02*
X540689D01*
G01X561673Y75983D02*
X540689D01*
G01X561673Y75491D02*
X540689D01*
G01X561673Y74999D02*
X540689D01*
G01X561673Y74507D02*
X540689D01*
G01Y72046D02*
X561673D01*
G01X540689Y73523D02*
X561673D01*
G01X540689Y72539D02*
X561673D01*
G01X540689D02*
X561673D01*
G01X540689Y73031D02*
X561673D01*
G01X540689D02*
X561673D01*
G01Y74015D02*
X540689D01*
G54D15*
G01X695254Y139740D02*
X695704Y140090D01*
G01X695254Y140440D02*
Y139740D01*
G01X695772Y140727D02*
Y139409D01*
G01X695704Y140090D02*
X695254Y140440D01*
G01X696512Y211545D02*
Y212863D01*
G01X696580Y212182D02*
X697030Y211832D01*
G01Y212532D02*
X696580Y212182D01*
G01X697030Y211832D02*
Y212532D01*
M02*
